G04 ================== begin FILE IDENTIFICATION RECORD ==================*
G04 Layout Name:  12004-1.brd*
G04 Film Name:    TSILK*
G04 File Format:  Gerber RS274X*
G04 File Origin:  Cadence Allegro 16.2-S033*
G04 Origin Date:  Tue Oct 16 14:35:54 2012*
G04 *
G04 Layer:  VIA CLASS/FILMMASKTOP*
G04 Layer:  REF DES/ASSEMBLY_TOP*
G04 Layer:  PACKAGE GEOMETRY/SILKSCREEN_TOP*
G04 Layer:  DRAWING FORMAT/LAYER_PCB_STORY*
G04 Layer:  DRAWING FORMAT/LAYER_SILK_T*
G04 Layer:  BOARD GEOMETRY/SILKSCREEN_TOP*
G04 *
G04 Offset:    (0.00 0.00)*
G04 Mirror:    No*
G04 Mode:      Positive*
G04 Rotation:  0*
G04 FullContactRelief:  No*
G04 UndefLineWidth:     6.00*
G04 ================== end FILE IDENTIFICATION RECORD ====================*
%FSLAX35Y35*MOIN*%
%IR0*IPPOS*OFA0.00000B0.00000*MIA0B0*SFA1.00000B1.00000*%
%ADD10C,.032*%
%ADD11C,.02*%
%ADD12C,.012*%
%ADD13C,.013*%
%ADD14C,.015*%
%ADD15C,.016*%
%ADD16C,.019*%
%ADD17C,.0005*%
%ADD18C,.002*%
%ADD19C,.005*%
%ADD20C,.006*%
%ADD21C,.008*%
G75*
%LPD*%
G75*
G36*
G01X68700Y164000D02*
X72700D01*
X70700Y162000D01*
X68700Y164000D01*
G37*
G36*
G01X59464Y504259D02*
Y500259D01*
X55464D01*
X59464Y504259D01*
G37*
G36*
G01X98895Y118251D02*
X81395D01*
Y130151D01*
X98895D01*
Y118251D01*
G37*
G36*
G01X121810Y206349D02*
Y202349D01*
X123810Y204349D01*
X121810Y206349D01*
G37*
G36*
G01X89934Y616172D02*
X92434Y613672D01*
Y618672D01*
X89934Y616172D01*
G37*
G36*
G01Y734282D02*
X92434Y731782D01*
Y736782D01*
X89934Y734282D01*
G37*
G36*
G01X212240Y95933D02*
Y91883D01*
X216290Y95933D01*
X212240D01*
G37*
G36*
G01X178249Y147197D02*
Y152197D01*
X173249Y147197D01*
X178249D01*
G37*
G36*
G01X219859Y200850D02*
Y192850D01*
X228959D01*
Y200850D01*
X219859D01*
G37*
G36*
G01X229122Y399936D02*
X227722Y401336D01*
Y398536D01*
X229122Y399936D01*
G37*
G36*
G01X238400Y432100D02*
X219900D01*
Y444500D01*
X238400D01*
Y432100D01*
G37*
G36*
G01X223206Y470818D02*
Y474818D01*
X221206Y472818D01*
X223206Y470818D01*
G37*
G36*
G01X219859Y767780D02*
Y759780D01*
X228959D01*
Y767780D01*
X219859D01*
G37*
G36*
G01X515034Y402225D02*
X526234D01*
Y419625D01*
X515034D01*
Y402225D01*
G37*
G36*
G01X678349Y320974D02*
Y315974D01*
X698349D01*
Y320974D01*
X678349D01*
G37*
G36*
G01X658407Y509919D02*
X663407D01*
X658407Y514919D01*
Y509919D01*
G37*
G36*
G01X699512Y826169D02*
Y854769D01*
X711912D01*
Y826169D01*
X699512D01*
G37*
G36*
G01X700198Y768266D02*
Y796866D01*
X712598D01*
Y768266D01*
X700198D01*
G37*
G36*
G01X456515Y105733D02*
Y142133D01*
X693715D01*
Y105733D01*
X456515D01*
G37*
G54D10*
X414894Y453432D03*
X419296Y449111D03*
X423572Y453454D03*
X419092Y457572D03*
X419225Y453324D03*
X694995Y453626D03*
X694923Y461253D03*
X694851Y469456D03*
X694907Y476993D03*
G54D20*
G01X-755164Y-252763D02*
Y-235263D01*
G01X-746868D02*
X-755164Y-246055D01*
G01X-745558Y-252763D02*
X-751453Y-241097D01*
G01X-737883Y-252763D02*
Y-235263D01*
X-727839Y-252763D01*
Y-235263D01*
G01X-715361Y-252763D02*
X-717108Y-252471D01*
X-718636Y-251305D01*
X-719946Y-249555D01*
X-720820Y-247513D01*
X-721256Y-245180D01*
Y-242846D01*
X-720820Y-240513D01*
X-719946Y-238471D01*
X-718636Y-236722D01*
X-717108Y-235555D01*
X-715361Y-235263D01*
X-713615Y-235555D01*
X-712086Y-236722D01*
X-710776Y-238471D01*
X-709902Y-240513D01*
X-709466Y-242846D01*
Y-245180D01*
X-709902Y-247513D01*
X-710776Y-249555D01*
X-712086Y-251305D01*
X-713615Y-252471D01*
X-715361Y-252763D01*
G01X-702446D02*
X-693276Y-235263D01*
G01X-702446D02*
X-693276Y-252763D01*
G01X-658494D02*
X-667228D01*
Y-235263D01*
X-658494D01*
G01X-661988Y-243721D02*
X-667228D01*
G01X-649946Y-252763D02*
X-640776Y-235263D01*
G01X-649946D02*
X-640776Y-252763D01*
G01X-632228D02*
Y-235263D01*
X-626988D01*
X-625241Y-236138D01*
X-623931Y-238180D01*
X-623494Y-240513D01*
X-623931Y-242846D01*
X-625023Y-244596D01*
X-626988Y-245472D01*
X-632228D01*
G01X-615820Y-252763D02*
X-610361Y-235263D01*
X-604902Y-252763D01*
G01X-606868Y-246638D02*
X-613855D01*
G01X-597883Y-252763D02*
Y-235263D01*
X-587839Y-252763D01*
Y-235263D01*
G01X-580164Y-252763D02*
Y-235263D01*
X-575798D01*
X-574051Y-236138D01*
X-572741Y-237305D01*
X-571649Y-239054D01*
X-570776Y-241097D01*
X-570558Y-244013D01*
X-570776Y-246930D01*
X-571649Y-248972D01*
X-572741Y-250722D01*
X-574051Y-251888D01*
X-575798Y-252763D01*
X-580164D01*
G01X-553494D02*
X-562228D01*
Y-235263D01*
X-553494D01*
G01X-556988Y-243721D02*
X-562228D01*
G01X-544728Y-252763D02*
Y-235263D01*
X-539269D01*
X-537523Y-236138D01*
X-536431Y-237305D01*
X-535994Y-239638D01*
X-536431Y-241972D01*
X-537741Y-243430D01*
X-539269Y-244305D01*
X-544728D01*
G01X-539269D02*
X-535994Y-252763D01*
G01X-503615Y-243430D02*
X-502741Y-242555D01*
X-502086Y-241097D01*
X-501649Y-239054D01*
X-502086Y-237305D01*
X-502959Y-236138D01*
X-504488Y-235263D01*
X-510383D01*
Y-252763D01*
X-503178D01*
X-501649Y-251597D01*
X-500776Y-249846D01*
X-500339Y-247805D01*
X-500776Y-245763D01*
X-502086Y-244013D01*
X-503615Y-243430D01*
X-510383D01*
G01X-487861Y-252763D02*
X-489608Y-252471D01*
X-491136Y-251305D01*
X-492446Y-249555D01*
X-493320Y-247513D01*
X-493756Y-245180D01*
Y-242846D01*
X-493320Y-240513D01*
X-492446Y-238471D01*
X-491136Y-236722D01*
X-489608Y-235555D01*
X-487861Y-235263D01*
X-486115Y-235555D01*
X-484586Y-236722D01*
X-483276Y-238471D01*
X-482402Y-240513D01*
X-481966Y-242846D01*
Y-245180D01*
X-482402Y-247513D01*
X-483276Y-249555D01*
X-484586Y-251305D01*
X-486115Y-252471D01*
X-487861Y-252763D01*
G01X-475820D02*
X-470361Y-235263D01*
X-464902Y-252763D01*
G01X-466868Y-246638D02*
X-473855D01*
G01X-457228Y-252763D02*
Y-235263D01*
X-451769D01*
X-450023Y-236138D01*
X-448931Y-237305D01*
X-448494Y-239638D01*
X-448931Y-241972D01*
X-450241Y-243430D01*
X-451769Y-244305D01*
X-457228D01*
G01X-451769D02*
X-448494Y-252763D01*
G01X-440164D02*
Y-235263D01*
X-435798D01*
X-434051Y-236138D01*
X-432741Y-237305D01*
X-431649Y-239054D01*
X-430776Y-241097D01*
X-430558Y-244013D01*
X-430776Y-246930D01*
X-431649Y-248972D01*
X-432741Y-250722D01*
X-434051Y-251888D01*
X-435798Y-252763D01*
X-440164D01*
G01X-633538Y-207763D02*
Y-190263D01*
X-627861Y-204846D01*
X-622184Y-190263D01*
Y-207763D01*
G01X-610361D02*
X-611671Y-207471D01*
X-612981Y-206305D01*
X-613855Y-204263D01*
X-614291Y-201930D01*
X-613855Y-199596D01*
X-612981Y-197555D01*
X-611671Y-196388D01*
X-610361Y-196097D01*
X-609051Y-196388D01*
X-607741Y-197555D01*
X-606868Y-199596D01*
X-606649Y-201930D01*
X-606868Y-204263D01*
X-607741Y-206305D01*
X-609051Y-207471D01*
X-610361Y-207763D01*
G01X-588931Y-190263D02*
Y-207763D01*
G01Y-205139D02*
X-589804Y-206597D01*
X-591115Y-207471D01*
X-592643Y-207763D01*
X-594389Y-207180D01*
X-595699Y-205722D01*
X-596573Y-203972D01*
X-596791Y-201930D01*
X-596573Y-199888D01*
X-595699Y-198138D01*
X-594389Y-196680D01*
X-592643Y-196097D01*
X-591115Y-196388D01*
X-590023Y-196972D01*
X-588931Y-198138D01*
G01X-578636Y-199888D02*
X-571649D01*
X-572304Y-197846D01*
X-573396Y-196680D01*
X-574924Y-196097D01*
X-576453Y-196388D01*
X-577763Y-197263D01*
X-578636Y-199305D01*
X-579073Y-201055D01*
Y-202805D01*
X-578636Y-204555D01*
X-577544Y-206305D01*
X-576234Y-207471D01*
X-574706Y-207763D01*
X-573178Y-207180D01*
X-571649Y-205430D01*
G01X-557861Y-207763D02*
Y-190263D01*
G01X-380161Y-252763D02*
Y-235263D01*
X-382781Y-238763D01*
G01Y-252763D02*
X-377541D01*
G01X-366809Y-238180D02*
X-365499Y-236430D01*
X-363971Y-235555D01*
X-362224Y-235263D01*
X-360041Y-235846D01*
X-358513Y-237305D01*
X-358076Y-239054D01*
X-358294Y-240805D01*
X-359168Y-242263D01*
X-363534Y-245180D01*
X-365499Y-247221D01*
X-366809Y-250139D01*
X-367246Y-252763D01*
X-358076D01*
G01X-345161Y-235263D02*
X-346908Y-235846D01*
X-348218Y-237305D01*
X-349091Y-239054D01*
X-349746Y-241388D01*
X-349964Y-244013D01*
X-349746Y-246638D01*
X-349091Y-248972D01*
X-348218Y-250722D01*
X-346908Y-252180D01*
X-345161Y-252763D01*
X-343415Y-252180D01*
X-342104Y-250722D01*
X-341231Y-248972D01*
X-340576Y-246638D01*
X-340358Y-244013D01*
X-340576Y-241388D01*
X-341231Y-239054D01*
X-342104Y-237305D01*
X-343415Y-235846D01*
X-345161Y-235263D01*
G01X-327661D02*
X-329408Y-235846D01*
X-330718Y-237305D01*
X-331591Y-239054D01*
X-332246Y-241388D01*
X-332464Y-244013D01*
X-332246Y-246638D01*
X-331591Y-248972D01*
X-330718Y-250722D01*
X-329408Y-252180D01*
X-327661Y-252763D01*
X-325915Y-252180D01*
X-324604Y-250722D01*
X-323731Y-248972D01*
X-323076Y-246638D01*
X-322858Y-244013D01*
X-323076Y-241388D01*
X-323731Y-239054D01*
X-324604Y-237305D01*
X-325915Y-235846D01*
X-327661Y-235263D01*
G01X-307541Y-252763D02*
Y-235263D01*
X-315620Y-247805D01*
X-304702D01*
G01X-393278Y-207763D02*
Y-190263D01*
X-388038D01*
X-386291Y-191138D01*
X-384981Y-193180D01*
X-384544Y-195513D01*
X-384981Y-197846D01*
X-386073Y-199596D01*
X-388038Y-200472D01*
X-393278D01*
G01X-366608Y-191722D02*
X-367918Y-190846D01*
X-369446Y-190263D01*
X-371193D01*
X-373158Y-191138D01*
X-374686Y-192596D01*
X-375778Y-194347D01*
X-376651Y-197263D01*
X-376870Y-199888D01*
X-376433Y-202513D01*
X-375778Y-204263D01*
X-374468Y-206013D01*
X-372939Y-207180D01*
X-371411Y-207763D01*
X-369883D01*
X-368354Y-207180D01*
X-367044Y-206305D01*
X-365952Y-205139D01*
G01X-352165Y-198430D02*
X-351291Y-197555D01*
X-350636Y-196097D01*
X-350199Y-194054D01*
X-350636Y-192305D01*
X-351509Y-191138D01*
X-353038Y-190263D01*
X-358933D01*
Y-207763D01*
X-351728D01*
X-350199Y-206597D01*
X-349326Y-204846D01*
X-348889Y-202805D01*
X-349326Y-200763D01*
X-350636Y-199013D01*
X-352165Y-198430D01*
X-358933D01*
G01X-342961Y-213596D02*
X-329861D01*
G01X-323933Y-207763D02*
Y-190263D01*
X-313889Y-207763D01*
Y-190263D01*
G01X-301411Y-207763D02*
X-303158Y-207471D01*
X-304686Y-206305D01*
X-305996Y-204555D01*
X-306870Y-202513D01*
X-307306Y-200180D01*
Y-197846D01*
X-306870Y-195513D01*
X-305996Y-193471D01*
X-304686Y-191722D01*
X-303158Y-190555D01*
X-301411Y-190263D01*
X-299665Y-190555D01*
X-298136Y-191722D01*
X-296826Y-193471D01*
X-295952Y-195513D01*
X-295516Y-197846D01*
Y-200180D01*
X-295952Y-202513D01*
X-296826Y-204555D01*
X-298136Y-206305D01*
X-299665Y-207471D01*
X-301411Y-207763D01*
G01X-218861Y-252763D02*
Y-235263D01*
X-221481Y-238763D01*
G01Y-252763D02*
X-216241D01*
G01X-250570Y-190263D02*
X-245111Y-207763D01*
X-239652Y-190263D01*
G01X-223244Y-207763D02*
X-231978D01*
Y-190263D01*
X-223244D01*
G01X-226738Y-198721D02*
X-231978D01*
G01X-214478Y-207763D02*
Y-190263D01*
X-209019D01*
X-207273Y-191138D01*
X-206181Y-192305D01*
X-205744Y-194638D01*
X-206181Y-196972D01*
X-207491Y-198430D01*
X-209019Y-199305D01*
X-214478D01*
G01X-209019D02*
X-205744Y-207763D01*
G01X-192611Y-208346D02*
X-193048Y-208055D01*
Y-207471D01*
X-192611Y-207180D01*
X-192174Y-207471D01*
Y-208055D01*
X-192611Y-208346D01*
G01X-112661Y-235263D02*
Y-252763D01*
G01X-117683Y-235263D02*
X-107639D01*
G01X-99746Y-250430D02*
X-97999Y-251888D01*
X-96034Y-252763D01*
X-94288D01*
X-92541Y-251888D01*
X-91231Y-250430D01*
X-90576Y-248388D01*
X-91013Y-246347D01*
X-92104Y-244596D01*
X-94069Y-243430D01*
X-96689Y-242846D01*
X-98218Y-241680D01*
X-98873Y-239638D01*
X-98436Y-237596D01*
X-97344Y-236138D01*
X-95816Y-235263D01*
X-94288D01*
X-92759Y-235846D01*
X-91449Y-237305D01*
G01X-80281Y-235263D02*
X-75041D01*
G01X-77661D02*
Y-252763D01*
G01X-80281D02*
X-75041D01*
G01X-64528Y-235263D02*
Y-252763D01*
X-55794D01*
G01X-47464D02*
Y-235263D01*
G01X-39168D02*
X-47464Y-246055D01*
G01X-37858Y-252763D02*
X-43753Y-241097D01*
G01X-125778Y-190263D02*
Y-207763D01*
X-117044D01*
G01X-99981D02*
Y-196097D01*
G01Y-198138D02*
X-100854Y-196972D01*
X-102165Y-196388D01*
X-103693Y-196097D01*
X-105221Y-196680D01*
X-106531Y-197846D01*
X-107405Y-199596D01*
X-107841Y-201930D01*
X-107405Y-204263D01*
X-106531Y-206013D01*
X-105221Y-207180D01*
X-103693Y-207763D01*
X-102165Y-207471D01*
X-100854Y-206597D01*
X-99981Y-205430D01*
G01X-90996Y-213013D02*
X-89686Y-213596D01*
X-87939Y-213013D01*
X-86848Y-211847D01*
X-85974Y-210388D01*
X-84665Y-205722D01*
X-81826Y-196097D01*
G01X-88813D02*
X-84665Y-205722D01*
G01X-72186Y-199888D02*
X-65199D01*
X-65854Y-197846D01*
X-66946Y-196680D01*
X-68474Y-196097D01*
X-70003Y-196388D01*
X-71313Y-197263D01*
X-72186Y-199305D01*
X-72623Y-201055D01*
Y-202805D01*
X-72186Y-204555D01*
X-71094Y-206305D01*
X-69784Y-207471D01*
X-68256Y-207763D01*
X-66728Y-207180D01*
X-65199Y-205430D01*
G01X-54468Y-207763D02*
Y-196097D01*
G01Y-198430D02*
X-53376Y-197263D01*
X-52284Y-196388D01*
X-50756Y-196097D01*
X-49665Y-196388D01*
X-48354Y-197263D01*
G01X-37186Y-205722D02*
X-36094Y-206888D01*
X-34566Y-207763D01*
X-33256D01*
X-31946Y-207180D01*
X-31073Y-206305D01*
X-30636Y-205139D01*
X-30854Y-203388D01*
X-31728Y-202513D01*
X-35658Y-200763D01*
X-36531Y-198721D01*
X-36094Y-197263D01*
X-35221Y-196388D01*
X-33911Y-196097D01*
X-32601Y-196388D01*
X-31291Y-197263D01*
G01X51772Y-235263D02*
Y-252763D01*
X60506D01*
G01X68836Y-235263D02*
Y-247805D01*
X69709Y-250430D01*
X71456Y-252180D01*
X73639Y-252763D01*
X75822Y-252180D01*
X77569Y-250430D01*
X78442Y-247805D01*
Y-235263D01*
G01X95942Y-236722D02*
X94632Y-235846D01*
X93104Y-235263D01*
X91357D01*
X89392Y-236138D01*
X87864Y-237596D01*
X86772Y-239347D01*
X85899Y-242263D01*
X85680Y-244888D01*
X86117Y-247513D01*
X86772Y-249263D01*
X88082Y-251013D01*
X89611Y-252180D01*
X91139Y-252763D01*
X92667D01*
X94196Y-252180D01*
X95506Y-251305D01*
X96598Y-250139D01*
G01X103836Y-252763D02*
Y-235263D01*
G01X112132D02*
X103836Y-246055D01*
G01X113442Y-252763D02*
X107547Y-241097D01*
G01X126139Y-252763D02*
Y-244888D01*
X121772Y-235263D01*
G01X130506D02*
X126139Y-244888D01*
G01X25086Y-207763D02*
Y-190263D01*
X29452D01*
X31199Y-191138D01*
X32509Y-192305D01*
X33601Y-194054D01*
X34474Y-196097D01*
X34692Y-199013D01*
X34474Y-201930D01*
X33601Y-203972D01*
X32509Y-205722D01*
X31199Y-206888D01*
X29452Y-207763D01*
X25086D01*
G01X44114Y-199888D02*
X51101D01*
X50446Y-197846D01*
X49354Y-196680D01*
X47826Y-196097D01*
X46297Y-196388D01*
X44987Y-197263D01*
X44114Y-199305D01*
X43677Y-201055D01*
Y-202805D01*
X44114Y-204555D01*
X45206Y-206305D01*
X46516Y-207471D01*
X48044Y-207763D01*
X49572Y-207180D01*
X51101Y-205430D01*
G01X61614Y-205722D02*
X62706Y-206888D01*
X64234Y-207763D01*
X65544D01*
X66854Y-207180D01*
X67727Y-206305D01*
X68164Y-205139D01*
X67946Y-203388D01*
X67072Y-202513D01*
X63142Y-200763D01*
X62269Y-198721D01*
X62706Y-197263D01*
X63579Y-196388D01*
X64889Y-196097D01*
X66199Y-196388D01*
X67509Y-197263D01*
G01X82389Y-196097D02*
Y-207763D01*
G01Y-191430D02*
X81952Y-191138D01*
Y-190555D01*
X82389Y-190263D01*
X82826Y-190555D01*
Y-191138D01*
X82389Y-191430D01*
G01X96832Y-212138D02*
X98361Y-213305D01*
X100107Y-213596D01*
X101635Y-213305D01*
X102946Y-211847D01*
X103819Y-209805D01*
Y-196097D01*
G01Y-198430D02*
X102946Y-197263D01*
X101635Y-196388D01*
X100107Y-196097D01*
X98361Y-196680D01*
X97269Y-197846D01*
X96395Y-199888D01*
X95959Y-201930D01*
X96177Y-203680D01*
X97051Y-205722D01*
X98361Y-207180D01*
X100107Y-207763D01*
X101417Y-207471D01*
X102946Y-206305D01*
X103819Y-205139D01*
G01X113677Y-207763D02*
Y-196097D01*
G01Y-199013D02*
X114551Y-197555D01*
X115861Y-196388D01*
X117607Y-196097D01*
X119135Y-196388D01*
X120446Y-197555D01*
X121101Y-199596D01*
Y-207763D01*
G01X131614Y-199888D02*
X138601D01*
X137946Y-197846D01*
X136854Y-196680D01*
X135326Y-196097D01*
X133797Y-196388D01*
X132487Y-197263D01*
X131614Y-199305D01*
X131177Y-201055D01*
Y-202805D01*
X131614Y-204555D01*
X132706Y-206305D01*
X134016Y-207471D01*
X135544Y-207763D01*
X137072Y-207180D01*
X138601Y-205430D01*
G01X149332Y-207763D02*
Y-196097D01*
G01Y-198430D02*
X150424Y-197263D01*
X151516Y-196388D01*
X153044Y-196097D01*
X154135Y-196388D01*
X155446Y-197263D01*
G01X196089Y-252763D02*
Y-235263D01*
X193469Y-238763D01*
G01Y-252763D02*
X198709D01*
G01X213589Y-235263D02*
X211842Y-235846D01*
X210532Y-237305D01*
X209659Y-239054D01*
X209004Y-241388D01*
X208786Y-244013D01*
X209004Y-246638D01*
X209659Y-248972D01*
X210532Y-250722D01*
X211842Y-252180D01*
X213589Y-252763D01*
X215335Y-252180D01*
X216646Y-250722D01*
X217519Y-248972D01*
X218174Y-246638D01*
X218392Y-244013D01*
X218174Y-241388D01*
X217519Y-239054D01*
X216646Y-237305D01*
X215335Y-235846D01*
X213589Y-235263D01*
G01X227159Y-253346D02*
X235019Y-235263D01*
G01X248589Y-252763D02*
Y-235263D01*
X245969Y-238763D01*
G01Y-252763D02*
X251209D01*
G01X261941Y-245472D02*
X263469Y-243430D01*
X264779Y-242263D01*
X266526Y-241680D01*
X268054Y-242263D01*
X269146Y-243430D01*
X270019Y-245180D01*
X270237Y-247221D01*
X270019Y-248972D01*
X269146Y-250722D01*
X267835Y-252180D01*
X266307Y-252763D01*
X264561Y-252180D01*
X263032Y-250430D01*
X262159Y-247805D01*
X261941Y-244888D01*
X262377Y-241097D01*
X263032Y-239054D01*
X264124Y-237013D01*
X265652Y-235555D01*
X267181Y-235263D01*
X268709Y-235846D01*
X269801Y-237305D01*
G01X279659Y-253346D02*
X287519Y-235263D01*
G01X296941Y-238180D02*
X298251Y-236430D01*
X299779Y-235555D01*
X301526Y-235263D01*
X303709Y-235846D01*
X305237Y-237305D01*
X305674Y-239054D01*
X305456Y-240805D01*
X304582Y-242263D01*
X300216Y-245180D01*
X298251Y-247221D01*
X296941Y-250139D01*
X296504Y-252763D01*
X305674D01*
G01X318589Y-235263D02*
X316842Y-235846D01*
X315532Y-237305D01*
X314659Y-239054D01*
X314004Y-241388D01*
X313786Y-244013D01*
X314004Y-246638D01*
X314659Y-248972D01*
X315532Y-250722D01*
X316842Y-252180D01*
X318589Y-252763D01*
X320335Y-252180D01*
X321646Y-250722D01*
X322519Y-248972D01*
X323174Y-246638D01*
X323392Y-244013D01*
X323174Y-241388D01*
X322519Y-239054D01*
X321646Y-237305D01*
X320335Y-235846D01*
X318589Y-235263D01*
G01X336089Y-252763D02*
Y-235263D01*
X333469Y-238763D01*
G01Y-252763D02*
X338709D01*
G01X349441Y-238180D02*
X350751Y-236430D01*
X352279Y-235555D01*
X354026Y-235263D01*
X356209Y-235846D01*
X357737Y-237305D01*
X358174Y-239054D01*
X357956Y-240805D01*
X357082Y-242263D01*
X352716Y-245180D01*
X350751Y-247221D01*
X349441Y-250139D01*
X349004Y-252763D01*
X358174D01*
G01X243786Y-207763D02*
Y-190263D01*
X248152D01*
X249899Y-191138D01*
X251209Y-192305D01*
X252301Y-194054D01*
X253174Y-196097D01*
X253392Y-199013D01*
X253174Y-201930D01*
X252301Y-203972D01*
X251209Y-205722D01*
X249899Y-206888D01*
X248152Y-207763D01*
X243786D01*
G01X270019D02*
Y-196097D01*
G01Y-198138D02*
X269146Y-196972D01*
X267835Y-196388D01*
X266307Y-196097D01*
X264779Y-196680D01*
X263469Y-197846D01*
X262595Y-199596D01*
X262159Y-201930D01*
X262595Y-204263D01*
X263469Y-206013D01*
X264779Y-207180D01*
X266307Y-207763D01*
X267835Y-207471D01*
X269146Y-206597D01*
X270019Y-205430D01*
G01X283589Y-190263D02*
Y-207763D01*
G01X280532Y-196097D02*
X286646D01*
G01X297814Y-199888D02*
X304801D01*
X304146Y-197846D01*
X303054Y-196680D01*
X301526Y-196097D01*
X299997Y-196388D01*
X298687Y-197263D01*
X297814Y-199305D01*
X297377Y-201055D01*
Y-202805D01*
X297814Y-204555D01*
X298906Y-206305D01*
X300216Y-207471D01*
X301744Y-207763D01*
X303272Y-207180D01*
X304801Y-205430D01*
G01X17Y115877D02*
X-2983D01*
Y49477D01*
X17D01*
G01X34317Y55577D02*
Y109777D01*
X18017D01*
Y115877D01*
X17D01*
Y49477D01*
X18017D01*
Y55577D01*
X34317D01*
G01X142Y152569D02*
X14942D01*
Y159869D01*
X44642D01*
Y131469D01*
X14942D01*
Y138769D01*
X142D01*
Y152569D01*
G01X5800Y446700D02*
Y448700D01*
G01Y447700D02*
X10800D01*
G01Y446700D02*
Y448700D01*
G01Y451383D02*
X5800D01*
X10800Y455217D01*
X5800D01*
G01Y458900D02*
X10800D01*
G01X5800Y456983D02*
Y460817D01*
G01X8133Y465167D02*
X7883Y465500D01*
X7467Y465750D01*
X6883Y465917D01*
X6383Y465750D01*
X6050Y465417D01*
X5800Y464833D01*
Y462583D01*
X10800D01*
Y465333D01*
X10467Y465917D01*
X9967Y466250D01*
X9383Y466417D01*
X8800Y466250D01*
X8300Y465750D01*
X8133Y465167D01*
Y462583D01*
G01X10133Y473950D02*
X10550Y474617D01*
X10800Y475367D01*
Y476033D01*
X10550Y476700D01*
X10133Y477200D01*
X9550Y477450D01*
X8967Y477283D01*
X8467Y476867D01*
X8133Y476117D01*
X7967Y475117D01*
X7633Y474533D01*
X7050Y474283D01*
X6467Y474450D01*
X6050Y474867D01*
X5800Y475450D01*
Y476033D01*
X5967Y476617D01*
X6383Y477117D01*
G01X10800Y479217D02*
X5800Y481300D01*
X10800Y483383D01*
G01X9050Y482633D02*
Y479967D01*
G01X10133Y485150D02*
X10550Y485817D01*
X10800Y486567D01*
Y487233D01*
X10550Y487900D01*
X10133Y488400D01*
X9550Y488650D01*
X8967Y488483D01*
X8467Y488067D01*
X8133Y487317D01*
X7967Y486317D01*
X7633Y485733D01*
X7050Y485483D01*
X6467Y485650D01*
X6050Y486067D01*
X5800Y486650D01*
Y487233D01*
X5967Y487817D01*
X6383Y488317D01*
G01X5800Y496433D02*
X10800D01*
Y499767D01*
G01Y505367D02*
Y502033D01*
X5800D01*
Y505367D01*
G01X8217Y504033D02*
Y502033D01*
G01X10800Y507467D02*
X5800D01*
Y509133D01*
X6050Y509800D01*
X6383Y510300D01*
X6883Y510717D01*
X7467Y511050D01*
X8300Y511133D01*
X9133Y511050D01*
X9717Y510717D01*
X10217Y510300D01*
X10550Y509800D01*
X10800Y509133D01*
Y507467D01*
G01X-14819Y534459D02*
X-19D01*
Y541759D01*
X29681D01*
Y513359D01*
X-19D01*
Y520659D01*
X-14819D01*
Y534459D01*
G01X-1276Y626933D02*
X44324D01*
Y624183D01*
X89624D01*
Y552983D01*
X44324D01*
Y550233D01*
X-1276D01*
Y626933D01*
G01X142Y652569D02*
X14942D01*
Y659869D01*
X44642D01*
Y631469D01*
X14942D01*
Y638769D01*
X142D01*
Y652569D01*
G01X-1276Y745043D02*
X44324D01*
Y742293D01*
X89624D01*
Y671093D01*
X44324D01*
Y668343D01*
X-1276D01*
Y745043D01*
G01X142Y770680D02*
X14942D01*
Y777980D01*
X44642D01*
Y749580D01*
X14942D01*
Y756880D01*
X142D01*
Y770680D01*
G01X41367Y53500D02*
Y58500D01*
X43033D01*
X43700Y58250D01*
X44200Y57917D01*
X44617Y57417D01*
X44950Y56833D01*
X45033Y56000D01*
X44950Y55167D01*
X44617Y54583D01*
X44200Y54083D01*
X43700Y53750D01*
X43033Y53500D01*
X41367D01*
G01X50467D02*
X47133D01*
Y58500D01*
X50467D01*
G01X49133Y56083D02*
X47133D01*
G01X55067Y56167D02*
X55400Y56417D01*
X55650Y56833D01*
X55817Y57417D01*
X55650Y57917D01*
X55317Y58250D01*
X54733Y58500D01*
X52483D01*
Y53500D01*
X55233D01*
X55817Y53833D01*
X56150Y54333D01*
X56317Y54917D01*
X56150Y55500D01*
X55650Y56000D01*
X55067Y56167D01*
X52483D01*
G01X58167Y58500D02*
Y54917D01*
X58500Y54167D01*
X59167Y53667D01*
X60000Y53500D01*
X60833Y53667D01*
X61500Y54167D01*
X61833Y54917D01*
Y58500D01*
G01X66100Y56000D02*
X67767D01*
Y54500D01*
X67267Y54000D01*
X66683Y53667D01*
X65850Y53500D01*
X65017Y53667D01*
X64433Y54000D01*
X63933Y54500D01*
X63600Y55083D01*
X63433Y55750D01*
Y56333D01*
X63600Y56833D01*
X63933Y57417D01*
X64433Y57917D01*
X64933Y58250D01*
X65600Y58500D01*
X66183D01*
X66850Y58333D01*
X67350Y58000D01*
G01X75633Y57983D02*
X75133Y58233D01*
X74550Y58400D01*
X73883D01*
X73133Y58150D01*
X72550Y57733D01*
X72133Y57233D01*
X71800Y56400D01*
X71717Y55650D01*
X71883Y54900D01*
X72133Y54400D01*
X72633Y53900D01*
X73217Y53567D01*
X73800Y53400D01*
X74383D01*
X74967Y53567D01*
X75467Y53817D01*
X75883Y54150D01*
G01X77317Y53400D02*
X79400Y58400D01*
X81483Y53400D01*
G01X80733Y55150D02*
X78067D01*
G01X83333Y53400D02*
Y58400D01*
X85417D01*
X86083Y58150D01*
X86500Y57817D01*
X86667Y57150D01*
X86500Y56483D01*
X86000Y56067D01*
X85417Y55817D01*
X83333D01*
G01X85417D02*
X86667Y53400D01*
G01X88767D02*
Y58400D01*
X90433D01*
X91100Y58150D01*
X91600Y57817D01*
X92017Y57317D01*
X92350Y56733D01*
X92433Y55900D01*
X92350Y55067D01*
X92017Y54483D01*
X91600Y53983D01*
X91100Y53650D01*
X90433Y53400D01*
X88767D01*
G01X35450Y121767D02*
X36117Y121350D01*
X36867Y121100D01*
X37533D01*
X38200Y121350D01*
X38700Y121767D01*
X38950Y122350D01*
X38783Y122933D01*
X38367Y123433D01*
X37617Y123767D01*
X36617Y123933D01*
X36033Y124267D01*
X35783Y124850D01*
X35950Y125433D01*
X36367Y125850D01*
X36950Y126100D01*
X37533D01*
X38117Y125933D01*
X38617Y125517D01*
G01X40967Y121100D02*
Y126100D01*
X42633D01*
X43300Y125850D01*
X43800Y125517D01*
X44217Y125017D01*
X44550Y124433D01*
X44633Y123600D01*
X44550Y122767D01*
X44217Y122183D01*
X43800Y121683D01*
X43300Y121350D01*
X42633Y121100D01*
X40967D01*
G01X52333Y126100D02*
Y121100D01*
X55667D01*
G01X57517D02*
X59600Y126100D01*
X61683Y121100D01*
G01X60933Y122850D02*
X58267D01*
G01X65200Y126100D02*
Y121100D01*
G01X63283Y126100D02*
X67117D01*
G01X72633Y125683D02*
X72133Y125933D01*
X71550Y126100D01*
X70883D01*
X70133Y125850D01*
X69550Y125433D01*
X69133Y124933D01*
X68800Y124100D01*
X68717Y123350D01*
X68883Y122600D01*
X69133Y122100D01*
X69633Y121600D01*
X70217Y121267D01*
X70800Y121100D01*
X71383D01*
X71967Y121267D01*
X72467Y121517D01*
X72883Y121850D01*
G01X74650Y121100D02*
Y126100D01*
G01X78150D02*
Y121100D01*
G01Y123600D02*
X74650D01*
G01X41433Y114100D02*
Y119100D01*
X43517D01*
X44183Y118850D01*
X44600Y118517D01*
X44767Y117850D01*
X44600Y117183D01*
X44100Y116767D01*
X43517Y116517D01*
X41433D01*
G01X43517D02*
X44767Y114100D01*
G01X50367D02*
X47033D01*
Y119100D01*
X50367D01*
G01X49033Y116683D02*
X47033D01*
G01X52633Y119100D02*
Y114100D01*
X55967D01*
G01X61567D02*
X58233D01*
Y119100D01*
X61567D01*
G01X60233Y116683D02*
X58233D01*
G01X63417Y114100D02*
X65500Y119100D01*
X67583Y114100D01*
G01X66833Y115850D02*
X64167D01*
G01X69350Y114767D02*
X70017Y114350D01*
X70767Y114100D01*
X71433D01*
X72100Y114350D01*
X72600Y114767D01*
X72850Y115350D01*
X72683Y115933D01*
X72267Y116433D01*
X71517Y116767D01*
X70517Y116933D01*
X69933Y117267D01*
X69683Y117850D01*
X69850Y118433D01*
X70267Y118850D01*
X70850Y119100D01*
X71433D01*
X72017Y118933D01*
X72517Y118517D01*
G01X78367Y114100D02*
X75033D01*
Y119100D01*
X78367D01*
G01X77033Y116683D02*
X75033D01*
G01X70209Y80838D02*
X62209D01*
Y93238D01*
X70209D01*
Y80838D01*
G01X66209Y82538D02*
X64709Y81038D01*
G01X66209Y82538D02*
X67709Y81038D01*
G01X45100Y108900D02*
X41100D01*
Y101500D01*
G01X43100Y95600D02*
Y91600D01*
X50500D01*
G01Y87400D02*
Y91400D01*
X43100D01*
G01X61000Y97900D02*
X65000D01*
Y105300D01*
G01X65300Y97900D02*
X69300D01*
Y105300D01*
G01X50600Y80900D02*
Y84900D01*
X43200D01*
G01X49000Y128900D02*
Y161700D01*
G01X76600Y128900D02*
X49000D01*
G01X76600Y161700D02*
Y128900D01*
G01X25600Y166567D02*
Y163233D01*
X20600D01*
Y166567D01*
G01X23017Y165233D02*
Y163233D01*
G01X25600Y168583D02*
X20600D01*
X25600Y172417D01*
X20600D01*
G01X21017Y177933D02*
X20767Y177433D01*
X20600Y176850D01*
Y176183D01*
X20850Y175433D01*
X21267Y174850D01*
X21767Y174433D01*
X22600Y174100D01*
X23350Y174017D01*
X24100Y174183D01*
X24600Y174433D01*
X25100Y174933D01*
X25433Y175517D01*
X25600Y176100D01*
Y176683D01*
X25433Y177267D01*
X25183Y177767D01*
X24850Y178183D01*
G01X20600Y180033D02*
X25600D01*
Y183367D01*
G01Y187300D02*
X25517Y186633D01*
X25183Y186050D01*
X24683Y185550D01*
X24100Y185217D01*
X23433Y185050D01*
X22767D01*
X22100Y185217D01*
X21517Y185550D01*
X21017Y186050D01*
X20683Y186633D01*
X20600Y187300D01*
X20683Y187967D01*
X21017Y188550D01*
X21517Y189050D01*
X22100Y189383D01*
X22767Y189550D01*
X23433D01*
X24100Y189383D01*
X24683Y189050D01*
X25183Y188550D01*
X25517Y187967D01*
X25600Y187300D01*
G01X24933Y191150D02*
X25350Y191817D01*
X25600Y192567D01*
Y193233D01*
X25350Y193900D01*
X24933Y194400D01*
X24350Y194650D01*
X23767Y194483D01*
X23267Y194067D01*
X22933Y193317D01*
X22767Y192317D01*
X22433Y191733D01*
X21850Y191483D01*
X21267Y191650D01*
X20850Y192067D01*
X20600Y192650D01*
Y193233D01*
X20767Y193817D01*
X21183Y194317D01*
G01X20600Y196667D02*
X24183D01*
X24933Y197000D01*
X25433Y197667D01*
X25600Y198500D01*
X25433Y199333D01*
X24933Y200000D01*
X24183Y200333D01*
X20600D01*
G01X25600Y202433D02*
X20600D01*
Y204517D01*
X20850Y205183D01*
X21183Y205600D01*
X21850Y205767D01*
X22517Y205600D01*
X22933Y205100D01*
X23183Y204517D01*
Y202433D01*
G01Y204517D02*
X25600Y205767D01*
G01Y211367D02*
Y208033D01*
X20600D01*
Y211367D01*
G01X23017Y210033D02*
Y208033D01*
G01X33433Y162250D02*
X33850Y162917D01*
X34100Y163667D01*
Y164333D01*
X33850Y165000D01*
X33433Y165500D01*
X32850Y165750D01*
X32267Y165583D01*
X31767Y165167D01*
X31433Y164417D01*
X31267Y163417D01*
X30933Y162833D01*
X30350Y162583D01*
X29767Y162750D01*
X29350Y163167D01*
X29100Y163750D01*
Y164333D01*
X29267Y164917D01*
X29683Y165417D01*
G01X29100Y169600D02*
X34100D01*
G01X29100Y167683D02*
Y171517D01*
G01X34100Y173117D02*
X29100Y175200D01*
X34100Y177283D01*
G01X32350Y176533D02*
Y173867D01*
G01X29100Y180800D02*
X34100D01*
G01X29100Y178883D02*
Y182717D01*
G01Y184567D02*
X32683D01*
X33433Y184900D01*
X33933Y185567D01*
X34100Y186400D01*
X33933Y187233D01*
X33433Y187900D01*
X32683Y188233D01*
X29100D01*
G01X33433Y190250D02*
X33850Y190917D01*
X34100Y191667D01*
Y192333D01*
X33850Y193000D01*
X33433Y193500D01*
X32850Y193750D01*
X32267Y193583D01*
X31767Y193167D01*
X31433Y192417D01*
X31267Y191417D01*
X30933Y190833D01*
X30350Y190583D01*
X29767Y190750D01*
X29350Y191167D01*
X29100Y191750D01*
Y192333D01*
X29267Y192917D01*
X29683Y193417D01*
G01X29100Y201533D02*
X34100D01*
Y204867D01*
G01Y210467D02*
Y207133D01*
X29100D01*
Y210467D01*
G01X31517Y209133D02*
Y207133D01*
G01X34100Y212567D02*
X29100D01*
Y214233D01*
X29350Y214900D01*
X29683Y215400D01*
X30183Y215817D01*
X30767Y216150D01*
X31600Y216233D01*
X32433Y216150D01*
X33017Y215817D01*
X33517Y215400D01*
X33850Y214900D01*
X34100Y214233D01*
Y212567D01*
G01X70693Y203035D02*
X84693D01*
G01X70693Y216035D02*
Y203035D01*
G01X64100Y183600D02*
Y197000D01*
G01X74100Y183600D02*
X64100D01*
G01X74100Y197000D02*
Y183600D01*
G01X64100Y197000D02*
X74100D01*
G01X49000Y161700D02*
X76600D01*
G01X61463Y269083D02*
Y265083D01*
X68863D01*
G01X53863Y269083D02*
Y265083D01*
X61263D01*
G01X60963Y274683D02*
Y270683D01*
X68363D01*
G01X61463Y260783D02*
Y256783D01*
X68863D01*
G01X53863Y260883D02*
Y256883D01*
X61263D01*
G01X53463Y278783D02*
Y274783D01*
X60863D01*
G01X60963Y278783D02*
Y274783D01*
X68363D01*
G01X61463Y256683D02*
Y252683D01*
X68863D01*
G01X53863Y253483D02*
Y249483D01*
X61263D01*
G01X61663Y252483D02*
Y248483D01*
X69063D01*
G01X61663Y248283D02*
Y244283D01*
X69063D01*
G01X53746Y244114D02*
Y240114D01*
X61146D01*
G01X61563Y244083D02*
Y240083D01*
X68963D01*
G01X61663Y239683D02*
Y235683D01*
X69063D01*
G01X61463Y264883D02*
Y260883D01*
X68863D01*
G01X77969Y217284D02*
Y221284D01*
X70569D01*
G01X84693Y216035D02*
X70693D01*
G01X47647Y328486D02*
X59447D01*
G01X47647Y296486D02*
Y328486D01*
G01X59447Y296486D02*
X47647D01*
G01X59447Y328486D02*
Y296486D01*
G01X61401Y296778D02*
Y292778D01*
X68801D01*
G01X61401Y292678D02*
Y288678D01*
X68801D01*
G01X53463Y287083D02*
Y283083D01*
X60863D01*
G01X61096Y287730D02*
Y283730D01*
X68496D01*
G01X61096Y283630D02*
Y279630D01*
X68496D01*
G01X72720Y384572D02*
X163508D01*
G01X62877D02*
X69020D01*
G01X61027Y392565D02*
Y386422D01*
G01Y487053D02*
Y396265D01*
G01X62877Y384572D02*
G03I-1850J0D01*
G01Y394415D02*
G03I-1850J0D01*
G01X72720Y384572D02*
G03I-1850J0D01*
G01X48963Y376983D02*
X52963D01*
Y384383D01*
G01X44763Y392483D02*
X48763D01*
Y399883D01*
G01X48863Y384383D02*
X44863D01*
Y376983D01*
G01X67763Y376283D02*
X63763D01*
Y368883D01*
G01X48830Y392489D02*
X52830D01*
Y399889D01*
G01X48963Y384783D02*
X52963D01*
Y392183D01*
G01X44763Y385083D02*
X48763D01*
Y392483D01*
G01X45280Y375862D02*
Y371862D01*
X52680D01*
G01X59563Y368883D02*
X63563D01*
Y376283D01*
G01X61027Y496896D02*
Y490753D01*
G01X69020Y498746D02*
X62877D01*
G01X163508D02*
X72720D01*
G01X62877D02*
G03I-1850J0D01*
G01Y488903D02*
G03I-1850J0D01*
G01X72720Y498746D02*
G03I-1850J0D01*
G01X30345Y497029D02*
Y502229D01*
G01X37345Y497029D02*
Y504829D01*
G01X30345Y497029D02*
X37345D01*
G01X30345Y510429D02*
Y501729D01*
G01X37345Y510429D02*
X30345D01*
G01X37345Y504029D02*
Y510429D01*
G01X68277Y519540D02*
X68577D01*
G01X75677Y515540D02*
Y519540D01*
X68277D01*
G01X68222Y515540D02*
X67922D01*
G01X60822Y519540D02*
Y515540D01*
X68222D01*
G01X57282Y523602D02*
X57582D01*
G01X64682Y519602D02*
Y523602D01*
X57282D01*
G01X57179Y519570D02*
X56879D01*
G01X49779Y523570D02*
Y519570D01*
X57179D01*
G01X46002Y519237D02*
X46302D01*
G01X53402Y515237D02*
Y519237D01*
X46002D01*
G01X45855Y515250D02*
X45555D01*
G01X38455Y519250D02*
Y515250D01*
X45855D01*
G01X71842Y523666D02*
Y519666D01*
X79242D01*
G01X38197Y511109D02*
Y497709D01*
G01X45397Y511109D02*
X38197D01*
G01X45397Y497709D02*
Y511109D01*
G01X38197Y497709D02*
X45397D01*
G01X61384Y643101D02*
X57384D01*
Y635701D01*
G01X81922Y638086D02*
X77922D01*
Y630686D01*
G01X78326Y653588D02*
X82326D01*
Y660988D01*
G01X69207Y645187D02*
Y649187D01*
X61807D01*
G01X77967Y638094D02*
X81967D01*
Y645494D01*
G01X82191Y653287D02*
X78191D01*
Y645887D01*
G01X48900Y648600D02*
X56900D01*
Y631000D01*
X48900D01*
Y648600D01*
G01X62180Y631298D02*
X76180D01*
G01X62180Y644298D02*
Y631298D01*
G01X76180Y644298D02*
X62180D01*
G01X76180Y631298D02*
Y644298D01*
G01X62064Y650003D02*
X76064D01*
G01X62064Y663003D02*
Y650003D01*
G01X76064Y663003D02*
X62064D01*
G01X76064Y650003D02*
Y663003D01*
G01X58122Y749061D02*
X62122D01*
Y756461D01*
G01X69698Y759923D02*
Y763923D01*
X62298D01*
G01X56900Y745000D02*
X48900D01*
Y762600D01*
X56900D01*
Y745000D01*
G01X62662Y746051D02*
X76662D01*
G01X62662Y759051D02*
Y746051D01*
G01X76662Y759051D02*
X62662D01*
G01X76662Y746051D02*
Y759051D01*
G01X62606Y764568D02*
X76606D01*
G01X62606Y777568D02*
Y764568D01*
G01X76606D02*
Y777568D01*
G01X45043Y787964D02*
X78701D01*
G01Y885264D02*
X45043D01*
Y787964D01*
G01X76606Y777568D02*
X62606D01*
G01X157600Y63500D02*
Y69700D01*
X145200D01*
Y63500D01*
G01Y57500D02*
Y51300D01*
X157600D01*
Y57500D01*
G01X122889Y63514D02*
Y69714D01*
X110489D01*
Y63514D01*
G01Y57514D02*
Y51314D01*
X122889D01*
Y57514D01*
G01X109728Y63514D02*
Y69714D01*
X97328D01*
Y63514D01*
G01Y57514D02*
Y51314D01*
X109728D01*
Y57514D01*
G01X125000Y45800D02*
Y57000D01*
G01X143000Y45800D02*
X125000D01*
G01X143000Y57000D02*
Y45800D01*
G01X105783Y81161D02*
X109783D01*
Y88561D01*
G01X81695Y129801D02*
X101245D01*
G01X81695Y118601D02*
Y129801D01*
G01X101245Y118601D02*
X81695D01*
G01X101245Y140201D02*
Y118601D01*
G01X99245Y124201D02*
X101245Y126201D01*
G01X99245Y124201D02*
X101245Y122201D01*
G01X125000Y84200D02*
Y73000D01*
G01X143000Y84200D02*
X125000D01*
G01X143000Y73000D02*
Y84200D01*
G01X144691Y121149D02*
X196591D01*
Y79749D01*
X144691D01*
Y121149D01*
G01X150528Y155985D02*
X129228D01*
Y129685D01*
X150528D01*
Y155985D01*
G01X119608Y110076D02*
Y127676D01*
G01X111608Y110076D02*
X119608D01*
G01X111608Y127676D02*
Y110076D01*
G01X119608Y127676D02*
X111608D01*
G01X109808Y110076D02*
Y127676D01*
G01X101808Y110076D02*
X109808D01*
G01X101808Y127676D02*
Y110076D01*
G01X109808Y127676D02*
X101808D01*
G01X169200Y180800D02*
X146300D01*
Y162000D01*
X152600D01*
Y159100D01*
X152596Y148432D01*
X152600Y141600D01*
X161500D01*
Y137700D01*
X170100D01*
Y126800D01*
G01X95749Y201121D02*
X103749D01*
Y188721D01*
X95749D01*
Y201121D01*
G01X99749Y199421D02*
X101249Y200921D01*
G01X99749Y199421D02*
X98249Y200921D01*
G01X124010Y209099D02*
X168210D01*
Y181299D01*
X124010D01*
Y209099D01*
G01X86296Y197848D02*
X82296D01*
Y190448D01*
G01X85841Y205800D02*
Y201800D01*
X93241D01*
G01X154682Y162664D02*
Y166664D01*
X147282D01*
G01X151031Y174300D02*
X147031D01*
Y166900D01*
G01X116371Y180699D02*
Y184699D01*
X108971D01*
G01X117096Y192370D02*
X113096D01*
Y184970D01*
G01X90100Y139100D02*
Y143100D01*
X82700D01*
G01X120541Y197000D02*
Y201000D01*
X113141D01*
G01X122741Y192500D02*
Y196500D01*
X115341D01*
G01X84693Y203035D02*
Y216035D01*
G01X113171Y208661D02*
Y204661D01*
X120571D01*
G01X89178Y205933D02*
X93178D01*
Y213333D01*
G01X167205Y215431D02*
X136605D01*
Y231031D01*
X167205D01*
Y215431D01*
G01X145610Y333731D02*
X145910D01*
G01X153010Y329731D02*
Y333731D01*
X145610D01*
G01X145553Y329742D02*
X145253D01*
G01X138153Y333742D02*
Y329742D01*
X145553D01*
G01X134517Y337856D02*
X134817D01*
G01X141917Y333856D02*
Y337856D01*
X134517D01*
G01X134417Y333856D02*
X134117D01*
G01X127017Y337856D02*
Y333856D01*
X134417D01*
G01X123273Y333655D02*
X123573D01*
G01X130673Y329655D02*
Y333655D01*
X123273D01*
G01X122955Y329729D02*
X122655D01*
G01X115555Y333729D02*
Y329729D01*
X122955D01*
G01X91350Y375067D02*
X92017Y374650D01*
X92767Y374400D01*
X93433D01*
X94100Y374650D01*
X94600Y375067D01*
X94850Y375650D01*
X94683Y376233D01*
X94267Y376733D01*
X93517Y377067D01*
X92517Y377233D01*
X91933Y377567D01*
X91683Y378150D01*
X91850Y378733D01*
X92267Y379150D01*
X92850Y379400D01*
X93433D01*
X94017Y379233D01*
X94517Y378817D01*
G01X96617Y374400D02*
X98700Y379400D01*
X100783Y374400D01*
G01X100033Y376150D02*
X97367D01*
G01X102550Y375067D02*
X103217Y374650D01*
X103967Y374400D01*
X104633D01*
X105300Y374650D01*
X105800Y375067D01*
X106050Y375650D01*
X105883Y376233D01*
X105467Y376733D01*
X104717Y377067D01*
X103717Y377233D01*
X103133Y377567D01*
X102883Y378150D01*
X103050Y378733D01*
X103467Y379150D01*
X104050Y379400D01*
X104633D01*
X105217Y379233D01*
X105717Y378817D01*
G01X117167Y374400D02*
X113833D01*
Y379400D01*
X117167D01*
G01X115833Y376983D02*
X113833D01*
G01X119350Y374400D02*
X122850Y379400D01*
G01X119350D02*
X122850Y374400D01*
G01X125033D02*
Y379400D01*
X127033D01*
X127700Y379150D01*
X128200Y378567D01*
X128367Y377900D01*
X128200Y377233D01*
X127783Y376733D01*
X127033Y376483D01*
X125033D01*
G01X130217Y374400D02*
X132300Y379400D01*
X134383Y374400D01*
G01X133633Y376150D02*
X130967D01*
G01X135983Y374400D02*
Y379400D01*
X139817Y374400D01*
Y379400D01*
G01X141667Y374400D02*
Y379400D01*
X143333D01*
X144000Y379150D01*
X144500Y378817D01*
X144917Y378317D01*
X145250Y377733D01*
X145333Y376900D01*
X145250Y376067D01*
X144917Y375483D01*
X144500Y374983D01*
X144000Y374650D01*
X143333Y374400D01*
X141667D01*
G01X150767D02*
X147433D01*
Y379400D01*
X150767D01*
G01X149433Y376983D02*
X147433D01*
G01X153033Y374400D02*
Y379400D01*
X155117D01*
X155783Y379150D01*
X156200Y378817D01*
X156367Y378150D01*
X156200Y377483D01*
X155700Y377067D01*
X155117Y376817D01*
X153033D01*
G01X155117D02*
X156367Y374400D01*
G01X102690Y556473D02*
Y558473D01*
G01Y557473D02*
X107690D01*
G01Y556473D02*
Y558473D01*
G01Y561156D02*
X102690D01*
X107690Y564990D01*
X102690D01*
G01Y568673D02*
X107690D01*
G01X102690Y566756D02*
Y570590D01*
G01X105023Y574940D02*
X104773Y575273D01*
X104357Y575523D01*
X103773Y575690D01*
X103273Y575523D01*
X102940Y575190D01*
X102690Y574606D01*
Y572356D01*
X107690D01*
Y575106D01*
X107357Y575690D01*
X106857Y576023D01*
X106273Y576190D01*
X105690Y576023D01*
X105190Y575523D01*
X105023Y574940D01*
Y572356D01*
G01X107023Y583723D02*
X107440Y584390D01*
X107690Y585140D01*
Y585806D01*
X107440Y586473D01*
X107023Y586973D01*
X106440Y587223D01*
X105857Y587056D01*
X105357Y586640D01*
X105023Y585890D01*
X104857Y584890D01*
X104523Y584306D01*
X103940Y584056D01*
X103357Y584223D01*
X102940Y584640D01*
X102690Y585223D01*
Y585806D01*
X102857Y586390D01*
X103273Y586890D01*
G01X107690Y588990D02*
X102690Y591073D01*
X107690Y593156D01*
G01X105940Y592406D02*
Y589740D01*
G01X107023Y594923D02*
X107440Y595590D01*
X107690Y596340D01*
Y597006D01*
X107440Y597673D01*
X107023Y598173D01*
X106440Y598423D01*
X105857Y598256D01*
X105357Y597840D01*
X105023Y597090D01*
X104857Y596090D01*
X104523Y595506D01*
X103940Y595256D01*
X103357Y595423D01*
X102940Y595840D01*
X102690Y596423D01*
Y597006D01*
X102857Y597590D01*
X103273Y598090D01*
G01X103107Y609706D02*
X102857Y609206D01*
X102690Y608623D01*
Y607956D01*
X102940Y607206D01*
X103357Y606623D01*
X103857Y606206D01*
X104690Y605873D01*
X105440Y605790D01*
X106190Y605956D01*
X106690Y606206D01*
X107190Y606706D01*
X107523Y607290D01*
X107690Y607873D01*
Y608456D01*
X107523Y609040D01*
X107273Y609540D01*
X106940Y609956D01*
G01X107690Y613473D02*
X107607Y612806D01*
X107273Y612223D01*
X106773Y611723D01*
X106190Y611390D01*
X105523Y611223D01*
X104857D01*
X104190Y611390D01*
X103607Y611723D01*
X103107Y612223D01*
X102773Y612806D01*
X102690Y613473D01*
X102773Y614140D01*
X103107Y614723D01*
X103607Y615223D01*
X104190Y615556D01*
X104857Y615723D01*
X105523D01*
X106190Y615556D01*
X106773Y615223D01*
X107273Y614723D01*
X107607Y614140D01*
X107690Y613473D01*
G01Y617156D02*
X102690D01*
X107690Y620990D01*
X102690D01*
G01X107690Y622756D02*
X102690D01*
X107690Y626590D01*
X102690D01*
G01X134863Y515903D02*
X134563D01*
G01X127463Y519903D02*
Y515903D01*
X134863D01*
G01X134963Y519903D02*
X135263D01*
G01X142363Y515903D02*
Y519903D01*
X134963D01*
G01X79242Y519666D02*
X78942D01*
G01X79425Y523698D02*
X79725D01*
G01X86825Y519698D02*
Y523698D01*
X79425D01*
G01X90362Y515603D02*
X90062D01*
G01X82962Y519603D02*
Y515603D01*
X90362D01*
G01X90450Y519603D02*
X90750D01*
G01X97850Y515603D02*
Y519603D01*
X90450D01*
G01X101385Y519826D02*
X101085D01*
G01X93985Y523826D02*
Y519826D01*
X101385D01*
G01X101504Y523857D02*
X101804D01*
G01X108904Y519857D02*
Y523857D01*
X101504D01*
G01X112607Y515857D02*
X112307D01*
G01X105207Y519857D02*
Y515857D01*
X112607D01*
G01X112725Y519858D02*
X113025D01*
G01X120125Y515858D02*
Y519858D01*
X112725D01*
G01X123751Y520079D02*
X123451D01*
G01X116351Y524079D02*
Y520079D01*
X123751D01*
G01X123800Y524071D02*
X124100D01*
G01X131200Y520071D02*
Y524071D01*
X123800D01*
G01X145912Y520038D02*
X145612D01*
G01X138512Y524038D02*
Y520038D01*
X145912D01*
G01X145954Y524037D02*
X146254D01*
G01X153354Y520037D02*
Y524037D01*
X145954D01*
G01X93207Y646181D02*
X95207D01*
G01X94207D02*
Y641181D01*
G01X93207D02*
X95207D01*
G01X97890D02*
Y646181D01*
X101724Y641181D01*
Y646181D01*
G01X105407D02*
Y641181D01*
G01X103490Y646181D02*
X107324D01*
G01X108924Y641181D02*
X111007Y646181D01*
X113090Y641181D01*
G01X112340Y642931D02*
X109674D01*
G01X120457Y641848D02*
X121124Y641431D01*
X121874Y641181D01*
X122540D01*
X123207Y641431D01*
X123707Y641848D01*
X123957Y642431D01*
X123790Y643014D01*
X123374Y643514D01*
X122624Y643848D01*
X121624Y644014D01*
X121040Y644348D01*
X120790Y644931D01*
X120957Y645514D01*
X121374Y645931D01*
X121957Y646181D01*
X122540D01*
X123124Y646014D01*
X123624Y645598D01*
G01X125724Y641181D02*
X127807Y646181D01*
X129890Y641181D01*
G01X129140Y642931D02*
X126474D01*
G01X131657Y641848D02*
X132324Y641431D01*
X133074Y641181D01*
X133740D01*
X134407Y641431D01*
X134907Y641848D01*
X135157Y642431D01*
X134990Y643014D01*
X134574Y643514D01*
X133824Y643848D01*
X132824Y644014D01*
X132240Y644348D01*
X131990Y644931D01*
X132157Y645514D01*
X132574Y645931D01*
X133157Y646181D01*
X133740D01*
X134324Y646014D01*
X134824Y645598D01*
G01X142940Y646181D02*
Y641181D01*
X146274D01*
G01X151874D02*
X148540D01*
Y646181D01*
X151874D01*
G01X150540Y643764D02*
X148540D01*
G01X153974Y641181D02*
Y646181D01*
X155640D01*
X156307Y645931D01*
X156807Y645598D01*
X157224Y645098D01*
X157557Y644514D01*
X157640Y643681D01*
X157557Y642848D01*
X157224Y642264D01*
X156807Y641764D01*
X156307Y641431D01*
X155640Y641181D01*
X153974D01*
G01X98700Y671800D02*
Y673800D01*
G01Y672800D02*
X103700D01*
G01Y671800D02*
Y673800D01*
G01Y676483D02*
X98700D01*
X103700Y680317D01*
X98700D01*
G01Y684000D02*
X103700D01*
G01X98700Y682083D02*
Y685917D01*
G01X103700Y687517D02*
X98700Y689600D01*
X103700Y691683D01*
G01X101950Y690933D02*
Y688267D01*
G01X103033Y699050D02*
X103450Y699717D01*
X103700Y700467D01*
Y701133D01*
X103450Y701800D01*
X103033Y702300D01*
X102450Y702550D01*
X101867Y702383D01*
X101367Y701967D01*
X101033Y701217D01*
X100867Y700217D01*
X100533Y699633D01*
X99950Y699383D01*
X99367Y699550D01*
X98950Y699967D01*
X98700Y700550D01*
Y701133D01*
X98867Y701717D01*
X99283Y702217D01*
G01X103700Y704317D02*
X98700Y706400D01*
X103700Y708483D01*
G01X101950Y707733D02*
Y705067D01*
G01X103033Y710250D02*
X103450Y710917D01*
X103700Y711667D01*
Y712333D01*
X103450Y713000D01*
X103033Y713500D01*
X102450Y713750D01*
X101867Y713583D01*
X101367Y713167D01*
X101033Y712417D01*
X100867Y711417D01*
X100533Y710833D01*
X99950Y710583D01*
X99367Y710750D01*
X98950Y711167D01*
X98700Y711750D01*
Y712333D01*
X98867Y712917D01*
X99283Y713417D01*
G01X99117Y725033D02*
X98867Y724533D01*
X98700Y723950D01*
Y723283D01*
X98950Y722533D01*
X99367Y721950D01*
X99867Y721533D01*
X100700Y721200D01*
X101450Y721117D01*
X102200Y721283D01*
X102700Y721533D01*
X103200Y722033D01*
X103533Y722617D01*
X103700Y723200D01*
Y723783D01*
X103533Y724367D01*
X103283Y724867D01*
X102950Y725283D01*
G01X103700Y728800D02*
X103617Y728133D01*
X103283Y727550D01*
X102783Y727050D01*
X102200Y726717D01*
X101533Y726550D01*
X100867D01*
X100200Y726717D01*
X99617Y727050D01*
X99117Y727550D01*
X98783Y728133D01*
X98700Y728800D01*
X98783Y729467D01*
X99117Y730050D01*
X99617Y730550D01*
X100200Y730883D01*
X100867Y731050D01*
X101533D01*
X102200Y730883D01*
X102783Y730550D01*
X103283Y730050D01*
X103617Y729467D01*
X103700Y728800D01*
G01Y732483D02*
X98700D01*
X103700Y736317D01*
X98700D01*
G01X103700Y738083D02*
X98700D01*
X103700Y741917D01*
X98700D01*
G01X111144Y757459D02*
X107810D01*
Y762459D01*
X111144D01*
G01X109810Y760042D02*
X107810D01*
G01X113327Y757459D02*
X116827Y762459D01*
G01X113327D02*
X116827Y757459D01*
G01X120677Y762459D02*
Y757459D01*
G01X118760Y762459D02*
X122594D01*
G01X130127Y758126D02*
X130794Y757709D01*
X131544Y757459D01*
X132210D01*
X132877Y757709D01*
X133377Y758126D01*
X133627Y758709D01*
X133460Y759292D01*
X133044Y759792D01*
X132294Y760126D01*
X131294Y760292D01*
X130710Y760626D01*
X130460Y761209D01*
X130627Y761792D01*
X131044Y762209D01*
X131627Y762459D01*
X132210D01*
X132794Y762292D01*
X133294Y761876D01*
G01X135394Y757459D02*
X137477Y762459D01*
X139560Y757459D01*
G01X138810Y759209D02*
X136144D01*
G01X141327Y758126D02*
X141994Y757709D01*
X142744Y757459D01*
X143410D01*
X144077Y757709D01*
X144577Y758126D01*
X144827Y758709D01*
X144660Y759292D01*
X144244Y759792D01*
X143494Y760126D01*
X142494Y760292D01*
X141910Y760626D01*
X141660Y761209D01*
X141827Y761792D01*
X142244Y762209D01*
X142827Y762459D01*
X143410D01*
X143994Y762292D01*
X144494Y761876D01*
G01X152610Y762459D02*
Y757459D01*
X155944D01*
G01X161544D02*
X158210D01*
Y762459D01*
X161544D01*
G01X160210Y760042D02*
X158210D01*
G01X163644Y757459D02*
Y762459D01*
X165310D01*
X165977Y762209D01*
X166477Y761876D01*
X166894Y761376D01*
X167227Y760792D01*
X167310Y759959D01*
X167227Y759126D01*
X166894Y758542D01*
X166477Y758042D01*
X165977Y757709D01*
X165310Y757459D01*
X163644D01*
G01X82653Y753104D02*
X78653D01*
Y745704D01*
G01X82464Y770206D02*
X78464D01*
Y762806D01*
G01X78653Y753247D02*
X82653D01*
Y760647D01*
G01X78701Y787964D02*
X204643D01*
Y885264D01*
X78701D01*
Y787964D01*
G01X132443Y808914D02*
Y864314D01*
G01X179743Y808914D02*
X132443D01*
G01X78415Y770933D02*
X82415D01*
Y778333D01*
G01X132443Y864314D02*
X179743D01*
G01X170700Y63500D02*
Y69700D01*
X158300D01*
Y63500D01*
G01Y57500D02*
Y51300D01*
X170700D01*
Y57500D01*
G01X169200Y218300D02*
Y225200D01*
X212600D01*
Y204000D01*
X204400D01*
Y178900D01*
X187800D01*
Y151600D01*
X199200D01*
Y126800D01*
X170100D01*
G01X212240Y73333D02*
Y68333D01*
X217240D01*
G01X213247Y74259D02*
X210247D01*
G01X213247Y84102D02*
X211247D01*
G01X206612Y76030D02*
X210612D01*
Y83430D01*
G01X215959Y108010D02*
Y104010D01*
X223359D01*
G01X219622Y99900D02*
Y103900D01*
X212222D01*
G01X208420Y91789D02*
Y95789D01*
X201020D01*
G01X207064Y83481D02*
Y87481D01*
X199664D01*
G01X208690Y100533D02*
Y104533D01*
X201290D01*
G01X201025Y100053D02*
Y96053D01*
X208425D01*
G01X219113Y136260D02*
X215113D01*
Y128860D01*
G01X198100Y127300D02*
Y149900D01*
G01X187900Y127300D02*
X198100D01*
G01X187900Y149900D02*
Y127300D01*
G01X198100D02*
Y149900D01*
G01X187900Y127300D02*
X198100D01*
G01X187900Y149900D02*
Y127300D01*
G01X201600Y132500D02*
Y138000D01*
G01X209600Y132500D02*
X201600D01*
G01X209600Y138000D02*
Y132500D01*
G01X169200Y180800D02*
Y218200D01*
G01X161449Y147197D02*
X156449D01*
Y152197D01*
G01X161449Y168997D02*
X156449D01*
Y163997D01*
G01X178249D02*
Y168997D01*
X173249D01*
G01X177239Y160066D02*
X179239D01*
G01X157459D02*
X154459D01*
G01X228659Y192850D02*
Y200850D01*
X216709D01*
Y192850D01*
X228659D01*
G01X216709Y199000D02*
X218709Y197000D01*
X216709Y195000D01*
G01X217504Y176170D02*
X221504D01*
Y183570D01*
G01X174685Y177433D02*
X170685D01*
Y170033D01*
G01X170353Y145690D02*
X166353D01*
Y138290D01*
G01X175087Y170033D02*
X179087D01*
Y177433D01*
G01X165761Y143062D02*
Y147062D01*
X158361D01*
G01X165249Y174397D02*
Y178397D01*
X157849D01*
G01X198100Y149900D02*
X187900D01*
G01X198100D02*
X187900D01*
G01X209600Y150100D02*
Y144600D01*
G01X201600Y150100D02*
X209600D01*
G01X201600Y144600D02*
Y150100D01*
G01X211108Y169068D02*
Y140068D01*
G01X246108Y169068D02*
X211108D01*
G01Y140068D02*
X246108D01*
G01X191400Y169700D02*
X209000D01*
G01X191400Y177700D02*
Y169700D01*
G01X209000Y177700D02*
X191400D01*
G01X209000Y169700D02*
Y177700D01*
G01X181843Y274656D02*
Y278656D01*
X174443D01*
G01X181882Y269928D02*
Y273928D01*
X174482D01*
G01X181743Y265018D02*
Y269018D01*
X174343D01*
G01X182756Y259409D02*
Y263409D01*
X175356D01*
G01X181109Y254562D02*
Y258562D01*
X173709D01*
G01X180977Y249228D02*
Y253228D01*
X173577D01*
G01X180850Y244422D02*
Y248422D01*
X173450D01*
G01X179390Y235502D02*
Y239502D01*
X171990D01*
G01X179390Y239702D02*
Y243702D01*
X171990D01*
G01X181810Y279361D02*
Y283361D01*
X174410D01*
G01X182010Y292061D02*
Y296061D01*
X174610D01*
G01X181910Y283561D02*
Y287561D01*
X174510D01*
G01X182010Y287861D02*
Y291861D01*
X174610D01*
G01X156681Y337850D02*
X156981D01*
G01X164081Y333850D02*
Y337850D01*
X156681D01*
G01X156552Y333814D02*
X156252D01*
G01X149152Y337814D02*
Y333814D01*
X156552D01*
G01X186138Y342153D02*
Y346153D01*
X178738D01*
G01X178638Y342153D02*
X178338D01*
G01X171238Y346153D02*
Y342153D01*
X178638D01*
G01X167685Y341913D02*
X167985D01*
G01X175085Y337913D02*
Y341913D01*
X167685D01*
G01X167585Y337913D02*
X167285D01*
G01X160185Y341913D02*
Y337913D01*
X167585D01*
G01X175201Y396265D02*
Y487053D01*
G01Y386422D02*
Y392565D01*
G01X167208Y384572D02*
X173351D01*
G01X177051D02*
G03I-1850J0D01*
G01Y394415D02*
G03I-1850J0D01*
G01X167208Y384572D02*
G03I-1850J0D01*
G01X191415Y418933D02*
X187415D01*
Y411533D01*
G01X183215Y412633D02*
X187215D01*
Y420033D01*
G01X211880Y354594D02*
X211580D01*
G01X204480Y358594D02*
Y354594D01*
X211880D01*
G01X212080Y358594D02*
X212380D01*
G01X219480Y354594D02*
Y358594D01*
X212080D01*
G01X215685Y365914D02*
Y361914D01*
X223085D01*
G01X200938Y354449D02*
X201238D01*
G01X208338Y350449D02*
Y354449D01*
X200938D01*
G01X200838Y350449D02*
X200538D01*
G01X193438Y354449D02*
Y350449D01*
X200838D01*
G01X189857Y350289D02*
X190157D01*
G01X197257Y346289D02*
Y350289D01*
X189857D01*
G01X189757Y346289D02*
X189457D01*
G01X182357Y350289D02*
Y346289D01*
X189757D01*
G01X178738Y346153D02*
X179038D01*
G01X211684Y392527D02*
Y379127D01*
G01X218884Y392527D02*
X211684D01*
G01X218884Y379127D02*
Y392527D01*
G01X211684Y379127D02*
X218884D01*
G01X195054Y477445D02*
X195010D01*
Y467712D01*
X215000Y467700D01*
Y466800D01*
X222400D01*
Y465000D01*
G01X222600Y460900D02*
Y458300D01*
X209600D01*
Y456400D01*
X200600D01*
Y453800D01*
X192000D01*
Y456100D01*
X181300D01*
Y461200D01*
G01X196106Y468868D02*
Y498468D01*
X221006D01*
Y468868D01*
X196106D01*
G01X187566Y483243D02*
Y479243D01*
X194966D01*
G01X187266Y487343D02*
X183266D01*
Y479943D01*
G01X217500Y447700D02*
Y451700D01*
X210100D01*
G01X194966Y483443D02*
Y487443D01*
X187566D01*
G01X217606Y446601D02*
Y435801D01*
X212406D01*
Y446601D01*
X217606D01*
G01X179367Y495500D02*
X182700Y502500D01*
X186033Y495500D01*
G01X184833Y497950D02*
X180567D01*
G01X173351Y498746D02*
X167208D01*
G01X175201Y490753D02*
Y496896D01*
G01X177051Y498746D02*
G03I-1850J0D01*
G01Y488903D02*
G03I-1850J0D01*
G01X167208Y498746D02*
G03I-1850J0D01*
G01X176781Y554832D02*
Y586832D01*
G01X188581Y554832D02*
X176781D01*
G01X188581Y586832D02*
Y554832D01*
G01X183266Y487643D02*
X187266D01*
Y495043D01*
G01X194966Y487543D02*
Y491543D01*
X187566D01*
G01X179104Y519848D02*
X179404D01*
G01X186504Y515848D02*
Y519848D01*
X179104D01*
G01X179049Y515848D02*
X178749D01*
G01X171649Y519848D02*
Y515848D01*
X179049D01*
G01X156874Y515879D02*
X156574D01*
G01X149474Y519879D02*
Y515879D01*
X156874D01*
G01X156967Y519830D02*
X157267D01*
G01X164367Y515830D02*
Y519830D01*
X156967D01*
G01X167905Y520020D02*
X167605D01*
G01X160505Y524020D02*
Y520020D01*
X167905D01*
G01X168087Y524020D02*
X168387D01*
G01X175487Y520020D02*
Y524020D01*
X168087D01*
G01X212463Y523903D02*
X212763D01*
G01X219863Y519903D02*
Y523903D01*
X212463D01*
G01X212263Y520003D02*
X211963D01*
G01X204863Y524003D02*
Y520003D01*
X212263D01*
G01X201263Y519803D02*
X201563D01*
G01X208663Y515803D02*
Y519803D01*
X201263D01*
G01X201063Y515803D02*
X200763D01*
G01X193663Y519803D02*
Y515803D01*
X201063D01*
G01X190163Y524003D02*
X190463D01*
G01X197563Y520003D02*
Y524003D01*
X190163D01*
G01X190063Y520003D02*
X189763D01*
G01X182663Y524003D02*
Y520003D01*
X190063D01*
G01X176781Y586832D02*
X188581D01*
G01X228659Y759780D02*
Y767780D01*
X216709D01*
Y759780D01*
X228659D01*
G01X216709Y765930D02*
X218709Y763930D01*
X216709Y761930D01*
G01X217303Y742714D02*
X221303D01*
Y750114D01*
G01X221100Y809167D02*
Y805833D01*
X216100D01*
Y809167D01*
G01X218517Y807833D02*
Y805833D01*
G01X221100Y811350D02*
X216100Y814850D01*
G01Y811350D02*
X221100Y814850D01*
G01X216100Y818700D02*
X221100D01*
G01X216100Y816783D02*
Y820617D01*
G01X220433Y828150D02*
X220850Y828817D01*
X221100Y829567D01*
Y830233D01*
X220850Y830900D01*
X220433Y831400D01*
X219850Y831650D01*
X219267Y831483D01*
X218767Y831067D01*
X218433Y830317D01*
X218267Y829317D01*
X217933Y828733D01*
X217350Y828483D01*
X216767Y828650D01*
X216350Y829067D01*
X216100Y829650D01*
Y830233D01*
X216267Y830817D01*
X216683Y831317D01*
G01X221100Y833417D02*
X216100Y835500D01*
X221100Y837583D01*
G01X219350Y836833D02*
Y834167D01*
G01X220433Y839350D02*
X220850Y840017D01*
X221100Y840767D01*
Y841433D01*
X220850Y842100D01*
X220433Y842600D01*
X219850Y842850D01*
X219267Y842683D01*
X218767Y842267D01*
X218433Y841517D01*
X218267Y840517D01*
X217933Y839933D01*
X217350Y839683D01*
X216767Y839850D01*
X216350Y840267D01*
X216100Y840850D01*
Y841433D01*
X216267Y842017D01*
X216683Y842517D01*
G01X216517Y854133D02*
X216267Y853633D01*
X216100Y853050D01*
Y852383D01*
X216350Y851633D01*
X216767Y851050D01*
X217267Y850633D01*
X218100Y850300D01*
X218850Y850217D01*
X219600Y850383D01*
X220100Y850633D01*
X220600Y851133D01*
X220933Y851717D01*
X221100Y852300D01*
Y852883D01*
X220933Y853467D01*
X220683Y853967D01*
X220350Y854383D01*
G01X221100Y857900D02*
X221017Y857233D01*
X220683Y856650D01*
X220183Y856150D01*
X219600Y855817D01*
X218933Y855650D01*
X218267D01*
X217600Y855817D01*
X217017Y856150D01*
X216517Y856650D01*
X216183Y857233D01*
X216100Y857900D01*
X216183Y858567D01*
X216517Y859150D01*
X217017Y859650D01*
X217600Y859983D01*
X218267Y860150D01*
X218933D01*
X219600Y859983D01*
X220183Y859650D01*
X220683Y859150D01*
X221017Y858567D01*
X221100Y857900D01*
G01Y861583D02*
X216100D01*
X221100Y865417D01*
X216100D01*
G01X221100Y867183D02*
X216100D01*
X221100Y871017D01*
X216100D01*
G01X179743Y864314D02*
Y808914D01*
G01X227613Y59498D02*
X231613D01*
Y66898D01*
G01X227231Y67020D02*
X223231D01*
Y59620D01*
G01X279505Y44089D02*
Y66689D01*
G01X269305Y44089D02*
X279505D01*
G01X269305Y66689D02*
Y44089D01*
G01X279505D02*
Y66689D01*
G01X269305Y44089D02*
X279505D01*
G01X269305Y66689D02*
Y44089D01*
G01X239940Y90933D02*
Y95933D01*
X234940D01*
G01Y68333D02*
X239940D01*
Y73333D01*
G01X238933Y88039D02*
X241933D01*
G01X238933Y78196D02*
X240933D01*
G01X244715Y95933D02*
Y91933D01*
X252115D01*
G01X250190Y96033D02*
Y100033D01*
X242790D01*
G01X244690Y91833D02*
Y87833D01*
X252090D01*
G01X242646Y79735D02*
Y75735D01*
X250046D01*
G01X242790Y104533D02*
Y100533D01*
X250190D01*
G01X242652Y75668D02*
Y71668D01*
X250052D01*
G01X227002Y136216D02*
X223002D01*
Y128816D01*
G01X279505Y66689D02*
X269305D01*
G01X279505D02*
X269305D01*
G01X249500Y131300D02*
Y139300D01*
G01X231900Y131300D02*
X249500D01*
G01X231900Y139300D02*
Y131300D01*
G01X242400Y202800D02*
Y197800D01*
G01X240483Y202800D02*
X244317D01*
G01X249667Y197800D02*
X246333D01*
Y202800D01*
X249667D01*
G01X248333Y200383D02*
X246333D01*
G01X251433Y197800D02*
Y202800D01*
X253600Y198633D01*
X255767Y202800D01*
Y197800D01*
G01X257533D02*
Y202800D01*
X259533D01*
X260200Y202550D01*
X260700Y201967D01*
X260867Y201300D01*
X260700Y200633D01*
X260283Y200133D01*
X259533Y199883D01*
X257533D01*
G01X268650Y198467D02*
X269317Y198050D01*
X270067Y197800D01*
X270733D01*
X271400Y198050D01*
X271900Y198467D01*
X272150Y199050D01*
X271983Y199633D01*
X271567Y200133D01*
X270817Y200467D01*
X269817Y200633D01*
X269233Y200967D01*
X268983Y201550D01*
X269150Y202133D01*
X269567Y202550D01*
X270150Y202800D01*
X270733D01*
X271317Y202633D01*
X271817Y202217D01*
G01X277667Y197800D02*
X274333D01*
Y202800D01*
X277667D01*
G01X276333Y200383D02*
X274333D01*
G01X279683Y197800D02*
Y202800D01*
X283517Y197800D01*
Y202800D01*
G01X285450Y198467D02*
X286117Y198050D01*
X286867Y197800D01*
X287533D01*
X288200Y198050D01*
X288700Y198467D01*
X288950Y199050D01*
X288783Y199633D01*
X288367Y200133D01*
X287617Y200467D01*
X286617Y200633D01*
X286033Y200967D01*
X285783Y201550D01*
X285950Y202133D01*
X286367Y202550D01*
X286950Y202800D01*
X287533D01*
X288117Y202633D01*
X288617Y202217D01*
G01X292800Y197800D02*
X292133Y197883D01*
X291550Y198217D01*
X291050Y198717D01*
X290717Y199300D01*
X290550Y199967D01*
Y200633D01*
X290717Y201300D01*
X291050Y201883D01*
X291550Y202383D01*
X292133Y202717D01*
X292800Y202800D01*
X293467Y202717D01*
X294050Y202383D01*
X294550Y201883D01*
X294883Y201300D01*
X295050Y200633D01*
Y199967D01*
X294883Y199300D01*
X294550Y198717D01*
X294050Y198217D01*
X293467Y197883D01*
X292800Y197800D01*
G01X296733D02*
Y202800D01*
X298817D01*
X299483Y202550D01*
X299900Y202217D01*
X300067Y201550D01*
X299900Y200883D01*
X299400Y200467D01*
X298817Y200217D01*
X296733D01*
G01X298817D02*
X300067Y197800D01*
G01X302417Y201967D02*
X302917Y202467D01*
X303500Y202717D01*
X304167Y202800D01*
X305000Y202633D01*
X305583Y202217D01*
X305750Y201717D01*
X305667Y201217D01*
X305333Y200800D01*
X303667Y199967D01*
X302917Y199383D01*
X302417Y198550D01*
X302250Y197800D01*
X305750D01*
G01X221817Y176208D02*
X225817D01*
Y183608D01*
G01X246108Y140068D02*
Y169068D01*
G01X249500Y139300D02*
X231900D01*
G01X229066Y216917D02*
Y220917D01*
X221666D01*
G01X233414Y212313D02*
X237414D01*
Y219713D01*
G01X221702Y216585D02*
Y212585D01*
X229102D01*
G01X233350Y219608D02*
X229350D01*
Y212208D01*
G01X280367Y372600D02*
X277033D01*
Y377600D01*
X280367D01*
G01X279033Y375183D02*
X277033D01*
G01X282550Y372600D02*
X286050Y377600D01*
G01X282550D02*
X286050Y372600D01*
G01X288233D02*
Y377600D01*
X290233D01*
X290900Y377350D01*
X291400Y376767D01*
X291567Y376100D01*
X291400Y375433D01*
X290983Y374933D01*
X290233Y374683D01*
X288233D01*
G01X301100Y377600D02*
Y372600D01*
G01X299183Y377600D02*
X303017D01*
G01X308367Y372600D02*
X305033D01*
Y377600D01*
X308367D01*
G01X307033Y375183D02*
X305033D01*
G01X310133Y372600D02*
Y377600D01*
X312300Y373433D01*
X314467Y377600D01*
Y372600D01*
G01X316233D02*
Y377600D01*
X318233D01*
X318900Y377350D01*
X319400Y376767D01*
X319567Y376100D01*
X319400Y375433D01*
X318983Y374933D01*
X318233Y374683D01*
X316233D01*
G01X327350Y373267D02*
X328017Y372850D01*
X328767Y372600D01*
X329433D01*
X330100Y372850D01*
X330600Y373267D01*
X330850Y373850D01*
X330683Y374433D01*
X330267Y374933D01*
X329517Y375267D01*
X328517Y375433D01*
X327933Y375767D01*
X327683Y376350D01*
X327850Y376933D01*
X328267Y377350D01*
X328850Y377600D01*
X329433D01*
X330017Y377433D01*
X330517Y377017D01*
G01X336367Y372600D02*
X333033D01*
Y377600D01*
X336367D01*
G01X335033Y375183D02*
X333033D01*
G01X338383Y372600D02*
Y377600D01*
X342217Y372600D01*
Y377600D01*
G01X344150Y373267D02*
X344817Y372850D01*
X345567Y372600D01*
X346233D01*
X346900Y372850D01*
X347400Y373267D01*
X347650Y373850D01*
X347483Y374433D01*
X347067Y374933D01*
X346317Y375267D01*
X345317Y375433D01*
X344733Y375767D01*
X344483Y376350D01*
X344650Y376933D01*
X345067Y377350D01*
X345650Y377600D01*
X346233D01*
X346817Y377433D01*
X347317Y377017D01*
G01X351500Y372600D02*
X350833Y372683D01*
X350250Y373017D01*
X349750Y373517D01*
X349417Y374100D01*
X349250Y374767D01*
Y375433D01*
X349417Y376100D01*
X349750Y376683D01*
X350250Y377183D01*
X350833Y377517D01*
X351500Y377600D01*
X352167Y377517D01*
X352750Y377183D01*
X353250Y376683D01*
X353583Y376100D01*
X353750Y375433D01*
Y374767D01*
X353583Y374100D01*
X353250Y373517D01*
X352750Y373017D01*
X352167Y372683D01*
X351500Y372600D01*
G01X355433D02*
Y377600D01*
X357517D01*
X358183Y377350D01*
X358600Y377017D01*
X358767Y376350D01*
X358600Y375683D01*
X358100Y375267D01*
X357517Y375017D01*
X355433D01*
G01X357517D02*
X358767Y372600D01*
G01X229722Y397136D02*
Y389136D01*
G01Y403136D02*
Y397136D01*
G01Y403136D02*
Y389136D01*
G01X247722Y403136D02*
X229722D01*
G01X247722Y389136D02*
Y403136D01*
G01X229722Y389136D02*
X247722D01*
G01X275768Y410128D02*
Y420128D01*
G01X261768Y410128D02*
X275768D01*
G01X261768Y420128D02*
Y410128D01*
G01X236000Y412700D02*
X240000D01*
Y420100D01*
G01X225900Y412600D02*
X229900D01*
Y420000D01*
G01X230100Y412600D02*
X234100D01*
Y420000D01*
G01X247153Y389029D02*
Y385029D01*
X254553D01*
G01X238662Y381684D02*
X242662D01*
Y389084D01*
G01X238158Y403205D02*
Y407205D01*
X230758D01*
G01X255209Y401106D02*
Y405106D01*
X247809D01*
G01X228428Y400441D02*
X224428D01*
Y393041D01*
G01X224254Y400349D02*
X220254D01*
Y392949D01*
G01X219821Y379161D02*
Y384361D01*
G01X226821Y379161D02*
Y386961D01*
G01X219821Y379161D02*
X226821D01*
G01X219821Y392561D02*
Y383861D01*
G01X226821Y392561D02*
X219821D01*
G01X226821Y386161D02*
Y392561D01*
G01X234637Y381693D02*
Y381993D01*
G01X238637Y389093D02*
X234637D01*
Y381693D01*
G01X223085Y361914D02*
X222785D01*
G01X223139Y365907D02*
X223439D01*
G01X230539Y361907D02*
Y365907D01*
X223139D01*
G01X243728Y362156D02*
Y361856D01*
G01X239728Y354756D02*
X243728D01*
Y362156D01*
G01X239728Y362256D02*
Y362556D01*
G01X243728Y369656D02*
X239728D01*
Y362256D01*
G01X239455Y373255D02*
Y372955D01*
G01X235455Y365855D02*
X239455D01*
Y373255D01*
G01X235455Y373355D02*
Y373655D01*
G01X239455Y380755D02*
X235455D01*
Y373355D01*
G01X219900Y444500D02*
X240000D01*
G01X239700D02*
Y432100D01*
G01X219900D02*
X239700D01*
G01X219900Y444500D02*
Y432100D01*
G01X238700Y438300D02*
X239700Y439300D01*
G01Y437300D02*
X238700Y438300D01*
G01X261768Y436128D02*
Y426128D01*
G01X275768Y436128D02*
X261768D01*
G01X275768Y426128D02*
Y436128D01*
G01X272963Y478953D02*
X290963D01*
G01X272963Y490153D02*
Y478953D01*
G01X248103Y426291D02*
Y430291D01*
X240703D01*
G01X240697Y434409D02*
Y430409D01*
X248097D01*
G01X240700Y434600D02*
X244700D01*
Y442000D01*
G01X248800D02*
X244800D01*
Y434600D01*
G01X240599Y459252D02*
Y463252D01*
X233199D01*
G01X233300Y484954D02*
Y480954D01*
X240700D01*
G01X240716Y471688D02*
Y475688D01*
X233316D01*
G01X233108Y469537D02*
X229108D01*
Y462137D01*
G01X228992Y469483D02*
X224992D01*
Y462083D01*
G01X242100Y463700D02*
X252900D01*
Y458500D01*
X242100D01*
Y463700D01*
G01X233156Y480817D02*
X243956D01*
Y475617D01*
X233156D01*
Y480817D01*
G01X234073Y471523D02*
X244873D01*
Y466323D01*
X234073D01*
Y471523D01*
G01X263200Y546100D02*
X262533Y546183D01*
X261950Y546517D01*
X261450Y547017D01*
X261117Y547600D01*
X260950Y548267D01*
Y548933D01*
X261117Y549600D01*
X261450Y550183D01*
X261950Y550683D01*
X262533Y551017D01*
X263200Y551100D01*
X263867Y551017D01*
X264450Y550683D01*
X264950Y550183D01*
X265283Y549600D01*
X265450Y548933D01*
Y548267D01*
X265283Y547600D01*
X264950Y547017D01*
X264450Y546517D01*
X263867Y546183D01*
X263200Y546100D01*
G01X267050Y546767D02*
X267717Y546350D01*
X268467Y546100D01*
X269133D01*
X269800Y546350D01*
X270300Y546767D01*
X270550Y547350D01*
X270383Y547933D01*
X269967Y548433D01*
X269217Y548767D01*
X268217Y548933D01*
X267633Y549267D01*
X267383Y549850D01*
X267550Y550433D01*
X267967Y550850D01*
X268550Y551100D01*
X269133D01*
X269717Y550933D01*
X270217Y550517D01*
G01X276233Y550683D02*
X275733Y550933D01*
X275150Y551100D01*
X274483D01*
X273733Y550850D01*
X273150Y550433D01*
X272733Y549933D01*
X272400Y549100D01*
X272317Y548350D01*
X272483Y547600D01*
X272733Y547100D01*
X273233Y546600D01*
X273817Y546267D01*
X274400Y546100D01*
X274983D01*
X275567Y546267D01*
X276067Y546517D01*
X276483Y546850D01*
G01X280000Y546100D02*
Y551100D01*
X279000Y550100D01*
G01Y546100D02*
X281000D01*
G01X285600Y545933D02*
X285433Y546017D01*
Y546183D01*
X285600Y546267D01*
X285767Y546183D01*
Y546017D01*
X285600Y545933D01*
G01Y548183D02*
X285433Y548267D01*
Y548433D01*
X285600Y548517D01*
X285767Y548433D01*
Y548267D01*
X285600Y548183D01*
G01X291200Y546100D02*
Y551100D01*
X290200Y550100D01*
G01Y546100D02*
X292200D01*
G01X294967Y546850D02*
X295467Y546433D01*
X296050Y546183D01*
X296800Y546100D01*
X297550Y546267D01*
X298133Y546600D01*
X298550Y547183D01*
X298633Y547850D01*
X298467Y548517D01*
X298050Y548933D01*
X297467Y549267D01*
X296883Y549350D01*
X296300Y549267D01*
X295550Y548933D01*
X295800Y551100D01*
X298050D01*
G01X302400D02*
X301733Y550933D01*
X301233Y550517D01*
X300900Y550017D01*
X300650Y549350D01*
X300567Y548600D01*
X300650Y547850D01*
X300900Y547183D01*
X301233Y546683D01*
X301733Y546267D01*
X302400Y546100D01*
X303067Y546267D01*
X303567Y546683D01*
X303900Y547183D01*
X304150Y547850D01*
X304233Y548600D01*
X304150Y549350D01*
X303900Y550017D01*
X303567Y550517D01*
X303067Y550933D01*
X302400Y551100D01*
G01X305833Y546100D02*
Y551100D01*
X308000Y546933D01*
X310167Y551100D01*
Y546100D01*
G01X311850D02*
Y551100D01*
G01X315350D02*
Y546100D01*
G01Y548600D02*
X311850D01*
G01X317617Y551100D02*
X320783D01*
X317617Y546100D01*
X320783D01*
G01X272963Y517353D02*
X290963D01*
G01X272963Y506153D02*
Y517353D01*
G01X257682Y506847D02*
Y501647D01*
G01X250682Y506847D02*
Y499047D01*
G01X257682Y506847D02*
X250682D01*
G01X257682Y493447D02*
Y502147D01*
G01X250682Y493447D02*
X257682D01*
G01X250682Y499847D02*
Y493447D01*
G01X240703Y530378D02*
Y525178D01*
G01X233703Y530378D02*
Y522578D01*
G01X240703Y530378D02*
X233703D01*
G01X240703Y516978D02*
Y525678D01*
G01X233703Y516978D02*
X240703D01*
G01X233703Y523378D02*
Y516978D01*
G01X266101Y493618D02*
Y507018D01*
G01X258901Y493618D02*
X266101D01*
G01X258901Y507018D02*
Y493618D01*
G01X266101Y507018D02*
X258901D01*
G01X232841Y517101D02*
Y530501D01*
G01X225641Y517101D02*
X232841D01*
G01X225641Y530501D02*
Y517101D01*
G01X232841Y530501D02*
X225641D01*
G01X239100Y765800D02*
Y760800D01*
G01X237183Y765800D02*
X241017D01*
G01X246367Y760800D02*
X243033D01*
Y765800D01*
X246367D01*
G01X245033Y763383D02*
X243033D01*
G01X248133Y760800D02*
Y765800D01*
X250300Y761633D01*
X252467Y765800D01*
Y760800D01*
G01X254233D02*
Y765800D01*
X256233D01*
X256900Y765550D01*
X257400Y764967D01*
X257567Y764300D01*
X257400Y763633D01*
X256983Y763133D01*
X256233Y762883D01*
X254233D01*
G01X265350Y761467D02*
X266017Y761050D01*
X266767Y760800D01*
X267433D01*
X268100Y761050D01*
X268600Y761467D01*
X268850Y762050D01*
X268683Y762633D01*
X268267Y763133D01*
X267517Y763467D01*
X266517Y763633D01*
X265933Y763967D01*
X265683Y764550D01*
X265850Y765133D01*
X266267Y765550D01*
X266850Y765800D01*
X267433D01*
X268017Y765633D01*
X268517Y765217D01*
G01X274367Y760800D02*
X271033D01*
Y765800D01*
X274367D01*
G01X273033Y763383D02*
X271033D01*
G01X276383Y760800D02*
Y765800D01*
X280217Y760800D01*
Y765800D01*
G01X282150Y761467D02*
X282817Y761050D01*
X283567Y760800D01*
X284233D01*
X284900Y761050D01*
X285400Y761467D01*
X285650Y762050D01*
X285483Y762633D01*
X285067Y763133D01*
X284317Y763467D01*
X283317Y763633D01*
X282733Y763967D01*
X282483Y764550D01*
X282650Y765133D01*
X283067Y765550D01*
X283650Y765800D01*
X284233D01*
X284817Y765633D01*
X285317Y765217D01*
G01X289500Y760800D02*
X288833Y760883D01*
X288250Y761217D01*
X287750Y761717D01*
X287417Y762300D01*
X287250Y762967D01*
Y763633D01*
X287417Y764300D01*
X287750Y764883D01*
X288250Y765383D01*
X288833Y765717D01*
X289500Y765800D01*
X290167Y765717D01*
X290750Y765383D01*
X291250Y764883D01*
X291583Y764300D01*
X291750Y763633D01*
Y762967D01*
X291583Y762300D01*
X291250Y761717D01*
X290750Y761217D01*
X290167Y760883D01*
X289500Y760800D01*
G01X293433D02*
Y765800D01*
X295517D01*
X296183Y765550D01*
X296600Y765217D01*
X296767Y764550D01*
X296600Y763883D01*
X296100Y763467D01*
X295517Y763217D01*
X293433D01*
G01X295517D02*
X296767Y760800D01*
G01X300700D02*
Y765800D01*
X299700Y764800D01*
G01Y760800D02*
X301700D01*
G01X221658Y742714D02*
X225658D01*
Y750114D01*
G01X229162Y781010D02*
Y777010D01*
X236562D01*
G01X232524Y769383D02*
X236524D01*
Y776783D01*
G01X229266Y785159D02*
Y781159D01*
X236666D01*
G01X229221Y789335D02*
Y785335D01*
X236621D01*
G01X280342Y796780D02*
Y792780D01*
X287742D01*
G01X255982Y804835D02*
Y841835D01*
X387982D01*
Y804835D01*
X255982D01*
G01X349774Y33579D02*
Y44779D01*
G01X331774Y33579D02*
X349774D01*
G01X331774Y44779D02*
Y33579D01*
G01X349774Y71979D02*
Y60779D01*
G01X331774D02*
Y71979D01*
G01X319274Y33579D02*
Y44779D01*
G01X301274Y33579D02*
X319274D01*
G01X301274Y44779D02*
Y33579D01*
G01X319274Y71979D02*
Y60779D01*
G01X301274D02*
Y71979D01*
G01X331774D02*
X349774D01*
G01X301274D02*
X319274D01*
G01X334791Y388798D02*
Y399998D01*
G01X352791Y388798D02*
X334791D01*
G01X352791Y399998D02*
Y388798D01*
G01X290963Y478953D02*
Y490153D01*
G01X352292Y478804D02*
Y490004D01*
G01X334292Y478804D02*
X352292D01*
G01X334292Y490004D02*
Y478804D01*
G01X321767Y478579D02*
Y489779D01*
G01X303767Y478579D02*
X321767D01*
G01X303767Y489779D02*
Y478579D01*
G01X334791Y427198D02*
Y415998D01*
G01X352791Y427198D02*
X334791D01*
G01X352791Y415998D02*
Y427198D01*
G01X314221Y477162D02*
Y465962D01*
G01X332221Y477162D02*
X314221D01*
G01X332221Y465962D02*
Y477162D01*
G01X314221Y438762D02*
Y449962D01*
G01X332221Y438762D02*
X314221D01*
G01X332221Y449962D02*
Y438762D01*
G01X290751Y434310D02*
Y439810D01*
G01X298751Y434310D02*
X290751D01*
G01X298751Y439810D02*
Y434310D01*
G01Y451910D02*
Y446410D01*
G01X290751Y451910D02*
X298751D01*
G01X290751Y446410D02*
Y451910D01*
G01X299549Y434256D02*
Y439756D01*
G01X307549Y434256D02*
X299549D01*
G01X307549Y439756D02*
Y434256D01*
G01Y451856D02*
Y446356D01*
G01X299549Y451856D02*
X307549D01*
G01X299549Y446356D02*
Y451856D01*
G01X336600Y562400D02*
X350900D01*
Y539800D01*
X378100D01*
Y525700D01*
X336600D01*
Y562400D01*
G01X290963Y517353D02*
Y506153D01*
G01X352292Y517204D02*
Y506004D01*
G01X334292Y517204D02*
X352292D01*
G01X334292Y506004D02*
Y517204D01*
G01X321767Y516979D02*
Y505779D01*
G01X303767Y516979D02*
X321767D01*
G01X303767Y505779D02*
Y516979D01*
G01X332746Y795055D02*
Y791055D01*
X340146D01*
G01X363400Y790962D02*
Y794962D01*
X356000D01*
G01X348527Y794923D02*
Y790923D01*
X355927D01*
G01X303499Y796862D02*
Y792862D01*
X310899D01*
G01X348234Y790836D02*
Y794836D01*
X340834D01*
G01X313715Y797010D02*
Y793010D01*
X321115D01*
G01X292176Y796808D02*
Y792808D01*
X299576D01*
G01X313882Y804835D02*
Y806835D01*
X330082D01*
Y804835D01*
G01X313883Y860471D02*
X315883D01*
G01X314883D02*
Y855471D01*
G01X313883D02*
X315883D01*
G01X322316Y860054D02*
X321816Y860304D01*
X321233Y860471D01*
X320566D01*
X319816Y860221D01*
X319233Y859804D01*
X318816Y859304D01*
X318483Y858471D01*
X318400Y857721D01*
X318566Y856971D01*
X318816Y856471D01*
X319316Y855971D01*
X319900Y855638D01*
X320483Y855471D01*
X321066D01*
X321650Y855638D01*
X322150Y855888D01*
X322566Y856221D01*
G01X327750Y855471D02*
X324416D01*
Y860471D01*
X327750D01*
G01X326416Y858054D02*
X324416D01*
G01X339116Y860054D02*
X338616Y860304D01*
X338033Y860471D01*
X337366D01*
X336616Y860221D01*
X336033Y859804D01*
X335616Y859304D01*
X335283Y858471D01*
X335200Y857721D01*
X335366Y856971D01*
X335616Y856471D01*
X336116Y855971D01*
X336700Y855638D01*
X337283Y855471D01*
X337866D01*
X338450Y855638D01*
X338950Y855888D01*
X339366Y856221D01*
G01X342883Y855471D02*
X342216Y855554D01*
X341633Y855888D01*
X341133Y856388D01*
X340800Y856971D01*
X340633Y857638D01*
Y858304D01*
X340800Y858971D01*
X341133Y859554D01*
X341633Y860054D01*
X342216Y860388D01*
X342883Y860471D01*
X343550Y860388D01*
X344133Y860054D01*
X344633Y859554D01*
X344966Y858971D01*
X345133Y858304D01*
Y857638D01*
X344966Y856971D01*
X344633Y856388D01*
X344133Y855888D01*
X343550Y855554D01*
X342883Y855471D01*
G01X346566D02*
Y860471D01*
X350400Y855471D01*
Y860471D01*
G01X352166Y855471D02*
Y860471D01*
X356000Y855471D01*
Y860471D01*
G01X380274Y33579D02*
Y44779D01*
G01X362274Y33579D02*
X380274D01*
G01X362274Y44779D02*
Y33579D01*
G01X380274Y71979D02*
Y60779D01*
G01X362274D02*
Y71979D01*
G01D02*
X380274D01*
G01X390376Y205632D02*
Y215632D01*
X384209Y208465D01*
X392543D01*
G01X398976Y205632D02*
X400143Y205799D01*
X401476Y206299D01*
X402309Y207132D01*
X402643Y208299D01*
X402309Y209465D01*
X401309Y210465D01*
X399809Y210965D01*
X398143D01*
X397143Y211299D01*
X396309Y212132D01*
X395976Y213299D01*
X396476Y214465D01*
X397642Y215299D01*
X398976Y215632D01*
X400309Y215299D01*
X401476Y214465D01*
X401976Y213299D01*
X401643Y212132D01*
X400809Y211299D01*
X399809Y210965D01*
X398143D01*
X396643Y210465D01*
X395643Y209465D01*
X395309Y208299D01*
X395643Y207132D01*
X396476Y206299D01*
X397809Y205799D01*
X398976Y205632D01*
G01X409576Y205299D02*
X409243Y205465D01*
Y205799D01*
X409576Y205965D01*
X409909Y205799D01*
Y205465D01*
X409576Y205299D01*
G01X417009Y209798D02*
X418176Y210965D01*
X419176Y211632D01*
X420509Y211965D01*
X421676Y211632D01*
X422509Y210965D01*
X423176Y209965D01*
X423343Y208799D01*
X423176Y207799D01*
X422509Y206798D01*
X421509Y205965D01*
X420343Y205632D01*
X419009Y205965D01*
X417843Y206965D01*
X417176Y208465D01*
X417009Y210132D01*
X417343Y212298D01*
X417843Y213465D01*
X418676Y214632D01*
X419843Y215465D01*
X421009Y215632D01*
X422176Y215299D01*
X423009Y214465D01*
G01X432776Y205632D02*
Y215632D01*
X426609Y208465D01*
X434943D01*
G01X436376Y215632D02*
X438709Y205632D01*
X441376Y215632D01*
X444043Y205632D01*
X446376Y215632D01*
G01X451976D02*
X450642Y215299D01*
X449643Y214465D01*
X448976Y213465D01*
X448476Y212132D01*
X448309Y210632D01*
X448476Y209132D01*
X448976Y207799D01*
X449643Y206798D01*
X450642Y205965D01*
X451976Y205632D01*
X453309Y205965D01*
X454309Y206798D01*
X454976Y207799D01*
X455476Y209132D01*
X455643Y210632D01*
X455476Y212132D01*
X454976Y213465D01*
X454309Y214465D01*
X453309Y215299D01*
X451976Y215632D01*
G01X458909Y207132D02*
X459909Y206299D01*
X461076Y205799D01*
X462576Y205632D01*
X464076Y205965D01*
X465243Y206632D01*
X466076Y207799D01*
X466243Y209132D01*
X465909Y210465D01*
X465076Y211299D01*
X463909Y211965D01*
X462743Y212132D01*
X461576Y211965D01*
X460076Y211299D01*
X460576Y215632D01*
X465076D01*
G01X473176Y205299D02*
X472843Y205465D01*
Y205799D01*
X473176Y205965D01*
X473509Y205799D01*
Y205465D01*
X473176Y205299D01*
G01X483776Y215632D02*
X482442Y215299D01*
X481443Y214465D01*
X480776Y213465D01*
X480276Y212132D01*
X480109Y210632D01*
X480276Y209132D01*
X480776Y207799D01*
X481443Y206798D01*
X482442Y205965D01*
X483776Y205632D01*
X485109Y205965D01*
X486109Y206798D01*
X486776Y207799D01*
X487276Y209132D01*
X487443Y210632D01*
X487276Y212132D01*
X486776Y213465D01*
X486109Y214465D01*
X485109Y215299D01*
X483776Y215632D01*
G01X494376Y205632D02*
Y215632D01*
X492376Y213632D01*
G01Y205632D02*
X496376D01*
G01X504976D02*
Y215632D01*
X502976Y213632D01*
G01Y205632D02*
X506976D01*
G01X387699Y190144D02*
Y200144D01*
X392032Y191811D01*
X396365Y200144D01*
Y190144D01*
G01X398465D02*
X402632Y200144D01*
X406799Y190144D01*
G01X405299Y193644D02*
X399965D01*
G01X409565Y190144D02*
Y200144D01*
X412899D01*
X414232Y199644D01*
X415232Y198977D01*
X416065Y197977D01*
X416732Y196810D01*
X416899Y195144D01*
X416732Y193477D01*
X416065Y192311D01*
X415232Y191310D01*
X414232Y190644D01*
X412899Y190144D01*
X409565D01*
G01X427165D02*
X420499D01*
Y200144D01*
X427165D01*
G01X424499Y195311D02*
X420499D01*
G01X443032Y200144D02*
X447032D01*
G01X445032D02*
Y190144D01*
G01X443032D02*
X447032D01*
G01X451799D02*
Y200144D01*
X459465Y190144D01*
Y200144D01*
G01X476832D02*
Y190144D01*
G01X472999Y200144D02*
X480665D01*
G01X483265Y190144D02*
X487432Y200144D01*
X491599Y190144D01*
G01X490099Y193644D02*
X484765D01*
G01X496032Y200144D02*
X500032D01*
G01X498032D02*
Y190144D01*
G01X496032D02*
X500032D01*
G01X503632Y200144D02*
X505965Y190144D01*
X508632Y200144D01*
X511299Y190144D01*
X513632Y200144D01*
G01X515065Y190144D02*
X519232Y200144D01*
X523399Y190144D01*
G01X521899Y193644D02*
X516565D01*
G01X525999Y190144D02*
Y200144D01*
X533665Y190144D01*
Y200144D01*
G01X389689Y222351D02*
Y232351D01*
X387689Y230351D01*
G01Y222351D02*
X391689D01*
G01X397122Y230684D02*
X398122Y231684D01*
X399289Y232184D01*
X400622Y232351D01*
X402289Y232018D01*
X403456Y231184D01*
X403789Y230184D01*
X403622Y229184D01*
X402956Y228351D01*
X399622Y226684D01*
X398122Y225518D01*
X397122Y223851D01*
X396789Y222351D01*
X403789D01*
G01X410889Y232351D02*
X409555Y232018D01*
X408556Y231184D01*
X407889Y230184D01*
X407389Y228851D01*
X407222Y227351D01*
X407389Y225851D01*
X407889Y224518D01*
X408556Y223517D01*
X409555Y222684D01*
X410889Y222351D01*
X412222Y222684D01*
X413222Y223517D01*
X413889Y224518D01*
X414389Y225851D01*
X414556Y227351D01*
X414389Y228851D01*
X413889Y230184D01*
X413222Y231184D01*
X412222Y232018D01*
X410889Y232351D01*
G01X421489D02*
X420155Y232018D01*
X419156Y231184D01*
X418489Y230184D01*
X417989Y228851D01*
X417822Y227351D01*
X417989Y225851D01*
X418489Y224518D01*
X419156Y223517D01*
X420155Y222684D01*
X421489Y222351D01*
X422822Y222684D01*
X423822Y223517D01*
X424489Y224518D01*
X424989Y225851D01*
X425156Y227351D01*
X424989Y228851D01*
X424489Y230184D01*
X423822Y231184D01*
X422822Y232018D01*
X421489Y232351D01*
G01X434089Y222351D02*
Y232351D01*
X427922Y225184D01*
X436256D01*
G01X440522Y225684D02*
X444856D01*
G01X453289Y222351D02*
Y232351D01*
X451289Y230351D01*
G01Y222351D02*
X455289D01*
G01X388053Y237309D02*
Y247309D01*
G01X394387D02*
X388053Y241142D01*
G01X395387Y237309D02*
X390887Y243975D01*
G01X398487Y237309D02*
Y247309D01*
X406153Y237309D01*
Y247309D01*
G01X412920Y237309D02*
X411586Y237476D01*
X410420Y238142D01*
X409420Y239142D01*
X408753Y240309D01*
X408420Y241642D01*
Y242976D01*
X408753Y244309D01*
X409420Y245476D01*
X410420Y246476D01*
X411586Y247142D01*
X412920Y247309D01*
X414253Y247142D01*
X415420Y246476D01*
X416420Y245476D01*
X417087Y244309D01*
X417420Y242976D01*
Y241642D01*
X417087Y240309D01*
X416420Y239142D01*
X415420Y238142D01*
X414253Y237476D01*
X412920Y237309D01*
G01X420020D02*
X427020Y247309D01*
G01X420020D02*
X427020Y237309D01*
G01X448053D02*
X441387D01*
Y247309D01*
X448053D01*
G01X445387Y242476D02*
X441387D01*
G01X451820Y237309D02*
X458820Y247309D01*
G01X451820D02*
X458820Y237309D01*
G01X462587D02*
Y247309D01*
X466587D01*
X467920Y246809D01*
X468920Y245642D01*
X469253Y244309D01*
X468920Y242976D01*
X468087Y241976D01*
X466587Y241475D01*
X462587D01*
G01X472353Y237309D02*
X476520Y247309D01*
X480687Y237309D01*
G01X479187Y240809D02*
X473853D01*
G01X483287Y237309D02*
Y247309D01*
X490953Y237309D01*
Y247309D01*
G01X494053Y237309D02*
Y247309D01*
X497387D01*
X498720Y246809D01*
X499720Y246142D01*
X500553Y245142D01*
X501220Y243975D01*
X501387Y242309D01*
X501220Y240642D01*
X500553Y239476D01*
X499720Y238475D01*
X498720Y237809D01*
X497387Y237309D01*
X494053D01*
G01X511653D02*
X504987D01*
Y247309D01*
X511653D01*
G01X508987Y242476D02*
X504987D01*
G01X515587Y237309D02*
Y247309D01*
X519753D01*
X521087Y246809D01*
X521920Y246142D01*
X522253Y244809D01*
X521920Y243476D01*
X520920Y242642D01*
X519753Y242142D01*
X515587D01*
G01X519753D02*
X522253Y237309D01*
G01X541453Y242642D02*
X542120Y243142D01*
X542620Y243975D01*
X542953Y245142D01*
X542620Y246142D01*
X541953Y246809D01*
X540787Y247309D01*
X536287D01*
Y237309D01*
X541787D01*
X542953Y237976D01*
X543620Y238976D01*
X543953Y240142D01*
X543620Y241309D01*
X542620Y242309D01*
X541453Y242642D01*
X536287D01*
G01X550720Y237309D02*
X549386Y237476D01*
X548220Y238142D01*
X547220Y239142D01*
X546553Y240309D01*
X546220Y241642D01*
Y242976D01*
X546553Y244309D01*
X547220Y245476D01*
X548220Y246476D01*
X549386Y247142D01*
X550720Y247309D01*
X552053Y247142D01*
X553220Y246476D01*
X554220Y245476D01*
X554887Y244309D01*
X555220Y242976D01*
Y241642D01*
X554887Y240309D01*
X554220Y239142D01*
X553220Y238142D01*
X552053Y237476D01*
X550720Y237309D01*
G01X557153D02*
X561320Y247309D01*
X565487Y237309D01*
G01X563987Y240809D02*
X558653D01*
G01X568587Y237309D02*
Y247309D01*
X572753D01*
X574087Y246809D01*
X574920Y246142D01*
X575253Y244809D01*
X574920Y243476D01*
X573920Y242642D01*
X572753Y242142D01*
X568587D01*
G01X572753D02*
X575253Y237309D01*
G01X578853D02*
Y247309D01*
X582187D01*
X583520Y246809D01*
X584520Y246142D01*
X585353Y245142D01*
X586020Y243975D01*
X586187Y242309D01*
X586020Y240642D01*
X585353Y239476D01*
X584520Y238475D01*
X583520Y237809D01*
X582187Y237309D01*
X578853D01*
G01X368267Y529200D02*
X371600Y536200D01*
X374933Y529200D01*
G01X373733Y531650D02*
X369467D01*
G01X498000Y373500D02*
X524000D01*
G01X498000Y386500D02*
Y373500D01*
G01X524000Y386500D02*
X498000D01*
G01X464170Y512032D02*
X472170D01*
Y499632D01*
X464170D01*
Y512032D01*
G01X468170Y510332D02*
X469670Y511832D01*
G01X468170Y510332D02*
X466670Y511832D01*
G01X464163Y512834D02*
Y516834D01*
X456763D01*
G01X471795Y512834D02*
Y516834D01*
X464395D01*
G01X492837Y526628D02*
Y530628D01*
X485437D01*
G01X492883Y535159D02*
Y539159D01*
X485483D01*
G01X492613Y543645D02*
Y547645D01*
X485213D01*
G01X485430Y534955D02*
Y530955D01*
X492830D01*
G01X485438Y543335D02*
Y539335D01*
X492838D01*
G01X485123Y551911D02*
Y547911D01*
X492523D01*
G01X492766Y487976D02*
Y491976D01*
X485366D01*
G01X473287Y492049D02*
Y488049D01*
X480687D01*
G01X455141Y492002D02*
Y488002D01*
X462541D01*
G01X445090Y498442D02*
X449090D01*
Y505842D01*
G01X485499Y510498D02*
Y506498D01*
X492899D01*
G01X485502Y514828D02*
Y510828D01*
X492902D01*
G01X445418Y510324D02*
Y506324D01*
X452818D01*
G01X518634Y400225D02*
X520434Y402325D01*
X522634Y400225D01*
G01X526234Y400125D02*
Y419325D01*
X515034D01*
Y400125D01*
X526234D01*
Y400525D01*
G01X502027Y407475D02*
X506027D01*
Y414875D01*
G01X534700Y391000D02*
Y395000D01*
X527300D01*
G01X501981Y415019D02*
X505981D01*
Y422419D01*
G01X502094Y399932D02*
X506094D01*
Y407332D01*
G01X502700Y391700D02*
Y387700D01*
X510100D01*
G01X539200Y399800D02*
X535200D01*
Y392400D01*
G01X510500Y399300D02*
Y387900D01*
G01X523900Y399300D02*
X510500D01*
G01X523900Y387900D02*
Y399300D01*
G01X510500Y387900D02*
X523900D01*
G01X524000Y373500D02*
Y386500D01*
G01X506334Y426179D02*
Y422179D01*
X513734D01*
G01X523410Y533644D02*
Y529644D01*
X530810D01*
G01X523388Y529470D02*
Y525470D01*
X530788D01*
G01X523463Y540533D02*
X527463D01*
Y547933D01*
G01X630623Y526113D02*
X648223D01*
G01X630623Y534113D02*
Y526113D01*
G01X648223Y534113D02*
X630623D01*
G01X647933Y287400D02*
Y292400D01*
X650017D01*
X650683Y292150D01*
X651100Y291817D01*
X651267Y291150D01*
X651100Y290483D01*
X650600Y290067D01*
X650017Y289817D01*
X647933D01*
G01X650017D02*
X651267Y287400D01*
G01X655200D02*
X654533Y287483D01*
X653950Y287817D01*
X653450Y288317D01*
X653117Y288900D01*
X652950Y289567D01*
Y290233D01*
X653117Y290900D01*
X653450Y291483D01*
X653950Y291983D01*
X654533Y292317D01*
X655200Y292400D01*
X655867Y292317D01*
X656450Y291983D01*
X656950Y291483D01*
X657283Y290900D01*
X657450Y290233D01*
Y289567D01*
X657283Y288900D01*
X656950Y288317D01*
X656450Y287817D01*
X655867Y287483D01*
X655200Y287400D01*
G01X659050D02*
Y292400D01*
G01X662550D02*
Y287400D01*
G01Y289900D02*
X659050D01*
G01X664650Y288067D02*
X665317Y287650D01*
X666067Y287400D01*
X666733D01*
X667400Y287650D01*
X667900Y288067D01*
X668150Y288650D01*
X667983Y289233D01*
X667567Y289733D01*
X666817Y290067D01*
X665817Y290233D01*
X665233Y290567D01*
X664983Y291150D01*
X665150Y291733D01*
X665567Y292150D01*
X666150Y292400D01*
X666733D01*
X667317Y292233D01*
X667817Y291817D01*
G01X678933Y290317D02*
X678350Y290650D01*
X677850Y290733D01*
X677183Y290567D01*
X676683Y290233D01*
X676350Y289650D01*
X676267Y289067D01*
X676350Y288483D01*
X676683Y287983D01*
X677183Y287567D01*
X677850Y287400D01*
X678433Y287567D01*
X678933Y287900D01*
G01X683200Y287400D02*
X682700Y287483D01*
X682200Y287817D01*
X681867Y288400D01*
X681700Y289067D01*
X681867Y289733D01*
X682200Y290317D01*
X682700Y290650D01*
X683200Y290733D01*
X683700Y290650D01*
X684200Y290317D01*
X684533Y289733D01*
X684617Y289067D01*
X684533Y288400D01*
X684200Y287817D01*
X683700Y287483D01*
X683200Y287400D01*
G01X686300D02*
Y290733D01*
G01Y289817D02*
X686550Y290233D01*
X686967Y290567D01*
X687550Y290733D01*
X688133Y290567D01*
X688550Y290233D01*
X688800Y289817D01*
Y287400D01*
G01Y289817D02*
X689050Y290233D01*
X689467Y290567D01*
X690050Y290733D01*
X690633Y290567D01*
X691050Y290233D01*
X691300Y289733D01*
Y287400D01*
G01X692900Y285733D02*
Y290733D01*
G01Y289983D02*
X693317Y290400D01*
X693733Y290650D01*
X694400Y290733D01*
X694983Y290650D01*
X695567Y290233D01*
X695817Y289650D01*
X695900Y289067D01*
X695817Y288483D01*
X695567Y287900D01*
X695067Y287567D01*
X694400Y287400D01*
X693817Y287483D01*
X693233Y287733D01*
X692900Y288067D01*
G01X700000Y287400D02*
Y292400D01*
G01X705600Y290733D02*
Y287400D01*
G01Y292067D02*
X705433Y292150D01*
Y292317D01*
X705600Y292400D01*
X705767Y292317D01*
Y292150D01*
X705600Y292067D01*
G01X712700Y287400D02*
Y290733D01*
G01Y290150D02*
X712367Y290483D01*
X711867Y290650D01*
X711283Y290733D01*
X710700Y290567D01*
X710200Y290233D01*
X709867Y289733D01*
X709700Y289067D01*
X709867Y288400D01*
X710200Y287900D01*
X710700Y287567D01*
X711283Y287400D01*
X711867Y287483D01*
X712367Y287733D01*
X712700Y288067D01*
G01X715383Y287400D02*
Y290733D01*
G01Y289900D02*
X715717Y290317D01*
X716217Y290650D01*
X716883Y290733D01*
X717467Y290650D01*
X717967Y290317D01*
X718217Y289733D01*
Y287400D01*
G01X723733Y290317D02*
X723150Y290650D01*
X722650Y290733D01*
X721983Y290567D01*
X721483Y290233D01*
X721150Y289650D01*
X721067Y289067D01*
X721150Y288483D01*
X721483Y287983D01*
X721983Y287567D01*
X722650Y287400D01*
X723233Y287567D01*
X723733Y287900D01*
G01X726750Y289650D02*
X729417D01*
X729167Y290233D01*
X728750Y290567D01*
X728167Y290733D01*
X727583Y290650D01*
X727083Y290400D01*
X726750Y289817D01*
X726583Y289317D01*
Y288817D01*
X726750Y288317D01*
X727167Y287817D01*
X727667Y287483D01*
X728250Y287400D01*
X728833Y287567D01*
X729417Y288067D01*
G01X677434Y311754D02*
X679684D01*
G01X677434Y305874D02*
Y311754D01*
G01X679684Y305874D02*
X677434D01*
G01X678784Y308909D02*
X677434D01*
G01X683184Y307544D02*
Y311754D01*
G01X682954Y306659D02*
X683184Y307544D01*
G01X682504Y306074D02*
X682954Y306659D01*
G01X681939Y305874D02*
X682504Y306074D01*
G01X681374D02*
X681939Y305874D01*
G01X680924Y306659D02*
X681374Y306074D01*
G01X680699Y307544D02*
X680924Y306659D01*
G01X680699Y311754D02*
Y307544D01*
G01X689149Y305969D02*
X688704Y305874D01*
G01X689549Y306364D02*
X689149Y305969D01*
G01X689884Y306954D02*
X689549Y306364D01*
G01X690114Y307639D02*
X689884Y306954D01*
G01X690224Y308424D02*
X690114Y307639D01*
G01X690224Y309204D02*
Y308424D01*
G01X690114Y309989D02*
X690224Y309204D01*
G01X689884Y310674D02*
X690114Y309989D01*
G01X689549Y311264D02*
X689884Y310674D01*
G01X689149Y311659D02*
X689549Y311264D01*
G01X688704Y311754D02*
X689149Y311659D01*
G01X688254D02*
X688704Y311754D01*
G01X687854Y311264D02*
X688254Y311659D01*
G01X687519Y310674D02*
X687854Y311264D01*
G01X687289Y309989D02*
X687519Y310674D01*
G01X687179Y309204D02*
X687289Y309989D01*
G01X687179Y308424D02*
Y309204D01*
G01X687289Y307639D02*
X687179Y308424D01*
G01X687519Y306954D02*
X687289Y307639D01*
G01X687854Y306364D02*
X687519Y306954D01*
G01X688254Y305969D02*
X687854Y306364D01*
G01X688704Y305874D02*
X688254Y305969D01*
G01X691129Y305874D02*
Y309794D01*
G01X693039Y308614D02*
Y305874D01*
G01X692869Y309304D02*
X693039Y308614D01*
G01X692529Y309694D02*
X692869Y309304D01*
G01X692139Y309794D02*
X692529Y309694D01*
G01X691684D02*
X692139Y309794D01*
G01X691349Y309304D02*
X691684Y309694D01*
G01X691129Y308814D02*
X691349Y309304D01*
G01X695464Y305874D02*
Y311754D01*
G01X699294Y306559D02*
X700029Y309794D01*
G01X698954Y304994D02*
X699294Y306559D01*
G01X698734Y304499D02*
X698954Y304994D01*
G01X698449Y304109D02*
X698734Y304499D01*
G01X697999Y303914D02*
X698449Y304109D01*
G01X697659D02*
X697999Y303914D01*
G01X698229Y309794D02*
X699294Y306559D01*
G01X651100Y392600D02*
Y396600D01*
X643700D01*
G01X675409Y460023D02*
Y464023D01*
X668009D01*
G01X706009Y455923D02*
Y451923D01*
X713409D01*
G01X663909Y460723D02*
X667909D01*
Y468123D01*
G01X659609Y476323D02*
X655609D01*
Y468923D01*
G01X663709Y472223D02*
X659709D01*
Y464823D01*
G01X676109Y459923D02*
X672109D01*
Y452523D01*
G01X680509Y455723D02*
X676509D01*
Y448323D01*
G01X658909Y476423D02*
Y480423D01*
X651509D01*
G01X654809Y480723D02*
Y484723D01*
X647409D01*
G01Y477323D02*
X651409D01*
Y484723D01*
G01X668009Y456623D02*
X672009D01*
Y464023D01*
G01X671309Y464123D02*
Y468123D01*
X663909D01*
G01X651509Y473023D02*
X655509D01*
Y480423D01*
G01X655609Y476323D02*
Y472323D01*
X663009D01*
G01X710109Y460023D02*
Y456023D01*
X717509D01*
G01X659709Y472223D02*
Y468223D01*
X667109D01*
G01X672109Y459923D02*
Y455923D01*
X679509D01*
G01X709409Y448523D02*
X713409D01*
Y455923D01*
G01X676509Y455723D02*
Y451723D01*
X683909D01*
G01X663407Y537619D02*
X658407D01*
Y532619D01*
G01X686107D02*
Y537619D01*
X681107D01*
G01Y509919D02*
X686107D01*
Y514919D01*
G01X659814Y518651D02*
X656814D01*
G01X684700Y528887D02*
X687700D01*
G01X667139Y536212D02*
Y538212D01*
G01X677375Y511326D02*
Y509326D01*
G01X656800Y534900D02*
X652800D01*
Y527500D01*
G01X648700D02*
X652700D01*
Y534900D01*
G01X687000Y539000D02*
Y535000D01*
X694400D01*
G01X693700Y542300D02*
Y546300D01*
X686300D01*
G01X688689Y519755D02*
X694189D01*
G01X688689Y511755D02*
Y519755D01*
G01X694189Y511755D02*
X688689D01*
G01X706289D02*
X700789D01*
G01X706289Y519755D02*
Y511755D01*
G01X700789Y519755D02*
X706289D01*
G01X688700Y528500D02*
X694200D01*
G01X688700Y520500D02*
Y528500D01*
G01X694200Y520500D02*
X688700D01*
G01X706300D02*
X700800D01*
G01X706300Y528500D02*
Y520500D01*
G01X700800Y528500D02*
X706300D01*
G01X715000Y537300D02*
X697400D01*
G01Y529300D02*
X715000D01*
G01X697400Y537300D02*
Y529300D01*
G01X648223Y526113D02*
Y534113D01*
G01X708098Y765066D02*
X704698D01*
G01X708098D02*
X712598D01*
G01X706398Y766766D02*
X708098Y765066D01*
G01X704698D02*
X706398Y766766D01*
G01X700198Y765066D02*
Y796866D01*
G01X704698Y765066D02*
X700198D01*
G01X687190Y766106D02*
X691190D01*
Y773506D01*
G01X707412Y822969D02*
X704012D01*
G01X707412D02*
X711912D01*
G01X705712Y824669D02*
X707412Y822969D01*
G01X704012D02*
X705712Y824669D01*
G01X699512Y822969D02*
Y854769D01*
G01X704012Y822969D02*
X699512D01*
G01X712598Y796866D02*
X700198D01*
G01D02*
X712598D01*
G01X711912Y854769D02*
X699512D01*
G01D02*
X711912D01*
G01X713509Y452523D02*
X717509D01*
Y459923D01*
G01X738209Y480623D02*
X734209D01*
Y473223D01*
G01X742309Y484823D02*
X738309D01*
Y477423D01*
G01X725809Y468123D02*
X721809D01*
Y460723D01*
G01X721709Y464023D02*
X717709D01*
Y456623D01*
G01X738209Y476623D02*
Y480623D01*
X730809D01*
G01X742309Y480823D02*
Y484823D01*
X734909D01*
G01X725809Y464123D02*
Y468123D01*
X718409D01*
G01X721709Y460023D02*
Y464023D01*
X714309D01*
G01X726709Y476523D02*
Y472523D01*
X734109D01*
G01X730109Y469123D02*
X734109D01*
Y476523D01*
G01X725909Y464823D02*
X729909D01*
Y472223D01*
G01X722509D02*
Y468223D01*
X729909D01*
G01X752700Y544500D02*
Y548500D01*
X745300D01*
G01X754900Y553900D02*
Y557900D01*
X747500D01*
G01X754900Y549800D02*
Y553800D01*
X747500D01*
G01X715000Y529300D02*
Y537300D01*
G01X755000Y575500D02*
Y579500D01*
X747600D01*
G01X754930Y567233D02*
Y571233D01*
X747530D01*
G01X754937Y558714D02*
Y562714D01*
X747537D01*
G01X755029Y571387D02*
Y575387D01*
X747629D01*
G01X712598Y796866D02*
Y765066D01*
G01X711912Y854769D02*
Y822969D01*
G01X723791Y859331D02*
Y855331D01*
X731191D01*
G01X731200Y851200D02*
Y855200D01*
X723800D01*
G54D11*
G01X-771361Y-182763D02*
Y-262763D01*
G01Y-218263D02*
X373639D01*
G01X-771361Y-262763D02*
X373639D01*
G01X-775361Y-166763D02*
G02I-12000J0D01*
G01X-780511D02*
G02I-6850J0D01*
G01X-787361Y-182763D02*
Y-150763D01*
G01X-771361Y-166763D02*
X-803361D01*
G01X-771361Y-182763D02*
X373639D01*
G01X-413861D02*
Y-262763D01*
G01X-276361Y-182763D02*
Y-262763D01*
G01X-161361Y-182763D02*
Y-262763D01*
G01X14000Y216000D02*
Y341000D01*
X-96500D01*
Y214000D01*
X14000D01*
Y216000D01*
G01X6139Y-182763D02*
Y-262763D01*
G01X70209Y81538D02*
X78209D01*
G01X86963Y293083D02*
X75463D01*
G01X29453Y484407D02*
Y489407D01*
G01X29450Y476524D02*
Y481524D01*
G01X101245Y139701D02*
Y129801D01*
G01X142300Y83500D02*
X125700D01*
G01X95749Y200421D02*
X87749D01*
G01X96875Y147869D02*
X101875D01*
G01X120897D02*
X125897D01*
G01X113101D02*
X118101D01*
G01X105172D02*
X110172D01*
G01X176139Y-182763D02*
Y-262763D01*
G01X217409Y192550D02*
Y184850D01*
G01X180534Y166605D02*
X185534D01*
G01X199709Y161997D02*
X194709D01*
G01X177450Y137059D02*
X172450D01*
G01X186200Y137100D02*
X181200D01*
G01X208100Y162000D02*
X203100D01*
G01X192377Y388899D02*
X197377D01*
G01X184665Y389035D02*
X189665D01*
G01X192811Y411790D02*
X197811D01*
G01X203459Y425949D02*
X198459D01*
G01X199714Y460381D02*
X194714D01*
G01X217356Y447301D02*
X212706D01*
G01X217409Y759480D02*
Y751780D01*
G01X240500Y56600D02*
X235500D01*
G01X265600D02*
X260600D01*
G01X257400D02*
X252400D01*
G01X248900D02*
X243900D01*
G01X249637Y86079D02*
Y81079D01*
G01X240000Y444500D02*
Y451300D01*
G01X275268Y437128D02*
X262268D01*
G01X273663Y479653D02*
X290263D01*
G01X241400Y463450D02*
Y458800D01*
G01X232456Y480567D02*
Y475917D01*
G01X233373Y471273D02*
Y466623D01*
G01X258924Y522913D02*
X263924D01*
G01X251008Y522983D02*
X256008D01*
G01X240618Y500316D02*
X235618D01*
G01X248632Y500310D02*
X243632D01*
G01X332474Y34279D02*
X349074D01*
G01X301974D02*
X318574D01*
G01X334992Y479504D02*
X351592D01*
G01X304467Y479279D02*
X321067D01*
G01X352091Y426498D02*
X335491D01*
G01X331521Y476462D02*
X314921D01*
G01X298487Y453735D02*
Y458735D01*
G01X373639Y-182763D02*
Y-262763D01*
G01X401639Y-166763D02*
G02I-12000J0D01*
G01X396489D02*
G02I-6850J0D01*
G01X389639Y-182763D02*
Y-150763D01*
G01X405639Y-166763D02*
X373639D01*
G01X362974Y34279D02*
X379574D01*
G01X539731Y185141D02*
X590472D01*
Y252369D01*
X379052D01*
Y185141D01*
X539731D01*
G01X464170Y511332D02*
X456170D01*
G01X501266Y545959D02*
X493266D01*
G01X650000Y518400D02*
Y523400D01*
G01X650019Y510668D02*
Y515668D01*
G01X711912Y823669D02*
X719712D01*
G01X712598Y765766D02*
X720398D01*
G54D21*
G01X152963Y293083D02*
X75463D01*
G01X27694Y491063D02*
Y495063D01*
G01X65340Y666712D02*
Y667812D01*
G01Y664012D02*
Y665112D01*
G01X59000Y767700D02*
X57900D01*
G01X61700D02*
X60600D01*
G01X92330Y147935D02*
X91230D01*
G01X95030D02*
X93930D01*
G01X80488Y182954D02*
Y186954D01*
G01X86963Y244083D02*
Y293083D01*
G01X152963Y244183D02*
X87063D01*
G01X105182Y215414D02*
X106282D01*
G01X102482D02*
X103582D01*
G01X101741Y208500D02*
Y209600D01*
G01Y205800D02*
Y206900D01*
G01X100325Y215410D02*
X101425D01*
G01X97625D02*
X98725D01*
G01X119963Y285583D02*
X127463Y293083D01*
G01X119963Y285583D02*
X112463Y293083D01*
G01X214700Y132500D02*
X210700D01*
G01X170084Y174855D02*
X166084D01*
G01X160113Y169759D02*
Y173759D01*
G01X210000Y174700D02*
X214000D01*
G01X152431Y174850D02*
Y178850D01*
G01X152963Y293083D02*
Y244183D01*
G01X213292Y405833D02*
X214392D01*
G01X210592D02*
X211692D01*
G01X199547Y409874D02*
X203547D01*
G01X205141Y389559D02*
X209141D01*
G01X218363Y404578D02*
X216363D01*
G01X184814Y461681D02*
X183714D01*
G01X187514D02*
X186414D01*
G01X210982Y426989D02*
Y425889D01*
G01Y429689D02*
Y428589D01*
G01X186734Y473029D02*
X187834D01*
G01X184034D02*
X185134D01*
G01X205439Y462152D02*
X201439D01*
G01X196624Y424263D02*
X192624D01*
G01X189714Y461481D02*
X191714D01*
G01X214143Y417666D02*
Y419666D01*
G01X191765Y473128D02*
X189765D01*
G01X247867Y70096D02*
Y71196D01*
G01Y67396D02*
Y68496D01*
G01X224577Y525319D02*
X220577D01*
G01X245262Y522209D02*
X249262D01*
G01X266353Y487734D02*
X262353D01*
G01X274970Y795574D02*
Y796674D01*
G01Y792874D02*
Y793974D01*
G01X363719Y396355D02*
X359719D01*
G01X301974Y474988D02*
Y473888D01*
G01Y477688D02*
Y476588D01*
G01X343430Y465951D02*
X339430D01*
G01X297500Y460500D02*
Y464500D01*
G01X302013Y470007D02*
Y472007D01*
G01X373408Y396355D02*
X369408D01*
G01X368586D02*
X364586D01*
G01X515266Y545959D02*
X497766D01*
G01X529700Y398200D02*
Y399300D01*
G01Y395500D02*
Y396600D01*
G01X501266Y533459D02*
Y545959D01*
G01X515266Y533459D02*
X501266D01*
G01X515266Y545959D02*
Y533459D01*
G01X508266Y543459D02*
X510766Y545959D01*
G01X508266Y543459D02*
X505766Y545959D01*
G54D12*
G01X-955512Y0D02*
X-986221D01*
G01X-955512D02*
X-986221D01*
G01X-996063Y70079D02*
Y39370D01*
G01Y708662D02*
Y739370D01*
G01X-986221Y925197D02*
X-955512D01*
G01X-986221D02*
X-955512D01*
G01X-769685Y0D02*
X-738977D01*
G01X-769685D02*
X-738977D01*
G01X-750000Y925197D02*
X-719292D01*
G01X-492126Y0D02*
X-522835D01*
G01X-492126D02*
X-522835D01*
G01X-482599Y925097D02*
X-513307D01*
G01X-334646Y0D02*
X-365355D01*
G01X-334646D02*
X-365355D01*
G01X-334646D02*
X-365355D01*
G01X-285248Y925097D02*
X-315957D01*
G01X-260630Y137796D02*
X-244882D01*
G01X-143740Y262205D02*
Y292914D01*
G01X-177221Y467569D02*
Y436860D01*
G01X-92481Y662992D02*
Y632284D01*
G01X-59000Y488137D02*
Y457429D01*
G01X61819Y0D02*
X31111D01*
G01X26880Y66929D02*
G02I-3900J0D01*
G01Y59055D02*
G02I-3900J0D01*
G01X34754Y66929D02*
G02I-3900J0D01*
G01Y59055D02*
G02I-3900J0D01*
G01X26880Y106299D02*
G02I-3900J0D01*
G01Y98425D02*
G02I-3900J0D01*
G01Y90551D02*
G02I-3900J0D01*
G01Y82677D02*
G02I-3900J0D01*
G01Y74803D02*
G02I-3900J0D01*
G01X34754Y106299D02*
G02I-3900J0D01*
G01Y98425D02*
G02I-3900J0D01*
G01Y90551D02*
G02I-3900J0D01*
G01Y82677D02*
G02I-3900J0D01*
G01Y74803D02*
G02I-3900J0D01*
G01X41142Y131769D02*
G02I0J3900D01*
G01Y141769D02*
G02I0J3900D01*
G01Y151769D02*
G02I0J3900D01*
G01X53547Y298336D02*
G02I0J4150D01*
G01Y318336D02*
G02I0J4150D01*
G01X26181Y523659D02*
G02I0J3900D01*
G01Y513659D02*
G02I0J3900D01*
G01Y533659D02*
G02I0J3900D01*
G01X41142Y641769D02*
G02I0J3900D01*
G01Y631769D02*
G02I0J3900D01*
G01Y651769D02*
G02I0J3900D01*
G01Y759880D02*
G02I0J3900D01*
G01Y749880D02*
G02I0J3900D01*
G01X8661Y787402D02*
X24409D01*
G01X41142Y769880D02*
G02I0J3900D01*
G01X118710Y796831D02*
G02I-9300J0D01*
G01Y876397D02*
G02I-9300J0D01*
G01X119291Y925197D02*
X88582D01*
G01X182681Y556682D02*
G02I0J4150D01*
G01Y576682D02*
G02I0J4150D01*
G01X177765Y796831D02*
G02I-9300J0D01*
G01Y876397D02*
G02I-9300J0D01*
G01X267031Y-100D02*
X297740D01*
G01X276982Y813885D02*
G02I0J4450D01*
G01X286982D02*
G02I0J4450D01*
G01X276982Y823885D02*
G02I0J4450D01*
G01X286982D02*
G02I0J4450D01*
G01X296982Y813885D02*
G02I0J4450D01*
G01Y823885D02*
G02I0J4450D01*
G01X306982Y813885D02*
G02I0J4450D01*
G01X316982D02*
G02I0J4450D01*
G01X326982D02*
G02I0J4450D01*
G01X306982Y823885D02*
G02I0J4450D01*
G01X316982D02*
G02I0J4450D01*
G01X326982D02*
G02I0J4450D01*
G01X336982Y813885D02*
G02I0J4450D01*
G01X346982D02*
G02I0J4450D01*
G01X356982D02*
G02I0J4450D01*
G01X336982Y823885D02*
G02I0J4450D01*
G01X346982D02*
G02I0J4450D01*
G01X356982D02*
G02I0J4450D01*
G01X335827Y925197D02*
X305118D01*
G01X366982Y813885D02*
G02I0J4450D01*
G01Y823885D02*
G02I0J4450D01*
G01X483071Y0D02*
X513779D01*
G01X522441Y925197D02*
X553149D01*
G01X719291Y0D02*
X750000D01*
G01X759842Y216536D02*
Y185827D01*
G01Y885827D02*
Y855118D01*
G01Y885827D02*
Y855118D01*
G01X719291Y925197D02*
X750000D01*
G54D13*
G01X71700Y197400D02*
X74550D01*
Y194700D01*
G01X77000Y156600D02*
Y162100D01*
X70700D01*
G01X70293Y212035D02*
Y216435D01*
X73793D01*
G01X76580Y635298D02*
Y630898D01*
X73080D01*
G01X76464Y654003D02*
Y649603D01*
X72964D01*
G01X77062Y750051D02*
Y745651D01*
X73562D01*
G01X77006Y768568D02*
Y764168D01*
X73506D01*
G01X128660Y209449D02*
X123660D01*
Y204449D01*
G01X89974Y617483D02*
Y614783D01*
G01Y735593D02*
Y732893D01*
G01X215708Y169368D02*
X210708D01*
Y164368D01*
G01X216356Y468468D02*
X221356D01*
Y473468D01*
G01X217956Y447701D02*
Y445851D01*
G01X212056Y447701D02*
Y445851D01*
G01X229922Y398936D02*
Y402936D01*
X235722D01*
G01X241000Y464050D02*
X242850D01*
G01X241000Y458150D02*
X242850D01*
G01X232056Y481167D02*
X233906D01*
G01X232056Y475267D02*
X233906D01*
G01X232973Y471873D02*
X234823D01*
G01X232973Y465973D02*
X234823D01*
G54D14*
G01X534184Y400575D02*
X526434D01*
G54D15*
G01X29857Y55057D02*
X34857D01*
Y60057D01*
G01X60547Y329586D02*
Y322586D01*
G01X53547Y329586D02*
X60547D01*
G01X189681Y587932D02*
Y580932D01*
G01X182681Y587932D02*
X189681D01*
G01X255482Y809335D02*
Y804335D01*
X260482D01*
G54D16*
G01X511200Y398600D02*
X514600D01*
G54D17*
G01X70305Y213487D02*
Y213384D01*
G01X70230Y213562D02*
Y213309D01*
G01X70155Y213637D02*
Y213234D01*
G01X70080Y213712D02*
Y213159D01*
G01X70005Y213787D02*
Y213084D01*
G01X69930Y213862D02*
Y213009D01*
G01X69855Y213937D02*
Y212934D01*
G01X69780Y214012D02*
Y212859D01*
G01X69705Y214087D02*
Y212784D01*
G01X69630Y214162D02*
Y212709D01*
G01X69555Y214237D02*
Y212634D01*
G01X69480Y214312D02*
Y212559D01*
G01X69405Y214387D02*
Y212484D01*
G01X69330Y214462D02*
Y212409D01*
G01X69246Y212366D02*
X69263Y214519D01*
G01X69220Y214572D02*
X70358Y213435D01*
G01D02*
X69218Y212296D01*
G01Y212355D02*
Y214515D01*
G01Y214571D02*
Y212296D01*
G01X69293Y214499D02*
Y212371D01*
G01X69368Y214424D02*
Y212446D01*
G01X69443Y214349D02*
Y212521D01*
G01X69518Y214274D02*
Y212596D01*
G01X69593Y214199D02*
Y212671D01*
G01X69668Y214124D02*
Y212746D01*
G01X69743Y214049D02*
Y212821D01*
G01X69818Y213974D02*
Y212896D01*
G01X69893Y213899D02*
Y212971D01*
G01X69968Y213824D02*
Y213046D01*
G01X70043Y213749D02*
Y213121D01*
G01X70118Y213674D02*
Y213196D01*
G01X70193Y213599D02*
Y213271D01*
G01X70268Y213524D02*
Y213346D01*
G01X70343Y213449D02*
Y213421D01*
G01X76568Y633846D02*
Y633949D01*
G01X76643Y633771D02*
Y634024D01*
G01X76718Y633696D02*
Y634099D01*
G01X76793Y633621D02*
Y634174D01*
G01X76868Y633546D02*
Y634249D01*
G01X76943Y633471D02*
Y634324D01*
G01X77018Y633396D02*
Y634399D01*
G01X77093Y633321D02*
Y634474D01*
G01X77168Y633246D02*
Y634549D01*
G01X77243Y633171D02*
Y634624D01*
G01X77318Y633096D02*
Y634699D01*
G01X77393Y633021D02*
Y634774D01*
G01X77468Y632946D02*
Y634849D01*
G01X77543Y632871D02*
Y634924D01*
G01X77627Y634967D02*
X77610Y632814D01*
G01X77653Y632761D02*
X76515Y633898D01*
G01D02*
X77655Y635037D01*
G01Y634978D02*
Y632818D01*
G01Y632762D02*
Y635037D01*
G01X77580Y632834D02*
Y634962D01*
G01X77505Y632909D02*
Y634887D01*
G01X77430Y632984D02*
Y634812D01*
G01X77355Y633059D02*
Y634737D01*
G01X77280Y633134D02*
Y634662D01*
G01X77205Y633209D02*
Y634587D01*
G01X77130Y633284D02*
Y634512D01*
G01X77055Y633359D02*
Y634437D01*
G01X76980Y633434D02*
Y634362D01*
G01X76905Y633509D02*
Y634287D01*
G01X76830Y633584D02*
Y634212D01*
G01X76755Y633659D02*
Y634137D01*
G01X76680Y633734D02*
Y634062D01*
G01X76605Y633809D02*
Y633987D01*
G01X76530Y633884D02*
Y633912D01*
G01X76452Y652551D02*
Y652654D01*
G01X76527Y652476D02*
Y652729D01*
G01X76602Y652401D02*
Y652804D01*
G01X76677Y652326D02*
Y652879D01*
G01X76752Y652251D02*
Y652954D01*
G01X76827Y652176D02*
Y653029D01*
G01X76902Y652101D02*
Y653104D01*
G01X76977Y652026D02*
Y653179D01*
G01X77052Y651951D02*
Y653254D01*
G01X77127Y651876D02*
Y653329D01*
G01X77202Y651801D02*
Y653404D01*
G01X77277Y651726D02*
Y653479D01*
G01X77352Y651651D02*
Y653554D01*
G01X77427Y651576D02*
Y653629D01*
G01X77511Y653672D02*
X77494Y651519D01*
G01X77537Y651466D02*
X76399Y652603D01*
G01D02*
X77539Y653742D01*
G01Y653683D02*
Y651523D01*
G01Y651467D02*
Y653742D01*
G01X77464Y651539D02*
Y653667D01*
G01X77389Y651614D02*
Y653592D01*
G01X77314Y651689D02*
Y653517D01*
G01X77239Y651764D02*
Y653442D01*
G01X77164Y651839D02*
Y653367D01*
G01X77089Y651914D02*
Y653292D01*
G01X77014Y651989D02*
Y653217D01*
G01X76939Y652064D02*
Y653142D01*
G01X76864Y652139D02*
Y653067D01*
G01X76789Y652214D02*
Y652992D01*
G01X76714Y652289D02*
Y652917D01*
G01X76639Y652364D02*
Y652842D01*
G01X76564Y652439D02*
Y652767D01*
G01X76489Y652514D02*
Y652692D01*
G01X76414Y652589D02*
Y652617D01*
G01X77050Y748599D02*
Y748702D01*
G01X77125Y748524D02*
Y748777D01*
G01X77200Y748449D02*
Y748852D01*
G01X77275Y748374D02*
Y748927D01*
G01X77350Y748299D02*
Y749002D01*
G01X77425Y748224D02*
Y749077D01*
G01X77500Y748149D02*
Y749152D01*
G01X77575Y748074D02*
Y749227D01*
G01X77650Y747999D02*
Y749302D01*
G01X77725Y747924D02*
Y749377D01*
G01X77800Y747849D02*
Y749452D01*
G01X77875Y747774D02*
Y749527D01*
G01X77950Y747699D02*
Y749602D01*
G01X78025Y747624D02*
Y749677D01*
G01X78135Y747514D02*
X76997Y748651D01*
G01D02*
X78137Y749790D01*
G01X78062Y747587D02*
Y749715D01*
G01X77987Y747662D02*
Y749640D01*
G01X77912Y747737D02*
Y749565D01*
G01X77837Y747812D02*
Y749490D01*
G01X77762Y747887D02*
Y749415D01*
G01X77687Y747962D02*
Y749340D01*
G01X77612Y748037D02*
Y749265D01*
G01X77537Y748112D02*
Y749190D01*
G01X77462Y748187D02*
Y749115D01*
G01X77387Y748262D02*
Y749040D01*
G01X77312Y748337D02*
Y748965D01*
G01X77237Y748412D02*
Y748890D01*
G01X77162Y748487D02*
Y748815D01*
G01X77087Y748562D02*
Y748740D01*
G01X77012Y748637D02*
Y748665D01*
G01X76994Y767116D02*
Y767219D01*
G01X77069Y767041D02*
Y767294D01*
G01X77144Y766966D02*
Y767369D01*
G01X77219Y766891D02*
Y767444D01*
G01X77294Y766816D02*
Y767519D01*
G01X77369Y766741D02*
Y767594D01*
G01X77444Y766666D02*
Y767669D01*
G01X77519Y766591D02*
Y767744D01*
G01X77594Y766516D02*
Y767819D01*
G01X77669Y766441D02*
Y767894D01*
G01X77744Y766366D02*
Y767969D01*
G01X77819Y766291D02*
Y768044D01*
G01X77894Y766216D02*
Y768119D01*
G01X77969Y766141D02*
Y768194D01*
G01X78053Y768237D02*
X78036Y766084D01*
G01X78079Y766031D02*
X76941Y767168D01*
G01D02*
X78081Y768307D01*
G01Y768248D02*
Y766088D01*
G01Y766032D02*
Y768307D01*
G01X78006Y766104D02*
Y768232D01*
G01X77931Y766179D02*
Y768157D01*
G01X77856Y766254D02*
Y768082D01*
G01X77781Y766329D02*
Y768007D01*
G01X77706Y766404D02*
Y767932D01*
G01X77631Y766479D02*
Y767857D01*
G01X77556Y766554D02*
Y767782D01*
G01X77481Y766629D02*
Y767707D01*
G01X77406Y766704D02*
Y767632D01*
G01X77331Y766779D02*
Y767557D01*
G01X77256Y766854D02*
Y767482D01*
G01X77181Y766929D02*
Y767407D01*
G01X77106Y767004D02*
Y767332D01*
G01X77031Y767079D02*
Y767257D01*
G01X76956Y767154D02*
Y767182D01*
G01X78109Y749720D02*
X78092Y747567D01*
G01X78137Y749731D02*
Y747571D01*
G01Y747515D02*
Y749790D01*
G54D18*
G01X681519Y326064D02*
X680859D01*
G01X680959Y326154D02*
X681619D01*
G01X681709Y326264D02*
X681059D01*
G01X681159Y326354D02*
X681809D01*
G01X681909Y326464D02*
X681249D01*
G01X681349Y326564D02*
X681999D01*
G01X682099Y326654D02*
X681449D01*
G01X681539Y326764D02*
X682199D01*
G01X682289Y326854D02*
X681639D01*
G01X681729Y326964D02*
X682389D01*
G01X682489Y327064D02*
X681829D01*
G01X681929Y327154D02*
X682579D01*
G01X682679Y327264D02*
X682034D01*
G01X682029D02*
X682079D01*
G01X682119Y327354D02*
X682159D01*
G01X682119D02*
X682769D01*
G01X682869Y327464D02*
X682219D01*
G01X682319Y327564D02*
X682969D01*
G01X683069Y327654D02*
X682409D01*
G01X682509Y327764D02*
X683159D01*
G01X683259Y327854D02*
X682599D01*
G01X682699Y327964D02*
X683359D01*
G01X683449Y328064D02*
X682799D01*
G01X682899Y328154D02*
X683549D01*
G01X683639Y328264D02*
X682989D01*
G01X683089Y328354D02*
X683739D01*
G01X683839Y328464D02*
X683179D01*
G01X683279Y328564D02*
X683939D01*
G01X684029Y328654D02*
X683379D01*
G01X683469Y328764D02*
X684129D01*
G01X684319Y328964D02*
X683669D01*
G01X683859Y329154D02*
X684509D01*
G01X679219Y343574D02*
X679249Y343594D01*
G01X679219Y343034D02*
Y343574D01*
G01X679229Y343014D02*
X679219Y343034D01*
G01X679279Y342904D02*
X679229Y343014D01*
G01X679289Y342894D02*
X679279Y342904D01*
G01X684469Y337304D02*
X679289Y342894D01*
G01X679219Y343564D02*
X679279D01*
G01X679219Y343464D02*
X679369D01*
G01X679459Y343354D02*
X679219D01*
G01Y343264D02*
X679559D01*
G01X679649Y343154D02*
X679219D01*
G01Y343064D02*
X679739D01*
G01X679839Y342964D02*
X679249D01*
G01X679319Y342854D02*
X679929D01*
G01X680019Y342764D02*
X679409D01*
G01X679499Y342654D02*
X680109D01*
G01X680209Y342564D02*
X679599D01*
G01X679689Y342464D02*
X680299D01*
G01X680389Y342354D02*
X679779D01*
G01X679869Y342264D02*
X680489D01*
G01X680579Y342154D02*
X679969D01*
G01X680059Y342064D02*
X680669D01*
G01X680769Y341964D02*
X680149D01*
G01X680249Y341854D02*
X680859D01*
G01X680949Y341764D02*
X680339D01*
G01X680429Y341654D02*
X681049D01*
G01X681139Y341564D02*
X680529D01*
G01X680619Y341464D02*
X681229D01*
G01X681329Y341354D02*
X680709D01*
G01X680799Y341264D02*
X681419D01*
G01X681509Y341154D02*
X680899D01*
G01X680989Y341064D02*
X681599D01*
G01X681699Y340964D02*
X681079D01*
G01X681179Y340854D02*
X681789D01*
G01X681879Y340764D02*
X681269D01*
G01X681359Y340654D02*
X681969D01*
G01X682069Y340564D02*
X681459D01*
G01X681549Y340464D02*
X682159D01*
G01X682249Y340354D02*
X681639D01*
G01X681729Y340264D02*
X682349D01*
G01X682439Y340154D02*
X681829D01*
G01X681919Y340064D02*
X682529D01*
G01X682629Y339964D02*
X682009D01*
G01X682099Y339854D02*
X682719D01*
G01X682809Y339764D02*
X682199D01*
G01X682289Y339654D02*
X682909D01*
G01X682999Y339564D02*
X682379D01*
G01X682469Y339464D02*
X683089D01*
G01X683189Y339354D02*
X682569D01*
G01X682659Y339264D02*
X683279D01*
G01X683369Y339154D02*
X682749D01*
G01X682839Y339064D02*
X683469D01*
G01X683559Y338964D02*
X682939D01*
G01X683029Y338854D02*
X683649D01*
G01X683739Y338764D02*
X683119D01*
G01X683219Y338654D02*
X683839D01*
G01X683929Y338564D02*
X683309D01*
G01X683399Y338464D02*
X684019D01*
G01X684119Y338354D02*
X683499D01*
G01X683679Y338154D02*
X684919D01*
G01X684929Y337964D02*
X683869D01*
G01X683619Y340254D02*
X684129D01*
G01X683579Y340214D02*
X683619Y340254D01*
G01X683579Y339754D02*
Y340214D01*
G01X683619Y339714D02*
X683579Y339754D01*
G01Y340154D02*
X693829D01*
G01X693759Y339964D02*
X683579D01*
G01Y339764D02*
X693599D01*
G01X686229Y341064D02*
X684799D01*
G01X684219Y340324D02*
X684129Y340254D01*
G01X684239Y340374D02*
X684219Y340324D01*
G01X684239Y340384D02*
Y340374D01*
G01X684359Y340634D02*
X684239Y340384D01*
G01X684379Y340644D02*
X684359Y340634D01*
G01X684809Y341064D02*
X684379Y340644D01*
G01X684139Y340264D02*
X684869D01*
G01X684979Y340594D02*
X685089Y340664D01*
G01X684809Y340424D02*
X684979Y340594D01*
G01X684789Y340314D02*
X684809Y340424D01*
G01X684879Y340254D02*
X684789Y340314D01*
G01X684949Y340564D02*
X684329D01*
G01X684279Y340464D02*
X684849D01*
G01X684799Y340354D02*
X684229D01*
G01X684489Y340764D02*
X686169D01*
G01Y340964D02*
X684699D01*
G01X685049Y337364D02*
X688279Y333884D01*
G01X685039Y337364D02*
X685049D01*
G01X684999Y337414D02*
X685039Y337364D01*
G01X684969Y337474D02*
X684999Y337414D01*
G01X684789Y339604D02*
X684969Y337474D01*
G01X684889Y339714D02*
X684789Y339604D01*
G01X685309Y333564D02*
X684839D01*
G01X684829Y333764D02*
X685289D01*
G01X685269Y333964D02*
X684809D01*
G01X684789Y334154D02*
X685259D01*
G01X685239Y334354D02*
X684769D01*
G01X684749Y334564D02*
X685219D01*
G01X685209Y334764D02*
X684739D01*
G01X684719Y334964D02*
X685189D01*
G01X685169Y335154D02*
X684699D01*
G01X684689Y335354D02*
X685159D01*
G01X685139Y335564D02*
X684669D01*
G01X684649Y335764D02*
X685119D01*
G01X685099Y335964D02*
X684639D01*
G01X684619Y336154D02*
X685089D01*
G01X685069Y336354D02*
X684599D01*
G01X684589Y336464D02*
X685099D01*
G01X685599Y336764D02*
X684569D01*
G01X684549Y336964D02*
X685419D01*
G01X684489Y337274D02*
X684469Y337304D01*
G01X684529Y337174D02*
X684489Y337274D01*
G01X684529Y337164D02*
Y337174D01*
G01Y337154D02*
Y337164D01*
G01X685229Y337154D02*
X684529D01*
G01X684429Y337354D02*
X685049D01*
G01X684979Y337464D02*
X684329D01*
G01X684239Y337564D02*
X684969D01*
G01X684959Y337654D02*
X684149D01*
G01X684049Y337764D02*
X684949D01*
G01X684939Y337854D02*
X683959D01*
G01X683769Y338064D02*
X684919D01*
G01X684909Y338264D02*
X684429D01*
G01X684219Y339714D02*
X683619D01*
G01X684319Y339624D02*
X684219Y339714D01*
G01X684439Y338274D02*
X684319Y339624D01*
G01X684279Y339654D02*
X684839D01*
G01X684789Y339564D02*
X684329D01*
G01X684339Y339464D02*
X684809D01*
G01Y339354D02*
X684339D01*
G01X684349Y339264D02*
X684819D01*
G01X684829Y339154D02*
X684359D01*
G01X684369Y339064D02*
X684839D01*
G01X684849Y338964D02*
X684379D01*
G01X684389Y338854D02*
X684859D01*
G01Y338764D02*
X684399D01*
G01Y338654D02*
X684869D01*
G01X684879Y338564D02*
X684419D01*
G01Y338464D02*
X684889D01*
G01X684899Y338354D02*
X684429D01*
G01X684269Y338204D02*
X679249Y343594D01*
G01X684379Y338174D02*
X684269Y338204D01*
G01X684439Y338274D02*
X684379Y338174D01*
G01X683589Y338264D02*
X684209D01*
G01X684529Y337154D02*
X684969Y332004D01*
G01X684979Y331964D02*
X685449D01*
G01X685459Y331764D02*
X684989D01*
G01X685009Y331564D02*
X685479D01*
G01X685499Y331354D02*
X685029D01*
G01X685049Y331154D02*
X685519D01*
G01X685559Y331064D02*
X685059D01*
G01X685069Y330414D02*
X684969Y330304D01*
G01X685099Y330484D02*
X685069Y330414D01*
G01X684919Y330264D02*
X685609D01*
G01Y330064D02*
X684729D01*
G01X684539Y329854D02*
X685629D01*
G01X684989Y329654D02*
X684339D01*
G01X684249Y329564D02*
X684899D01*
G01X684799Y329464D02*
X684149D01*
G01X684049Y329354D02*
X684709D01*
G01X684609Y329264D02*
X683959D01*
G01X683769Y329064D02*
X684419D01*
G01X684219Y328854D02*
X683569D01*
G01X684949Y332264D02*
X685419D01*
G01X685399Y332464D02*
X684939D01*
G01X684919Y332654D02*
X685389D01*
G01X685369Y332854D02*
X684899D01*
G01X684879Y333064D02*
X685349D01*
G01X685339Y333264D02*
X684869D01*
G01X684859Y333354D02*
X685329D01*
G01X685319Y333464D02*
X684849D01*
G01X684829Y333654D02*
X685299D01*
G01X685289Y333854D02*
X684819D01*
G01X684799Y334064D02*
X685269D01*
G01X685249Y334264D02*
X684779D01*
G01X684769Y334464D02*
X685229D01*
G01X685209Y334654D02*
X684749D01*
G01X684729Y334854D02*
X685199D01*
G01X685179Y335064D02*
X684709D01*
G01X684699Y335264D02*
X685159D01*
G01X685149Y335464D02*
X684679D01*
G01X684659Y335654D02*
X685129D01*
G01X685109Y335854D02*
X684639D01*
G01X684629Y336064D02*
X685089D01*
G01X685079Y336264D02*
X684609D01*
G01X685239Y336484D02*
X687969Y333544D01*
G01X685119Y336504D02*
X685239Y336484D01*
G01X685069Y336404D02*
X685119Y336504D01*
G01X685339Y333154D02*
X684879D01*
G01X684889Y332964D02*
X685359D01*
G01X685379Y332764D02*
X684909D01*
G01X684929Y332564D02*
X685399D01*
G01X685409Y332354D02*
X684939D01*
G01X684959Y332154D02*
X685429D01*
G01X685439Y332064D02*
X684969D01*
G01X685099Y330544D02*
Y330484D01*
G01X684969Y332004D02*
X685099Y330544D01*
G01X685089Y330464D02*
X685769D01*
G01X685619Y330284D02*
X685599Y330214D01*
G01X685669Y330364D02*
X685619Y330284D01*
G01X685599Y330154D02*
X684829D01*
G01X684639Y329964D02*
X685619D01*
G01X685639Y329654D02*
X685139D01*
G01X685109Y329694D02*
X685009Y329674D01*
G01X685379Y327254D02*
X685489D01*
G01X685379Y327264D02*
Y327254D01*
G01X685179Y329614D02*
X685379Y327264D01*
G01X685109Y329694D02*
X685179Y329614D01*
G01X685479Y327354D02*
X685369D01*
G01X685374D02*
X690969D01*
G01X691034Y327264D02*
X685379D01*
G01X685619Y326214D02*
X686509D01*
G01X685579Y326254D02*
X685619Y326214D01*
G01X685579Y326934D02*
Y326254D01*
G01X685549Y327004D02*
X685579Y326934D01*
G01X685399Y327164D02*
X685549Y327004D01*
G01X685389Y327184D02*
X685399Y327164D01*
G01X685379Y327244D02*
X685389Y327184D01*
G01X686549Y326264D02*
X685579D01*
G01Y326464D02*
X686549D01*
G01Y326654D02*
X685579D01*
G01Y326854D02*
X686549D01*
G01X685829Y327564D02*
X685359D01*
G01X685339Y327654D02*
X685809D01*
G01X685799Y327854D02*
X685329D01*
G01X685309Y328064D02*
X685779D01*
G01X685759Y328264D02*
X685289D01*
G01X685279Y328464D02*
X685749D01*
G01X685729Y328654D02*
X685259D01*
G01X685239Y328854D02*
X685709D01*
G01X685699Y329064D02*
X685229D01*
G01X685209Y329264D02*
X685679D01*
G01X685659Y329464D02*
X685199D01*
G01X685089Y330654D02*
X685959D01*
G01X686149Y330854D02*
X685069D01*
G01X685039Y331264D02*
X685509D01*
G01X685519Y331114D02*
X685069Y336404D01*
G01X685259Y336464D02*
X685879D01*
G01X686069Y336264D02*
X685449D01*
G01X685629Y336064D02*
X686249D01*
G01X685509Y336854D02*
X684559D01*
G01X684539Y337064D02*
X685329D01*
G01X685139Y337264D02*
X684499D01*
G01X685199Y340674D02*
X685089Y340664D01*
G01X685249Y340584D02*
X685199Y340674D01*
G01X685249Y340354D02*
Y340584D01*
G01X685149Y340254D02*
X685249Y340354D01*
G01X684879Y340254D02*
X685149D01*
G01X685079Y340654D02*
X684389D01*
G01X685259Y341644D02*
X685289Y341664D01*
G01X685249Y341614D02*
X685259Y341644D01*
G01X685249Y341414D02*
Y341614D01*
G01X685239Y341374D02*
X685249Y341414D01*
G01X685219Y341324D02*
X685239Y341374D01*
G01X685169Y341264D02*
X685219Y341324D01*
G01X685079Y341224D02*
X685169Y341264D01*
G01X684809Y341064D02*
X685079Y341224D01*
G01X685289Y341654D02*
X686119D01*
G01X685249Y341464D02*
X688139D01*
G01X688129Y341264D02*
X685149D01*
G01X685199Y340654D02*
X686169D01*
G01Y340464D02*
X685249D01*
G01X685159Y340264D02*
X686269D01*
G01X685459Y331854D02*
X684989D01*
G01X684999Y331654D02*
X685469D01*
G01X685489Y331464D02*
X685019D01*
G01X685589Y331024D02*
X685689Y331054D01*
G01X685519Y331114D02*
X685589Y331024D01*
G01X685499Y327064D02*
X691279D01*
G01X685819Y327634D02*
X685599Y330214D01*
G01X685819Y327564D02*
Y327634D01*
G01X685919Y327474D02*
X685819Y327564D01*
G01X690019Y327474D02*
X685919D01*
G01X685669Y330354D02*
X685019D01*
G01X685099Y330564D02*
X685859D01*
G01X685679Y330364D02*
X685669D01*
G01X685679Y330374D02*
Y330364D01*
G01Y330374D02*
X688269Y333064D01*
G01X688079Y332854D02*
X687439D01*
G01X687239Y332654D02*
X687889D01*
G01X687699Y332464D02*
X687049D01*
G01X686859Y332264D02*
X687499D01*
G01X687409Y332154D02*
X686759D01*
G01X686809Y332214D02*
X685689Y331054D01*
G01X685699Y331064D02*
X686339D01*
G01X686249Y330964D02*
X685069D01*
G01X685079Y330764D02*
X686059D01*
G01X685799Y331154D02*
X686439D01*
G01X686539Y331264D02*
X685899D01*
G01X685989Y331354D02*
X686639D01*
G01X686729Y331464D02*
X686089D01*
G01X686179Y331564D02*
X686829D01*
G01X686919Y331654D02*
X686279D01*
G01X686379Y331764D02*
X687019D01*
G01X687119Y331854D02*
X686469D01*
G01X686569Y331964D02*
X687209D01*
G01X687309Y332064D02*
X686659D01*
G01X687489Y334064D02*
X688119D01*
G01X687929Y334264D02*
X687309D01*
G01X687119Y334464D02*
X687739D01*
G01X687559Y334654D02*
X686929D01*
G01X686839Y334764D02*
X687459D01*
G01X687369Y334854D02*
X686749D01*
G01X686659Y334964D02*
X687279D01*
G01X687179Y335064D02*
X686559D01*
G01X686469Y335154D02*
X687089D01*
G01X686999Y335264D02*
X686379D01*
G01X686279Y335354D02*
X686909D01*
G01X686809Y335464D02*
X686189D01*
G01X686099Y335564D02*
X686719D01*
G01X686629Y335654D02*
X685999D01*
G01X685909Y335764D02*
X686529D01*
G01X686439Y335854D02*
X685819D01*
G01X685729Y335964D02*
X686349D01*
G01X686159Y336154D02*
X685539D01*
G01X685349Y336354D02*
X685969D01*
G01X685789Y336564D02*
X684589D01*
G01X684579Y336654D02*
X685699D01*
G01X687549Y335934D02*
X687589Y335894D01*
G01X686169Y340354D02*
X685249D01*
G01X686269Y340254D02*
X686169Y340354D01*
G01X685249Y340564D02*
X686169D01*
G01X687499Y341264D02*
X687609Y341154D01*
G01X687229Y341234D02*
X687499Y341264D01*
G01X686949Y341204D02*
X687229Y341234D01*
G01X686829Y341194D02*
X686949Y341204D01*
G01X686729Y341174D02*
X686829Y341194D01*
G01X686479Y341134D02*
X686729Y341174D01*
G01X686469Y341134D02*
X686479D01*
G01X686379Y341114D02*
X686469Y341134D01*
G01X686369Y341114D02*
X686379D01*
G01X686249Y341094D02*
X686369Y341114D01*
G01X686169Y340994D02*
X686249Y341094D01*
G01X686169Y340354D02*
Y340994D01*
G01X686109Y341664D02*
X685289D01*
G01X686129Y341654D02*
X686109Y341664D01*
G01X686159Y341644D02*
X686129Y341654D01*
G01X686189Y341624D02*
X686159Y341644D01*
G01X686269Y341604D02*
X686189Y341624D01*
G01X686289Y341614D02*
X686269Y341604D01*
G01X686529Y341654D02*
X686289Y341614D01*
G01X687029Y341724D02*
X686529Y341654D01*
G01X687149Y341734D02*
X687029Y341724D01*
G01X687209Y341734D02*
X687149D01*
G01X687369Y341754D02*
X687209Y341734D01*
G01X687509Y341764D02*
X687369Y341754D01*
G01X684969Y341154D02*
X686619D01*
G01X686169Y340854D02*
X684599D01*
G01X686269Y340254D02*
X692109D01*
G01X690179Y341764D02*
X687489D01*
G01X687509D02*
X687609Y341864D01*
G01X685639Y329764D02*
X684439D01*
G01X685179Y329564D02*
X685649D01*
G01X685669Y329354D02*
X685199D01*
G01X685219Y329154D02*
X685689D01*
G01X685699Y328964D02*
X685229D01*
G01X685249Y328764D02*
X685719D01*
G01X685739Y328564D02*
X685269D01*
G01X685289Y328354D02*
X685749D01*
G01X685769Y328154D02*
X685309D01*
G01X685319Y327964D02*
X685789D01*
G01X685809Y327764D02*
X685339D01*
G01X685569Y326964D02*
X686619D01*
G01X686549Y326254D02*
X686509Y326214D01*
G01X686549Y326894D02*
Y326254D01*
G01X686649Y326994D02*
X686549Y326894D01*
G01Y326354D02*
X685579D01*
G01Y326564D02*
X686549D01*
G01Y326764D02*
X685579D01*
G01X690119Y327944D02*
Y327954D01*
G01X690109Y327874D02*
X690119Y327944D01*
G01X690109Y327614D02*
Y327874D01*
G01X690119Y327594D02*
X690109Y327614D01*
G01X690019Y327474D02*
X690119Y327594D01*
G01Y327964D02*
X690889D01*
G01X690849Y327764D02*
X690109D01*
G01X690089Y327564D02*
X690889D01*
G01X688729Y333394D02*
Y333534D01*
G01X691429Y330494D02*
X688729Y333394D01*
G01X688749Y333564D02*
X687959D01*
G01X687969Y333404D02*
X686809Y332214D01*
G01X687969Y333544D02*
Y333404D01*
G01X686959Y332354D02*
X687599D01*
G01X687789Y332564D02*
X687149D01*
G01X687339Y332764D02*
X687989D01*
G01X688179Y332964D02*
X687529D01*
G01X688419Y333064D02*
X690099Y331244D01*
G01X688269Y333064D02*
X688419D01*
G01X687629D02*
X688269D01*
G01X690089Y331264D02*
X690719D01*
G01X690529Y331464D02*
X689899D01*
G01X689719Y331654D02*
X690349D01*
G01X690159Y331854D02*
X689529D01*
G01X689439Y331964D02*
X690069D01*
G01X689969Y332064D02*
X689339D01*
G01X689249Y332154D02*
X689879D01*
G01X689789Y332264D02*
X689159D01*
G01X689069Y332354D02*
X689699D01*
G01X689599Y332464D02*
X688969D01*
G01X688879Y332564D02*
X689509D01*
G01X689419Y332654D02*
X688789D01*
G01X688699Y332764D02*
X689329D01*
G01X689229Y332854D02*
X688599D01*
G01X688509Y332964D02*
X689139D01*
G01X689049Y333064D02*
X688399D01*
G01X688769Y333354D02*
X687919D01*
G01X687969Y333464D02*
X688729D01*
G01X688849Y333654D02*
X687859D01*
G01X687769Y333764D02*
X688949D01*
G01X689049Y333854D02*
X687679D01*
G01X687589Y333964D02*
X688209D01*
G01X688419Y333884D02*
X689849Y335354D01*
G01X688279Y333884D02*
X688419D01*
G01X689749Y335264D02*
X690389D01*
G01X690199Y335064D02*
X689559D01*
G01X689469Y334964D02*
X690099D01*
G01X690009Y334854D02*
X689369D01*
G01X689269Y334764D02*
X689909D01*
G01X689819Y334654D02*
X689179D01*
G01X689079Y334564D02*
X689719D01*
G01X689619Y334464D02*
X688979D01*
G01X688889Y334354D02*
X689529D01*
G01X689429Y334264D02*
X688789D01*
G01X688699Y334154D02*
X689329D01*
G01X689239Y334064D02*
X688599D01*
G01X688499Y333964D02*
X689139D01*
G01X688859Y333264D02*
X687829D01*
G01X687729Y333154D02*
X688949D01*
G01X688019Y334154D02*
X687399D01*
G01X687209Y334354D02*
X687839D01*
G01X687649Y334564D02*
X687029D01*
G01X687639Y335894D02*
X690129D01*
G01X687589D02*
X687639D01*
G01X690139Y335654D02*
X690779D01*
G01X690589Y335464D02*
X689949D01*
G01X691069Y335964D02*
X687549D01*
G01X687589Y336924D02*
X687639D01*
G01X687549Y336884D02*
X687589Y336924D01*
G01X687549Y335934D02*
Y336884D01*
G01Y336764D02*
X690809D01*
G01X690839Y336564D02*
X687549D01*
G01Y336354D02*
X691459D01*
G01X691259Y336154D02*
X687549D01*
G01X687609Y340814D02*
Y341154D01*
G01X687649Y340764D02*
X687609Y340814D01*
G01X687599Y341154D02*
X690229D01*
G01X690099Y340764D02*
X687649D01*
G01X690149Y340814D02*
X690099Y340764D01*
G01X690149Y341094D02*
Y340814D01*
G01X687609Y340854D02*
X690149D01*
G01Y340964D02*
X687609D01*
G01Y341064D02*
X690149D01*
G01X689699Y341374D02*
Y341334D01*
G01X689599Y341474D02*
X689699Y341374D01*
G01X688159Y341474D02*
X689599D01*
G01X688059Y341374D02*
X688159Y341474D01*
G01X688059Y341334D02*
Y341374D01*
G01X688159Y341224D02*
X688059Y341334D01*
G01X689599Y341224D02*
X688159D01*
G01X689699Y341334D02*
X689599Y341224D01*
G01X689699Y341354D02*
X691669D01*
G01X691379Y341464D02*
X689609D01*
G01X687609Y341894D02*
Y341864D01*
G01X687649Y341934D02*
X687609Y341894D01*
G01X690099Y341934D02*
X687649D01*
G01X690149Y341894D02*
X690099Y341934D01*
G01X690149Y341794D02*
Y341894D01*
G01X687599Y341854D02*
X690149D01*
G01X688059Y341354D02*
X685229D01*
G01X685249Y341564D02*
X691009D01*
G01X690229Y341694D02*
X690149Y341794D01*
G01X690279Y341694D02*
X690229D01*
G01X690839Y341604D02*
X690279Y341694D01*
G01X691019Y341564D02*
X690839Y341604D01*
G01X690459Y341654D02*
X686589D01*
G01X690659Y341124D02*
X691069Y341034D01*
G01X690369Y341174D02*
X690659Y341124D01*
G01X690339Y341174D02*
X690369D01*
G01X690259Y341194D02*
X690339Y341174D01*
G01X690149Y341094D02*
X690259Y341194D01*
G01X690449Y341154D02*
X692039D01*
G01X690759Y336924D02*
X687639D01*
G01X687549Y336854D02*
X690809D01*
G01X690799Y336884D02*
X690759Y336924D01*
G01X690979Y336534D02*
X691179Y336734D01*
G01X690869Y336504D02*
X690979Y336534D01*
G01X690809Y336604D02*
X690869Y336504D01*
G01X690809Y336784D02*
Y336604D01*
G01Y336794D02*
Y336784D01*
G01X690799Y336884D02*
X690809Y336794D01*
G01X691009Y336564D02*
X691649D01*
G01X690809Y336654D02*
X687549D01*
G01X689659Y335154D02*
X690299D01*
G01X690219Y335834D02*
X690129Y335894D01*
G01X690199Y335724D02*
X690219Y335834D01*
G01X689849Y335354D02*
X690199Y335724D01*
G01X690489Y335354D02*
X689849D01*
G01X690179Y335854D02*
X690969D01*
G01X690879Y335764D02*
X690209D01*
G01X690049Y335564D02*
X690679D01*
G01X690249Y331764D02*
X689619D01*
G01X689809Y331564D02*
X690439D01*
G01X690619Y331354D02*
X689989D01*
G01X690179Y331154D02*
X690809D01*
G01X690899Y331064D02*
X690269D01*
G01X690359Y330964D02*
X690999D01*
G01X691089Y330854D02*
X690459D01*
G01X690549Y330764D02*
X691179D01*
G01X691369Y330564D02*
X690739D01*
G01X690919Y330354D02*
X692059D01*
G01X692049Y330264D02*
X691019D01*
G01X690159Y328134D02*
X690119Y327954D01*
G01X690159Y328144D02*
Y328134D01*
G01X690269Y328454D02*
X690159Y328144D01*
G01X690279Y328464D02*
X690269Y328454D01*
G01X690489Y328774D02*
X690279Y328464D01*
G01X690499Y328784D02*
X690489Y328774D01*
G01X690739Y329004D02*
X690499Y328784D01*
G01X690749Y329004D02*
X690739D01*
G01X690869Y329084D02*
X690749Y329004D01*
G01X690879Y329094D02*
X690869Y329084D01*
G01X690939Y329124D02*
X690879Y329094D01*
G01X691099Y329194D02*
X690939Y329124D01*
G01X690109Y327854D02*
X690869D01*
G01X690909Y327464D02*
X685359D01*
G01X690899Y327484D02*
X690909Y327464D01*
G01X690849Y327744D02*
X690899Y327484D01*
G01X690849Y327754D02*
Y327744D01*
G01Y327774D02*
Y327754D01*
G01X685399Y327154D02*
X691139D01*
G01X691059Y327224D02*
X690999Y327314D01*
G01X691069Y327214D02*
X691059Y327224D01*
G01X691079Y327204D02*
X691069Y327214D01*
G01X690919Y327454D02*
X690909Y327464D01*
G01X690999Y327324D02*
X690919Y327454D01*
G01X690869Y327654D02*
X690109D01*
G01X690139Y328064D02*
X690909D01*
G01X690899Y328034D02*
X690849Y327774D01*
G01X690909Y328054D02*
X690899Y328034D01*
G01X691129Y327784D02*
X691139Y327804D01*
G01X691079Y328314D02*
X691299Y328474D01*
G01X691069Y328304D02*
X691079Y328314D01*
G01X691059Y328284D02*
X691069Y328304D01*
G01X690919Y328074D02*
X691059Y328284D01*
G01X690909Y328054D02*
X690919Y328074D01*
G01X691139Y328354D02*
X690239D01*
G01X690199Y328264D02*
X691039D01*
G01X690969Y328154D02*
X690159D01*
G01X690339Y328564D02*
X691599D01*
G01X691009Y329154D02*
X692679D01*
G01X692769Y329064D02*
X690829D01*
G01X690589Y328854D02*
X692959D01*
G01X693139Y328654D02*
X690419D01*
G01X690999Y327264D02*
X691039D01*
G01X691079Y327204D02*
X691299Y327044D01*
G01X690869Y326464D02*
X692419D01*
G01X692579Y326564D02*
X690689D01*
G01X690249Y326994D02*
X686649D01*
G01X690329Y326964D02*
X690249Y326994D01*
G01X690339Y326954D02*
X690329Y326964D01*
G01X690339Y326944D02*
Y326954D01*
G01X690379Y326874D02*
X690339Y326944D01*
G01X690389Y326874D02*
X690379D01*
G01X690399Y326864D02*
X690389Y326874D01*
G01X690469Y326764D02*
X690399Y326864D01*
G01X690479Y326754D02*
X690469Y326764D01*
G01X690709Y326534D02*
X690479Y326754D01*
G01Y326764D02*
X692819D01*
G01X690729Y326524D02*
X690709Y326534D01*
G01X691529Y326224D02*
X691869Y326234D01*
G01X691519Y326224D02*
X691529D01*
G01X691509D02*
X691519D01*
G01X691349Y326244D02*
X691509Y326224D01*
G01X691329Y326244D02*
X691349D01*
G01X690729Y326524D02*
X691329Y326244D01*
G01X691979Y326264D02*
X691309D01*
G01Y327034D02*
X691299Y327044D01*
G01X691329Y327034D02*
X691309D01*
G01X691499Y326974D02*
X691329Y327034D01*
G01X691719Y326964D02*
X691739D01*
G01X691589D02*
X691719D01*
G01X691519Y326974D02*
X691589Y326964D01*
G01X691499Y326974D02*
X691519D01*
G01X691159Y327594D02*
X691129Y327784D01*
G01X691169Y327564D02*
X691159Y327594D01*
G01X691339Y327344D02*
X691169Y327564D01*
G01X691359Y327334D02*
X691339Y327344D01*
G01X691529Y327254D02*
X691359Y327334D01*
G01X691539Y327254D02*
X691529D01*
G01X691579Y327244D02*
X691539Y327254D01*
G01X691639Y327244D02*
X691579D01*
G01X691659D02*
X691639D01*
G01X691689Y328274D02*
X691699D01*
G01X691599D02*
X691689D01*
G01X691579Y328264D02*
X691599Y328274D01*
G01X691269Y328104D02*
X691579Y328264D01*
G01X691249Y328084D02*
X691269Y328104D01*
G01X691139Y327804D02*
X691249Y328084D01*
G01X691309Y328484D02*
X691299Y328474D01*
G01X691329Y328484D02*
X691309D01*
G01X691499Y328544D02*
X691329Y328484D01*
G01X691519Y328544D02*
X691499D01*
G01X691589Y328554D02*
X691519Y328544D01*
G01X691609Y328564D02*
X691589Y328554D01*
G01X691669Y328564D02*
X691609D01*
G01X691699Y328554D02*
X691669Y328564D01*
G01X691279Y328464D02*
X690279D01*
G01X691189Y327944D02*
X692129D01*
G01X692149Y327744D02*
X691139D01*
G01X691189Y327544D02*
X692099D01*
G01X691919Y327344D02*
X691349D01*
G01X691659Y327244D02*
X691789Y327264D01*
G01X691989Y328134D02*
X691339D01*
G01X691739Y328554D02*
X691939Y328504D01*
G01X691699Y328554D02*
X691739D01*
G01X691189Y329224D02*
X691099Y329194D01*
G01X691199Y329234D02*
X691189Y329224D01*
G01X691339Y329264D02*
X691199Y329234D01*
G01X691419Y329284D02*
X691339Y329264D01*
G01X691199Y330064D02*
X690099Y331244D01*
G01X691459Y329784D02*
X691199Y330064D01*
G01X691489Y329734D02*
X691459Y329784D01*
G01X691519Y329584D02*
X691489Y329734D01*
G01X691529Y329564D02*
X691519Y329584D01*
G01X691529Y329544D02*
Y329564D01*
G01X691509Y329374D02*
X691529Y329544D01*
G01X691509Y329364D02*
Y329374D01*
G01X691419Y329284D02*
X691509Y329364D01*
G01X690639Y330654D02*
X691279D01*
G01X691599Y330554D02*
X692109Y336784D01*
G01X691539Y330474D02*
X691599Y330554D01*
G01X691429Y330494D02*
X691539Y330474D01*
G01X691199Y336764D02*
X691179Y336734D01*
G01X691839Y336764D02*
X691199D01*
G01D02*
X692009Y337604D01*
G01X691589Y337154D02*
X693849D01*
G01Y336964D02*
X691399D01*
G01X691099Y336654D02*
X691739D01*
G01X691549Y336464D02*
X687549D01*
G01Y336264D02*
X691359D01*
G01X691159Y336064D02*
X687549D01*
G01X691769Y332564D02*
X692229D01*
G01X692219Y332354D02*
X691749D01*
G01X691729Y332154D02*
X692199D01*
G01X692189Y331964D02*
X691719D01*
G01X691699Y331764D02*
X692169D01*
G01X692159Y331564D02*
X691689D01*
G01X691669Y331354D02*
X692139D01*
G01X692119Y331154D02*
X691659D01*
G01X691639Y330964D02*
X692099D01*
G01X692089Y330764D02*
X691619D01*
G01X691599Y330564D02*
X692069D01*
G01X692029Y330064D02*
X691199D01*
G01X691389Y329854D02*
X692029D01*
G01X692209Y329654D02*
X691509D01*
G01X691519Y329464D02*
X692399D01*
G01X691349Y340954D02*
X691069Y341034D01*
G01X691359Y340944D02*
X691349Y340954D01*
G01X691469Y340914D02*
X691359Y340944D01*
G01X691469Y340904D02*
Y340914D01*
G01X691579Y340864D02*
X691469Y340904D01*
G01X691589Y340854D02*
X691579Y340864D01*
G01X692449Y340854D02*
X691589D01*
G01X691309Y340964D02*
X692339D01*
G01X691139Y341524D02*
X691019Y341564D01*
G01X691249Y341504D02*
X691139Y341524D01*
G01X691489Y341424D02*
X691249Y341504D01*
G01X691599Y341384D02*
X691489Y341424D01*
G01X691659Y341364D02*
X691599Y341384D01*
G01X690949Y341064D02*
X692199D01*
G01X691879Y341264D02*
X689629D01*
G01X692199Y340304D02*
X692109Y340254D01*
G01X692189Y340404D02*
X692199Y340304D01*
G01X692119Y340514D02*
X692189Y340404D01*
G01X692099Y340534D02*
X692119Y340514D01*
G01X691799Y340754D02*
X692099Y340534D01*
G01X691789Y340764D02*
X691799Y340754D01*
G01X691779Y340764D02*
X691789D01*
G01X691589Y340854D02*
X691779Y340764D01*
G01X692119Y340264D02*
X693839D01*
G01X693819Y340464D02*
X692159D01*
G01X691929Y340654D02*
X693739D01*
G01X693849Y338654D02*
X692069D01*
G01X692039Y337634D02*
X692009Y337604D01*
G01X692069Y337694D02*
X692039Y337634D01*
G01X692069Y338714D02*
Y337694D01*
G01X691969Y337564D02*
X692639D01*
G01X692809Y337764D02*
X692069D01*
G01Y337964D02*
X692999D01*
G01X693189Y338154D02*
X692069D01*
G01Y338264D02*
X693849D01*
G01Y338464D02*
X692069D01*
G01X692179Y338794D02*
X692279Y338894D01*
G01X692109Y338794D02*
X692179D01*
G01X692069Y338754D02*
X692109Y338794D01*
G01X692069Y338714D02*
Y338754D01*
G01X691779Y337354D02*
X693849D01*
G01X692569Y336654D02*
X692099D01*
G01X691939Y336864D02*
X688729Y333534D01*
G01X692049Y336884D02*
X691939Y336864D01*
G01X692109Y336784D02*
X692049Y336884D01*
G01X691829Y333354D02*
X692299D01*
G01X692309Y333464D02*
X691839D01*
G01X691859Y333654D02*
X692329D01*
G01X692339Y333854D02*
X691879D01*
G01X691889Y334064D02*
X692359D01*
G01X692369Y334264D02*
X691909D01*
G01X691919Y334464D02*
X692389D01*
G01X692409Y334654D02*
X691939D01*
G01X691959Y334854D02*
X692419D01*
G01X692439Y335064D02*
X691969D01*
G01X691989Y335264D02*
X692459D01*
G01X692469Y335464D02*
X692009D01*
G01X692019Y335654D02*
X692489D01*
G01X692499Y335854D02*
X692039D01*
G01X692049Y336064D02*
X692519D01*
G01X692539Y336264D02*
X692069D01*
G01X692089Y336464D02*
X692549D01*
G01X691939Y336854D02*
X691299D01*
G01X691819Y333154D02*
X692289D01*
G01X692269Y332964D02*
X691799D01*
G01X691789Y332764D02*
X692249D01*
G01X692239Y332654D02*
X691779D01*
G01X691759Y332464D02*
X692229D01*
G01X692209Y332264D02*
X691739D01*
G01X691729Y332064D02*
X692199D01*
G01X692179Y331854D02*
X691709D01*
G01X691699Y331654D02*
X692159D01*
G01X692149Y331464D02*
X691679D01*
G01X691659Y331264D02*
X692129D01*
G01X692109Y331064D02*
X691649D01*
G01X691629Y330854D02*
X692099D01*
G01X692079Y330654D02*
X691609D01*
G01X692069Y330464D02*
X690829D01*
G01X691109Y330154D02*
X692039D01*
G01X692029Y329964D02*
X691299D01*
G01X691469Y329764D02*
X692109D01*
G01X692049Y329824D02*
X693009Y328804D01*
G01X693329Y328464D02*
X691999D01*
G01X691979Y328484D02*
X691939Y328504D01*
G01X691979Y328484D02*
X692289Y328224D01*
G01X692059Y328044D02*
X691229D01*
G01X691149Y327844D02*
X692139D01*
G01X691949Y328174D02*
X691699Y328274D01*
G01X691969Y328164D02*
X691949Y328174D01*
G01X692119Y327964D02*
X691969Y328164D01*
G01X692129Y327934D02*
X692119Y327964D01*
G01X691789Y328244D02*
X691519D01*
G01X691809Y327264D02*
X691789D01*
G01X692029Y327404D02*
X691809Y327264D01*
G01X692039Y327424D02*
X692029Y327404D01*
G01X692149Y327654D02*
X692039Y327424D01*
G01X692159Y327674D02*
X692149Y327654D01*
G01X692129Y327934D02*
X692159Y327674D01*
G01X691999Y327064D02*
X693019D01*
G01X691879Y326234D02*
X691869D01*
G01X692169Y326304D02*
X691879Y326234D01*
G01X692179Y326314D02*
X692169Y326304D01*
G01X692689Y326624D02*
X692179Y326314D01*
G01X691939Y327014D02*
X691979Y327034D01*
G01X691739Y326964D02*
X691939Y327014D01*
G01X692049Y327444D02*
X691269D01*
G01X691149Y327634D02*
X692149D01*
G01X692039Y329844D02*
X692019Y329914D01*
G01X692049Y329834D02*
X692039Y329844D01*
G01X692049Y329824D02*
Y329834D01*
G01X691809Y341304D02*
X691659Y341364D01*
G01X691819Y341294D02*
X691809Y341304D01*
G01X693069Y341014D02*
X693129Y341024D01*
G01X693059Y341014D02*
X693069D01*
G01X692949Y340984D02*
X693059Y341014D01*
G01X692939Y340984D02*
X692949D01*
G01X692809Y340934D02*
X692939Y340984D01*
G01X692809Y340924D02*
Y340934D01*
G01X692749Y340894D02*
X692809Y340924D01*
G01X692729Y340874D02*
X692749Y340894D01*
G01X692669Y340824D02*
X692729Y340874D01*
G01X692649Y340804D02*
X692669Y340824D01*
G01X692509Y340804D02*
X692649D01*
G01X692329Y340974D02*
X692509Y340804D01*
G01X692319Y340984D02*
X692329Y340974D01*
G01X691819Y341294D02*
X692319Y340984D01*
G01X692879Y340964D02*
X693399D01*
G01X693449Y339654D02*
X692289D01*
G01X692339Y339604D02*
X692279Y338894D01*
G01X692249Y338854D02*
X692799D01*
G01X693089Y339584D02*
X693119Y339574D01*
G01X693009Y339594D02*
X693089Y339584D01*
G01X692939Y339614D02*
X693009Y339594D01*
G01X692929Y339614D02*
X692939D01*
G01X692799Y339524D02*
X692929Y339614D01*
G01X692749Y338914D02*
X692799Y339524D01*
G01X692849Y338804D02*
X692749Y338914D01*
G01X692849Y339564D02*
X692339D01*
G01X692239Y339714D02*
X684889D01*
G01X692339Y339604D02*
X692239Y339714D01*
G01X691879Y337464D02*
X692699D01*
G01X692669Y337614D02*
X693219Y338194D01*
G01X692639Y337564D02*
X692669Y337614D01*
G01X692639Y337524D02*
Y337564D01*
G01X692739Y337414D02*
X692639Y337524D01*
G01X693099Y338064D02*
X692069D01*
G01Y337854D02*
X692899D01*
G01X692709Y337654D02*
X692049D01*
G01X692069Y336854D02*
X692599D01*
G01X692589Y336844D02*
X692019Y329914D01*
G01X692299Y329564D02*
X691529D01*
G01X691499Y329354D02*
X692489D01*
G01X692579Y329264D02*
X691309D01*
G01X690699Y328964D02*
X692859D01*
G01X693049Y328764D02*
X690479D01*
G01X690329Y326964D02*
X692959D01*
G01X692779Y326714D02*
X692689Y326624D01*
G01X692839Y326784D02*
X692779Y326714D01*
G01X692969Y326974D02*
X692839Y326784D01*
G01X692729Y326654D02*
X690579D01*
G01X690399Y326854D02*
X692889D01*
G01X693089Y327224D02*
X693149Y327394D01*
G01X693049Y327124D02*
X693089Y327224D01*
G01X693049Y327114D02*
Y327124D01*
G01X692979Y326984D02*
X693049Y327114D01*
G01X692969Y326974D02*
X692979Y326984D01*
G01X693139Y327354D02*
X692324D01*
G01X692329D02*
X692389D01*
G01X692289Y327294D02*
X691979Y327034D01*
G01X692319Y327344D02*
X692289Y327294D01*
G01X692119Y327154D02*
X693069D01*
G01X693099Y327264D02*
X692309D01*
G01X693069D02*
X693099D01*
G01X692319Y328174D02*
X692289Y328224D01*
G01X692439Y327784D02*
X692319Y328174D01*
G01X692439Y327724D02*
Y327784D01*
G01X692319Y327344D02*
X692439Y327724D01*
G01X692249Y328264D02*
X693509D01*
G01X693699Y328064D02*
X692359D01*
G01X692419Y327854D02*
X693879D01*
G01X693179Y327654D02*
X692419D01*
G01X692359Y327464D02*
X693159D01*
G01X692249Y326354D02*
X691089D01*
G01X691789Y332854D02*
X692259D01*
G01X692279Y333064D02*
X691809D01*
G01X691829Y333264D02*
X692289D01*
G01X692319Y333564D02*
X691849D01*
G01X691859Y333764D02*
X692329D01*
G01X692349Y333964D02*
X691879D01*
G01X691899Y334154D02*
X692359D01*
G01X692379Y334354D02*
X691919D01*
G01X691929Y334564D02*
X692399D01*
G01X692419Y334764D02*
X691949D01*
G01X691959Y334964D02*
X692429D01*
G01X692449Y335154D02*
X691979D01*
G01X691999Y335354D02*
X692459D01*
G01X692479Y335564D02*
X692009D01*
G01X692029Y335764D02*
X692489D01*
G01X692509Y335964D02*
X692049D01*
G01X692059Y336154D02*
X692529D01*
G01X692549Y336354D02*
X692079D01*
G01X692089Y336564D02*
X692559D01*
G01X692579Y336764D02*
X692109D01*
G01X692589Y336844D02*
X692679Y336934D01*
G01X693009Y338794D02*
X693129D01*
G01X692849Y338804D02*
X693009Y338794D01*
G01X692759Y338964D02*
X692289D01*
G01X692299Y339064D02*
X692769D01*
G01Y339154D02*
X692309D01*
G01Y339264D02*
X692779D01*
G01X692789Y339354D02*
X692319D01*
G01X692329Y339464D02*
X692799D01*
G01X693199Y341024D02*
X693129D01*
G01X693209Y341014D02*
X693199Y341024D01*
G01X693469Y340944D02*
X693209Y341014D01*
G01X693479Y340934D02*
X693469Y340944D01*
G01X693679Y340764D02*
X693479Y340934D01*
G01X693689Y340754D02*
X693679Y340764D01*
G01X693809Y340524D02*
X693689Y340754D01*
G01X693819Y340504D02*
X693809Y340524D01*
G01X693839Y340224D02*
X693819Y340504D01*
G01X693839Y340214D02*
Y340224D01*
G01X693759Y339954D02*
X693839Y340214D01*
G01X693749Y339944D02*
X693759Y339954D01*
G01X693589Y339744D02*
X693749Y339944D01*
G01X693579Y339724D02*
X693589Y339744D01*
G01X693349Y339604D02*
X693579Y339724D01*
G01X693329Y339604D02*
X693349D01*
G01X693209Y339584D02*
X693329Y339604D01*
G01X693199Y339584D02*
X693209D01*
G01X693139Y339574D02*
X693199Y339584D01*
G01X693119Y339574D02*
X693139D01*
G01X692709Y340854D02*
X693569D01*
G01X693679Y340764D02*
X691789D01*
G01X692069Y340564D02*
X693789D01*
G01X693829Y340354D02*
X692199D01*
G01X693689Y339854D02*
X683579D01*
G01Y340064D02*
X693789D01*
G01X694099Y339764D02*
X694729D01*
G01X694829Y339854D02*
X694199D01*
G01X694289Y339964D02*
X694929D01*
G01X695019Y340064D02*
X694389D01*
G01X694489Y340154D02*
X695119D01*
G01X695209Y340264D02*
X694589D01*
G01X694679Y340354D02*
X695309D01*
G01X695409Y340464D02*
X694779D01*
G01X694879Y340564D02*
X695509D01*
G01X695699Y340764D02*
X695069D01*
G01X695259Y340964D02*
X695889D01*
G01X694639Y339654D02*
X694009D01*
G01X693909Y339564D02*
X694539D01*
G01X694439Y339464D02*
X693809D01*
G01X693709Y339354D02*
X694349D01*
G01X694249Y339264D02*
X693619D01*
G01X693519Y339154D02*
X694159D01*
G01X694059Y339064D02*
X693429D01*
G01X693329Y338964D02*
X693959D01*
G01X693809Y336934D02*
X692679D01*
G01X693849Y336954D02*
X693809Y336934D01*
G01X693849Y336964D02*
Y336954D01*
G01Y338784D02*
Y336964D01*
G01Y338794D02*
Y338784D01*
G01X693879Y338874D02*
X693849Y338794D01*
G01X693329Y338214D02*
X693219Y338194D01*
G01X693389Y338114D02*
X693329Y338214D01*
G01X693389Y337514D02*
Y338114D01*
G01X693289Y337414D02*
X693389Y337514D01*
G01X692739Y337414D02*
X693289D01*
G01X693359Y338154D02*
X693849D01*
G01Y338064D02*
X693389D01*
G01Y337964D02*
X693849D01*
G01Y337854D02*
X693389D01*
G01Y337764D02*
X693849D01*
G01Y337654D02*
X693389D01*
G01Y337564D02*
X693849D01*
G01Y337464D02*
X693339D01*
G01X693849Y337264D02*
X691679D01*
G01X691489Y337064D02*
X693849D01*
G01Y338354D02*
X692069D01*
G01Y338564D02*
X693849D01*
G01Y338764D02*
X692069D01*
G01X693129Y338794D02*
X693199Y338824D01*
G01X693229Y338854D02*
X693869D01*
G01X693229Y328564D02*
X691679D01*
G01X692119Y328354D02*
X693419D01*
G01X693599Y328154D02*
X692329D01*
G01X692379Y327964D02*
X693789D01*
G01X693979Y327764D02*
X693289D01*
G01X693149Y327414D02*
Y327394D01*
G01X693189Y327684D02*
X693149Y327414D01*
G01X693249Y327764D02*
X693189Y327684D01*
G01X693169Y327564D02*
X692389D01*
G01X693249Y327764D02*
X693359Y327744D01*
G01X692439Y327764D02*
X693249D01*
G01X693439Y327654D02*
X694069D01*
G01X694159Y327564D02*
X693529D01*
G01X693619Y327464D02*
X694259D01*
G01X694309Y327354D02*
X694349D01*
G01X694359D02*
X693719D01*
G01X693809Y327264D02*
X694444D01*
G01X694439D02*
X694389D01*
G01X694544Y327154D02*
X693899D01*
G01X693989Y327064D02*
X694629D01*
G01X694719Y326964D02*
X694084D01*
G01X694184Y326854D02*
X694819D01*
G01X694909Y326764D02*
X694269D01*
G01X694374Y326654D02*
X694999D01*
G01X695099Y326564D02*
X694459D01*
G01X694549Y326464D02*
X695189D01*
G01X695279Y326354D02*
X694639D01*
G01X694729Y326264D02*
X695379D01*
G01X695559Y326064D02*
X694919D01*
G01X694829Y326154D02*
X695469D01*
G01X695649Y325964D02*
X695009D01*
G01X695109Y325854D02*
X695749D01*
G01X695839Y325764D02*
X695199D01*
G01X695289Y325654D02*
X695929D01*
G01X696029Y325564D02*
X695379D01*
G01X695479Y325464D02*
X696119D01*
G01X696209Y325354D02*
X695569D01*
G01X695659Y325264D02*
X696309D01*
G01X696399Y325154D02*
X695759D01*
G01X695849Y325064D02*
X696489D01*
G01X696679Y324854D02*
X696039D01*
G01X696219Y324654D02*
X696829D01*
G01X696819Y324714D02*
X693009Y328804D01*
G01X696489Y324374D02*
X696509Y324354D01*
G01X693359Y327744D02*
X696489Y324374D01*
G01X696409Y324464D02*
X696629D01*
G01X679549Y324694D02*
X684969Y330304D01*
G01X679519Y324664D02*
X679549Y324694D01*
G01X679529Y324644D02*
X679519Y324664D01*
G01X679839Y324374D02*
X679529Y324644D01*
G01X679869Y324364D02*
X679839Y324374D01*
G01X679889D02*
X679869Y324364D01*
G01X685009Y329674D02*
X679889Y324374D01*
G01X679969Y324464D02*
X679739D01*
G01X679619Y324564D02*
X680069D01*
G01X680169Y324654D02*
X679519D01*
G01X679609Y324764D02*
X680269D01*
G01X680359Y324854D02*
X679709D01*
G01X679799Y324964D02*
X680459D01*
G01X680549Y325064D02*
X679899D01*
G01X679989Y325154D02*
X680649D01*
G01X680749Y325264D02*
X680089D01*
G01X680189Y325354D02*
X680839D01*
G01X680939Y325464D02*
X680289D01*
G01X680379Y325564D02*
X681039D01*
G01X681129Y325654D02*
X680479D01*
G01X680579Y325764D02*
X681229D01*
G01X681329Y325854D02*
X680669D01*
G01X680769Y325964D02*
X681419D01*
G01X693199Y338824D02*
X697779Y343564D01*
G01X697809Y342954D02*
X693879Y338874D01*
G01X694969Y340654D02*
X695599D01*
G01X695789Y340854D02*
X695159D01*
G01X695359Y341064D02*
X695989D01*
G01X696089Y341154D02*
X695459D01*
G01X695549Y341264D02*
X696179D01*
G01X696279Y341354D02*
X695649D01*
G01X695749Y341464D02*
X696369D01*
G01X696469Y341564D02*
X695839D01*
G01X696029Y341764D02*
X696659D01*
G01X696859Y341964D02*
X696229D01*
G01X696419Y342154D02*
X697049D01*
G01X696949Y342064D02*
X696329D01*
G01X696519Y342264D02*
X697139D01*
G01X697239Y342354D02*
X696609D01*
G01X696709Y342464D02*
X697339D01*
G01X697439Y342564D02*
X696809D01*
G01X696899Y342654D02*
X697529D01*
G01X697629Y342764D02*
X696999D01*
G01X697099Y342854D02*
X697719D01*
G01X697829Y343064D02*
X697289D01*
G01X697819Y342984D02*
X697829Y343064D01*
G01X697809Y342954D02*
X697819Y342984D01*
G01X697199Y342964D02*
X697809D01*
G01X697829Y343554D02*
X697779Y343564D01*
G01X697829Y343064D02*
Y343554D01*
G01X697769Y343564D02*
X697809D01*
G01X697829Y343464D02*
X697679D01*
G01X697579Y343354D02*
X697829D01*
G01Y343264D02*
X697479D01*
G01X697389Y343154D02*
X697829D01*
G01X696759Y341854D02*
X696129D01*
G01X695939Y341654D02*
X696569D01*
G01X696589Y324964D02*
X695939D01*
G01X696129Y324764D02*
X696769D01*
G01X696539Y324374D02*
X696509Y324354D01*
G01X696829Y324664D02*
X696539Y324374D01*
G01X696839Y324684D02*
X696829Y324664D01*
G01Y324694D02*
X696839Y324684D01*
G01X696819Y324714D02*
X696829Y324694D01*
G01X696309Y324564D02*
X696729D01*
G54D19*
G01X9217Y120444D02*
X8967Y120569D01*
X8675Y120652D01*
X8342D01*
X7967Y120527D01*
X7675Y120319D01*
X7467Y120069D01*
X7300Y119652D01*
X7258Y119277D01*
X7342Y118902D01*
X7467Y118652D01*
X7717Y118402D01*
X8008Y118235D01*
X8300Y118152D01*
X8592D01*
X8883Y118235D01*
X9133Y118360D01*
X9342Y118527D01*
G01X10342Y118152D02*
Y120652D01*
X12258Y118152D01*
Y120652D01*
G01X13383Y118527D02*
X13633Y118319D01*
X13925Y118194D01*
X14300Y118152D01*
X14675Y118235D01*
X14967Y118402D01*
X15175Y118694D01*
X15217Y119027D01*
X15133Y119360D01*
X14925Y119569D01*
X14633Y119735D01*
X14342Y119777D01*
X14050Y119735D01*
X13675Y119569D01*
X13800Y120652D01*
X14925D01*
G01X28125Y41500D02*
Y44000D01*
G01X29875D02*
Y41500D01*
G01Y42750D02*
X28125D01*
G01X31208Y43583D02*
X31458Y43833D01*
X31750Y43958D01*
X32083Y44000D01*
X32500Y43917D01*
X32792Y43708D01*
X32875Y43458D01*
X32833Y43208D01*
X32667Y43000D01*
X31833Y42583D01*
X31458Y42292D01*
X31208Y41875D01*
X31125Y41500D01*
X32875D01*
G01X73625D02*
Y44000D01*
G01X75375D02*
Y41500D01*
G01Y42750D02*
X73625D01*
G01X78000Y41500D02*
Y44000D01*
X76458Y42208D01*
X78542D01*
G01X48800Y99467D02*
X46300D01*
Y100508D01*
X46425Y100842D01*
X46592Y101050D01*
X46925Y101133D01*
X47258Y101050D01*
X47467Y100800D01*
X47592Y100508D01*
Y99467D01*
G01Y100508D02*
X48800Y101133D01*
G01X46717Y102508D02*
X46467Y102758D01*
X46342Y103050D01*
X46300Y103383D01*
X46383Y103800D01*
X46592Y104092D01*
X46842Y104175D01*
X47092Y104133D01*
X47300Y103967D01*
X47717Y103133D01*
X48008Y102758D01*
X48425Y102508D01*
X48800Y102425D01*
Y104175D01*
G01Y106800D02*
X46300D01*
X48092Y105258D01*
Y107342D01*
G01X48425Y108383D02*
X48633Y108633D01*
X48758Y108925D01*
X48800Y109300D01*
X48717Y109675D01*
X48550Y109967D01*
X48258Y110175D01*
X47925Y110217D01*
X47592Y110133D01*
X47383Y109925D01*
X47217Y109633D01*
X47175Y109342D01*
X47217Y109050D01*
X47383Y108675D01*
X46300Y108800D01*
Y109925D01*
G01X40905Y76891D02*
Y79391D01*
X41946D01*
X42280Y79266D01*
X42488Y79099D01*
X42571Y78766D01*
X42488Y78433D01*
X42238Y78224D01*
X41946Y78099D01*
X40905D01*
G01X41946D02*
X42571Y76891D01*
G01X43946Y78974D02*
X44196Y79224D01*
X44488Y79349D01*
X44821Y79391D01*
X45238Y79308D01*
X45530Y79099D01*
X45613Y78849D01*
X45571Y78599D01*
X45405Y78391D01*
X44571Y77974D01*
X44196Y77683D01*
X43946Y77266D01*
X43863Y76891D01*
X45613D01*
G01X47738Y79391D02*
X47405Y79308D01*
X47155Y79099D01*
X46988Y78849D01*
X46863Y78516D01*
X46821Y78141D01*
X46863Y77766D01*
X46988Y77433D01*
X47155Y77183D01*
X47405Y76974D01*
X47738Y76891D01*
X48071Y76974D01*
X48321Y77183D01*
X48488Y77433D01*
X48613Y77766D01*
X48655Y78141D01*
X48613Y78516D01*
X48488Y78849D01*
X48321Y79099D01*
X48071Y79308D01*
X47738Y79391D01*
G01X49821Y77391D02*
X50071Y77099D01*
X50405Y76933D01*
X50780Y76891D01*
X51113Y76933D01*
X51446Y77141D01*
X51655Y77391D01*
X51696Y77641D01*
X51613Y77933D01*
X51321Y78141D01*
X51030Y78224D01*
X50655D01*
G01X51030D02*
X51280Y78349D01*
X51488Y78558D01*
X51571Y78808D01*
X51488Y79058D01*
X51280Y79266D01*
X50905Y79391D01*
X50530Y79349D01*
X50155Y79183D01*
G01X41047Y73065D02*
Y75565D01*
X42088D01*
X42422Y75440D01*
X42630Y75273D01*
X42713Y74940D01*
X42630Y74607D01*
X42380Y74398D01*
X42088Y74273D01*
X41047D01*
G01X42088D02*
X42713Y73065D01*
G01X44088Y75148D02*
X44338Y75398D01*
X44630Y75523D01*
X44963Y75565D01*
X45380Y75482D01*
X45672Y75273D01*
X45755Y75023D01*
X45713Y74773D01*
X45547Y74565D01*
X44713Y74148D01*
X44338Y73857D01*
X44088Y73440D01*
X44005Y73065D01*
X45755D01*
G01X47880Y75565D02*
X47547Y75482D01*
X47297Y75273D01*
X47130Y75023D01*
X47005Y74690D01*
X46963Y74315D01*
X47005Y73940D01*
X47130Y73607D01*
X47297Y73357D01*
X47547Y73148D01*
X47880Y73065D01*
X48213Y73148D01*
X48463Y73357D01*
X48630Y73607D01*
X48755Y73940D01*
X48797Y74315D01*
X48755Y74690D01*
X48630Y75023D01*
X48463Y75273D01*
X48213Y75482D01*
X47880Y75565D01*
G01X50088Y75148D02*
X50338Y75398D01*
X50630Y75523D01*
X50963Y75565D01*
X51380Y75482D01*
X51672Y75273D01*
X51755Y75023D01*
X51713Y74773D01*
X51547Y74565D01*
X50713Y74148D01*
X50338Y73857D01*
X50088Y73440D01*
X50005Y73065D01*
X51755D01*
G01X56700Y98067D02*
X54200D01*
Y99108D01*
X54325Y99442D01*
X54492Y99650D01*
X54825Y99733D01*
X55158Y99650D01*
X55367Y99400D01*
X55492Y99108D01*
Y98067D01*
G01Y99108D02*
X56700Y99733D01*
G01X54617Y101108D02*
X54367Y101358D01*
X54242Y101650D01*
X54200Y101983D01*
X54283Y102400D01*
X54492Y102692D01*
X54742Y102775D01*
X54992Y102733D01*
X55200Y102567D01*
X55617Y101733D01*
X55908Y101358D01*
X56325Y101108D01*
X56700Y101025D01*
Y102775D01*
G01X56200Y103983D02*
X56492Y104233D01*
X56658Y104567D01*
X56700Y104942D01*
X56658Y105275D01*
X56450Y105608D01*
X56200Y105817D01*
X55950Y105858D01*
X55658Y105775D01*
X55450Y105483D01*
X55367Y105192D01*
Y104817D01*
G01Y105192D02*
X55242Y105442D01*
X55033Y105650D01*
X54783Y105733D01*
X54533Y105650D01*
X54325Y105442D01*
X54200Y105067D01*
X54242Y104692D01*
X54408Y104317D01*
G01X54617Y107108D02*
X54367Y107358D01*
X54242Y107650D01*
X54200Y107983D01*
X54283Y108400D01*
X54492Y108692D01*
X54742Y108775D01*
X54992Y108733D01*
X55200Y108567D01*
X55617Y107733D01*
X55908Y107358D01*
X56325Y107108D01*
X56700Y107025D01*
Y108775D01*
G01X76300Y97767D02*
X73800D01*
Y98808D01*
X73925Y99142D01*
X74092Y99350D01*
X74425Y99433D01*
X74758Y99350D01*
X74967Y99100D01*
X75092Y98808D01*
Y97767D01*
G01Y98808D02*
X76300Y99433D01*
G01X74217Y100808D02*
X73967Y101058D01*
X73842Y101350D01*
X73800Y101683D01*
X73883Y102100D01*
X74092Y102392D01*
X74342Y102475D01*
X74592Y102433D01*
X74800Y102267D01*
X75217Y101433D01*
X75508Y101058D01*
X75925Y100808D01*
X76300Y100725D01*
Y102475D01*
G01X75800Y103683D02*
X76092Y103933D01*
X76258Y104267D01*
X76300Y104642D01*
X76258Y104975D01*
X76050Y105308D01*
X75800Y105517D01*
X75550Y105558D01*
X75258Y105475D01*
X75050Y105183D01*
X74967Y104892D01*
Y104517D01*
G01Y104892D02*
X74842Y105142D01*
X74633Y105350D01*
X74383Y105433D01*
X74133Y105350D01*
X73925Y105142D01*
X73800Y104767D01*
X73842Y104392D01*
X74008Y104017D01*
G01X73800Y107600D02*
X73883Y107267D01*
X74092Y107017D01*
X74342Y106850D01*
X74675Y106725D01*
X75050Y106683D01*
X75425Y106725D01*
X75758Y106850D01*
X76008Y107017D01*
X76217Y107267D01*
X76300Y107600D01*
X76217Y107933D01*
X76008Y108183D01*
X75758Y108350D01*
X75425Y108475D01*
X75050Y108517D01*
X74675Y108475D01*
X74342Y108350D01*
X74092Y108183D01*
X73883Y107933D01*
X73800Y107600D01*
G01X41214Y69317D02*
Y71817D01*
X42255D01*
X42589Y71692D01*
X42797Y71525D01*
X42880Y71192D01*
X42797Y70859D01*
X42547Y70650D01*
X42255Y70525D01*
X41214D01*
G01X42255D02*
X42880Y69317D01*
G01X45047D02*
Y71817D01*
X44547Y71317D01*
G01Y69317D02*
X45547D01*
G01X47339Y69609D02*
X47630Y69400D01*
X47964Y69317D01*
X48297Y69400D01*
X48589Y69650D01*
X48797Y70025D01*
X48880Y70400D01*
Y70859D01*
X48797Y71234D01*
X48589Y71567D01*
X48339Y71734D01*
X48047Y71817D01*
X47714Y71734D01*
X47464Y71567D01*
X47297Y71317D01*
X47214Y70984D01*
X47297Y70692D01*
X47505Y70400D01*
X47755Y70234D01*
X48047Y70192D01*
X48380Y70275D01*
X48630Y70484D01*
X48880Y70859D01*
G01X50339Y69609D02*
X50630Y69400D01*
X50964Y69317D01*
X51297Y69400D01*
X51589Y69650D01*
X51797Y70025D01*
X51880Y70400D01*
Y70859D01*
X51797Y71234D01*
X51589Y71567D01*
X51339Y71734D01*
X51047Y71817D01*
X50714Y71734D01*
X50464Y71567D01*
X50297Y71317D01*
X50214Y70984D01*
X50297Y70692D01*
X50505Y70400D01*
X50755Y70234D01*
X51047Y70192D01*
X51380Y70275D01*
X51630Y70484D01*
X51880Y70859D01*
G01X23661Y129599D02*
Y127099D01*
X25327D01*
G01X28327D02*
X26661D01*
Y129599D01*
X28327D01*
G01X27661Y128391D02*
X26661D01*
G01X29577Y127099D02*
Y129599D01*
X30411D01*
X30744Y129474D01*
X30994Y129307D01*
X31202Y129057D01*
X31369Y128766D01*
X31411Y128349D01*
X31369Y127932D01*
X31202Y127641D01*
X30994Y127391D01*
X30744Y127224D01*
X30411Y127099D01*
X29577D01*
G01X32702Y128141D02*
X32994Y128432D01*
X33244Y128599D01*
X33577Y128682D01*
X33869Y128599D01*
X34077Y128432D01*
X34244Y128182D01*
X34286Y127891D01*
X34244Y127641D01*
X34077Y127391D01*
X33827Y127182D01*
X33536Y127099D01*
X33202Y127182D01*
X32911Y127432D01*
X32744Y127807D01*
X32702Y128224D01*
X32786Y128766D01*
X32911Y129057D01*
X33119Y129349D01*
X33411Y129557D01*
X33702Y129599D01*
X33994Y129516D01*
X34202Y129307D01*
G01X62467Y199500D02*
Y202000D01*
X63467D01*
X63800Y201875D01*
X64050Y201583D01*
X64133Y201250D01*
X64050Y200917D01*
X63842Y200667D01*
X63467Y200542D01*
X62467D01*
G01X67217Y201792D02*
X66967Y201917D01*
X66675Y202000D01*
X66342D01*
X65967Y201875D01*
X65675Y201667D01*
X65467Y201417D01*
X65300Y201000D01*
X65258Y200625D01*
X65342Y200250D01*
X65467Y200000D01*
X65717Y199750D01*
X66008Y199583D01*
X66300Y199500D01*
X66592D01*
X66883Y199583D01*
X67133Y199708D01*
X67342Y199875D01*
G01X69800Y199500D02*
Y202000D01*
X68258Y200208D01*
X70342D01*
G01X72800Y199500D02*
Y202000D01*
X71258Y200208D01*
X73342D01*
G01X42217Y177492D02*
X41967Y177617D01*
X41675Y177700D01*
X41342D01*
X40967Y177575D01*
X40675Y177367D01*
X40467Y177117D01*
X40300Y176700D01*
X40258Y176325D01*
X40342Y175950D01*
X40467Y175700D01*
X40717Y175450D01*
X41008Y175283D01*
X41300Y175200D01*
X41592D01*
X41883Y175283D01*
X42133Y175408D01*
X42342Y175575D01*
G01X43508Y177283D02*
X43758Y177533D01*
X44050Y177658D01*
X44383Y177700D01*
X44800Y177617D01*
X45092Y177408D01*
X45175Y177158D01*
X45133Y176908D01*
X44967Y176700D01*
X44133Y176283D01*
X43758Y175992D01*
X43508Y175575D01*
X43425Y175200D01*
X45175D01*
G01X47800D02*
Y177700D01*
X46258Y175908D01*
X48342D01*
G01X49383Y175575D02*
X49633Y175367D01*
X49925Y175242D01*
X50300Y175200D01*
X50675Y175283D01*
X50967Y175450D01*
X51175Y175742D01*
X51217Y176075D01*
X51133Y176408D01*
X50925Y176617D01*
X50633Y176783D01*
X50342Y176825D01*
X50050Y176783D01*
X49675Y176617D01*
X49800Y177700D01*
X50925D01*
G01X77317Y179892D02*
X77067Y180017D01*
X76775Y180100D01*
X76442D01*
X76067Y179975D01*
X75775Y179767D01*
X75567Y179517D01*
X75400Y179100D01*
X75358Y178725D01*
X75442Y178350D01*
X75567Y178100D01*
X75817Y177850D01*
X76108Y177683D01*
X76400Y177600D01*
X76692D01*
X76983Y177683D01*
X77233Y177808D01*
X77442Y177975D01*
G01X78608Y179683D02*
X78858Y179933D01*
X79150Y180058D01*
X79483Y180100D01*
X79900Y180017D01*
X80192Y179808D01*
X80275Y179558D01*
X80233Y179308D01*
X80067Y179100D01*
X79233Y178683D01*
X78858Y178392D01*
X78608Y177975D01*
X78525Y177600D01*
X80275D01*
G01X82900D02*
Y180100D01*
X81358Y178308D01*
X83442D01*
G01X85400Y177600D02*
X85692Y177642D01*
X86025Y177767D01*
X86233Y177975D01*
X86317Y178267D01*
X86233Y178558D01*
X85983Y178808D01*
X85608Y178933D01*
X85192D01*
X84942Y179017D01*
X84733Y179225D01*
X84650Y179517D01*
X84775Y179808D01*
X85067Y180017D01*
X85400Y180100D01*
X85733Y180017D01*
X86025Y179808D01*
X86150Y179517D01*
X86067Y179225D01*
X85858Y179017D01*
X85608Y178933D01*
X85192D01*
X84817Y178808D01*
X84567Y178558D01*
X84483Y178267D01*
X84567Y177975D01*
X84775Y177767D01*
X85108Y177642D01*
X85400Y177600D01*
G01X68200Y204867D02*
X65700D01*
Y205867D01*
X65825Y206200D01*
X66117Y206450D01*
X66450Y206533D01*
X66783Y206450D01*
X67033Y206242D01*
X67158Y205867D01*
Y204867D01*
G01X68200Y208700D02*
X68158Y208367D01*
X67992Y208075D01*
X67742Y207825D01*
X67450Y207658D01*
X67117Y207575D01*
X66783D01*
X66450Y207658D01*
X66158Y207825D01*
X65908Y208075D01*
X65742Y208367D01*
X65700Y208700D01*
X65742Y209033D01*
X65908Y209325D01*
X66158Y209575D01*
X66450Y209742D01*
X66783Y209825D01*
X67117D01*
X67450Y209742D01*
X67742Y209575D01*
X67992Y209325D01*
X68158Y209033D01*
X68200Y208700D01*
G01X67533Y209033D02*
X68200Y209533D01*
G01Y212200D02*
X65700D01*
X67492Y210658D01*
Y212742D01*
G01X59900Y183883D02*
X61692D01*
X62067Y184050D01*
X62317Y184383D01*
X62400Y184800D01*
X62317Y185217D01*
X62067Y185550D01*
X61692Y185717D01*
X59900D01*
G01X62400Y187800D02*
X59900D01*
X60400Y187300D01*
G01X62400D02*
Y188300D01*
G01X62108Y190092D02*
X62317Y190383D01*
X62400Y190717D01*
X62317Y191050D01*
X62067Y191342D01*
X61692Y191550D01*
X61317Y191633D01*
X60858D01*
X60483Y191550D01*
X60150Y191342D01*
X59983Y191092D01*
X59900Y190800D01*
X59983Y190467D01*
X60150Y190217D01*
X60400Y190050D01*
X60733Y189967D01*
X61025Y190050D01*
X61317Y190258D01*
X61483Y190508D01*
X61525Y190800D01*
X61442Y191133D01*
X61233Y191383D01*
X60858Y191633D01*
G01X68925Y166733D02*
X69258Y166525D01*
X69633Y166400D01*
X69967D01*
X70300Y166525D01*
X70550Y166733D01*
X70675Y167025D01*
X70592Y167317D01*
X70383Y167567D01*
X70008Y167733D01*
X69508Y167817D01*
X69217Y167983D01*
X69092Y168275D01*
X69175Y168567D01*
X69383Y168775D01*
X69675Y168900D01*
X69967D01*
X70258Y168817D01*
X70508Y168608D01*
G01X71550Y168900D02*
X72133Y166400D01*
X72800Y168900D01*
X73467Y166400D01*
X74050Y168900D01*
G01X75800Y166400D02*
Y168900D01*
X75300Y168400D01*
G01Y166400D02*
X76300D01*
G01X43867Y266000D02*
Y268500D01*
X44908D01*
X45242Y268375D01*
X45450Y268208D01*
X45533Y267875D01*
X45450Y267542D01*
X45200Y267333D01*
X44908Y267208D01*
X43867D01*
G01X44908D02*
X45533Y266000D01*
G01X47617D02*
X47700Y266542D01*
X47825Y267000D01*
X47992Y267417D01*
X48200Y267875D01*
X48533Y268500D01*
X46867D01*
G01X50617Y266000D02*
X50700Y266542D01*
X50825Y267000D01*
X50992Y267417D01*
X51200Y267875D01*
X51533Y268500D01*
X49867D01*
G01X33867Y266000D02*
Y268500D01*
X34908D01*
X35242Y268375D01*
X35450Y268208D01*
X35533Y267875D01*
X35450Y267542D01*
X35200Y267333D01*
X34908Y267208D01*
X33867D01*
G01X34908D02*
X35533Y266000D01*
G01X37617D02*
X37700Y266542D01*
X37825Y267000D01*
X37992Y267417D01*
X38200Y267875D01*
X38533Y268500D01*
X36867D01*
G01X39908Y267042D02*
X40200Y267333D01*
X40450Y267500D01*
X40783Y267583D01*
X41075Y267500D01*
X41283Y267333D01*
X41450Y267083D01*
X41492Y266792D01*
X41450Y266542D01*
X41283Y266292D01*
X41033Y266083D01*
X40742Y266000D01*
X40408Y266083D01*
X40117Y266333D01*
X39950Y266708D01*
X39908Y267125D01*
X39992Y267667D01*
X40117Y267958D01*
X40325Y268250D01*
X40617Y268458D01*
X40908Y268500D01*
X41200Y268417D01*
X41408Y268208D01*
G01X43867Y271100D02*
Y273600D01*
X44908D01*
X45242Y273475D01*
X45450Y273308D01*
X45533Y272975D01*
X45450Y272642D01*
X45200Y272433D01*
X44908Y272308D01*
X43867D01*
G01X44908D02*
X45533Y271100D01*
G01X47617D02*
X47700Y271642D01*
X47825Y272100D01*
X47992Y272517D01*
X48200Y272975D01*
X48533Y273600D01*
X46867D01*
G01X49783Y271475D02*
X50033Y271267D01*
X50325Y271142D01*
X50700Y271100D01*
X51075Y271183D01*
X51367Y271350D01*
X51575Y271642D01*
X51617Y271975D01*
X51533Y272308D01*
X51325Y272517D01*
X51033Y272683D01*
X50742Y272725D01*
X50450Y272683D01*
X50075Y272517D01*
X50200Y273600D01*
X51325D01*
G01X44167Y257300D02*
Y259800D01*
X45208D01*
X45542Y259675D01*
X45750Y259508D01*
X45833Y259175D01*
X45750Y258842D01*
X45500Y258633D01*
X45208Y258508D01*
X44167D01*
G01X45208D02*
X45833Y257300D01*
G01X47917D02*
X48000Y257842D01*
X48125Y258300D01*
X48292Y258717D01*
X48500Y259175D01*
X48833Y259800D01*
X47167D01*
G01X51500Y257300D02*
Y259800D01*
X49958Y258008D01*
X52042D01*
G01X33867Y257500D02*
Y260000D01*
X34908D01*
X35242Y259875D01*
X35450Y259708D01*
X35533Y259375D01*
X35450Y259042D01*
X35200Y258833D01*
X34908Y258708D01*
X33867D01*
G01X34908D02*
X35533Y257500D01*
G01X37617D02*
X37700Y258042D01*
X37825Y258500D01*
X37992Y258917D01*
X38200Y259375D01*
X38533Y260000D01*
X36867D01*
G01X39783Y258000D02*
X40033Y257708D01*
X40367Y257542D01*
X40742Y257500D01*
X41075Y257542D01*
X41408Y257750D01*
X41617Y258000D01*
X41658Y258250D01*
X41575Y258542D01*
X41283Y258750D01*
X40992Y258833D01*
X40617D01*
G01X40992D02*
X41242Y258958D01*
X41450Y259167D01*
X41533Y259417D01*
X41450Y259667D01*
X41242Y259875D01*
X40867Y260000D01*
X40492Y259958D01*
X40117Y259792D01*
G01X43867Y275600D02*
Y278100D01*
X44908D01*
X45242Y277975D01*
X45450Y277808D01*
X45533Y277475D01*
X45450Y277142D01*
X45200Y276933D01*
X44908Y276808D01*
X43867D01*
G01X44908D02*
X45533Y275600D01*
G01X46908Y276642D02*
X47200Y276933D01*
X47450Y277100D01*
X47783Y277183D01*
X48075Y277100D01*
X48283Y276933D01*
X48450Y276683D01*
X48492Y276392D01*
X48450Y276142D01*
X48283Y275892D01*
X48033Y275683D01*
X47742Y275600D01*
X47408Y275683D01*
X47117Y275933D01*
X46950Y276308D01*
X46908Y276725D01*
X46992Y277267D01*
X47117Y277558D01*
X47325Y277850D01*
X47617Y278058D01*
X47908Y278100D01*
X48200Y278017D01*
X48408Y277808D01*
G01X50700Y275600D02*
Y278100D01*
X50200Y277600D01*
G01Y275600D02*
X51200D01*
G01X44267Y253600D02*
Y256100D01*
X45308D01*
X45642Y255975D01*
X45850Y255808D01*
X45933Y255475D01*
X45850Y255142D01*
X45600Y254933D01*
X45308Y254808D01*
X44267D01*
G01X45308D02*
X45933Y253600D01*
G01X47308Y254642D02*
X47600Y254933D01*
X47850Y255100D01*
X48183Y255183D01*
X48475Y255100D01*
X48683Y254933D01*
X48850Y254683D01*
X48892Y254392D01*
X48850Y254142D01*
X48683Y253892D01*
X48433Y253683D01*
X48142Y253600D01*
X47808Y253683D01*
X47517Y253933D01*
X47350Y254308D01*
X47308Y254725D01*
X47392Y255267D01*
X47517Y255558D01*
X47725Y255850D01*
X48017Y256058D01*
X48308Y256100D01*
X48600Y256017D01*
X48808Y255808D01*
G01X51100Y256100D02*
X50767Y256017D01*
X50517Y255808D01*
X50350Y255558D01*
X50225Y255225D01*
X50183Y254850D01*
X50225Y254475D01*
X50350Y254142D01*
X50517Y253892D01*
X50767Y253683D01*
X51100Y253600D01*
X51433Y253683D01*
X51683Y253892D01*
X51850Y254142D01*
X51975Y254475D01*
X52017Y254850D01*
X51975Y255225D01*
X51850Y255558D01*
X51683Y255808D01*
X51433Y256017D01*
X51100Y256100D01*
G01X34067Y250300D02*
Y252800D01*
X35108D01*
X35442Y252675D01*
X35650Y252508D01*
X35733Y252175D01*
X35650Y251842D01*
X35400Y251633D01*
X35108Y251508D01*
X34067D01*
G01X35108D02*
X35733Y250300D01*
G01X36983Y250675D02*
X37233Y250467D01*
X37525Y250342D01*
X37900Y250300D01*
X38275Y250383D01*
X38567Y250550D01*
X38775Y250842D01*
X38817Y251175D01*
X38733Y251508D01*
X38525Y251717D01*
X38233Y251883D01*
X37942Y251925D01*
X37650Y251883D01*
X37275Y251717D01*
X37400Y252800D01*
X38525D01*
G01X40192Y250592D02*
X40483Y250383D01*
X40817Y250300D01*
X41150Y250383D01*
X41442Y250633D01*
X41650Y251008D01*
X41733Y251383D01*
Y251842D01*
X41650Y252217D01*
X41442Y252550D01*
X41192Y252717D01*
X40900Y252800D01*
X40567Y252717D01*
X40317Y252550D01*
X40150Y252300D01*
X40067Y251967D01*
X40150Y251675D01*
X40358Y251383D01*
X40608Y251217D01*
X40900Y251175D01*
X41233Y251258D01*
X41483Y251467D01*
X41733Y251842D01*
G01X44267Y250100D02*
Y252600D01*
X45308D01*
X45642Y252475D01*
X45850Y252308D01*
X45933Y251975D01*
X45850Y251642D01*
X45600Y251433D01*
X45308Y251308D01*
X44267D01*
G01X45308D02*
X45933Y250100D01*
G01X47183Y250475D02*
X47433Y250267D01*
X47725Y250142D01*
X48100Y250100D01*
X48475Y250183D01*
X48767Y250350D01*
X48975Y250642D01*
X49017Y250975D01*
X48933Y251308D01*
X48725Y251517D01*
X48433Y251683D01*
X48142Y251725D01*
X47850Y251683D01*
X47475Y251517D01*
X47600Y252600D01*
X48725D01*
G01X51100Y250100D02*
X51392Y250142D01*
X51725Y250267D01*
X51933Y250475D01*
X52017Y250767D01*
X51933Y251058D01*
X51683Y251308D01*
X51308Y251433D01*
X50892D01*
X50642Y251517D01*
X50433Y251725D01*
X50350Y252017D01*
X50475Y252308D01*
X50767Y252517D01*
X51100Y252600D01*
X51433Y252517D01*
X51725Y252308D01*
X51850Y252017D01*
X51767Y251725D01*
X51558Y251517D01*
X51308Y251433D01*
X50892D01*
X50517Y251308D01*
X50267Y251058D01*
X50183Y250767D01*
X50267Y250475D01*
X50475Y250267D01*
X50808Y250142D01*
X51100Y250100D01*
G01X44367Y245300D02*
Y247800D01*
X45408D01*
X45742Y247675D01*
X45950Y247508D01*
X46033Y247175D01*
X45950Y246842D01*
X45700Y246633D01*
X45408Y246508D01*
X44367D01*
G01X45408D02*
X46033Y245300D01*
G01X47283Y245675D02*
X47533Y245467D01*
X47825Y245342D01*
X48200Y245300D01*
X48575Y245383D01*
X48867Y245550D01*
X49075Y245842D01*
X49117Y246175D01*
X49033Y246508D01*
X48825Y246717D01*
X48533Y246883D01*
X48242Y246925D01*
X47950Y246883D01*
X47575Y246717D01*
X47700Y247800D01*
X48825D01*
G01X51117Y245300D02*
X51200Y245842D01*
X51325Y246300D01*
X51492Y246717D01*
X51700Y247175D01*
X52033Y247800D01*
X50367D01*
G01X34267Y240900D02*
Y243400D01*
X35308D01*
X35642Y243275D01*
X35850Y243108D01*
X35933Y242775D01*
X35850Y242442D01*
X35600Y242233D01*
X35308Y242108D01*
X34267D01*
G01X35308D02*
X35933Y240900D01*
G01X37183Y241275D02*
X37433Y241067D01*
X37725Y240942D01*
X38100Y240900D01*
X38475Y240983D01*
X38767Y241150D01*
X38975Y241442D01*
X39017Y241775D01*
X38933Y242108D01*
X38725Y242317D01*
X38433Y242483D01*
X38142Y242525D01*
X37850Y242483D01*
X37475Y242317D01*
X37600Y243400D01*
X38725D01*
G01X40308Y241942D02*
X40600Y242233D01*
X40850Y242400D01*
X41183Y242483D01*
X41475Y242400D01*
X41683Y242233D01*
X41850Y241983D01*
X41892Y241692D01*
X41850Y241442D01*
X41683Y241192D01*
X41433Y240983D01*
X41142Y240900D01*
X40808Y240983D01*
X40517Y241233D01*
X40350Y241608D01*
X40308Y242025D01*
X40392Y242567D01*
X40517Y242858D01*
X40725Y243150D01*
X41017Y243358D01*
X41308Y243400D01*
X41600Y243317D01*
X41808Y243108D01*
G01X44967Y240800D02*
Y243300D01*
X46008D01*
X46342Y243175D01*
X46550Y243008D01*
X46633Y242675D01*
X46550Y242342D01*
X46300Y242133D01*
X46008Y242008D01*
X44967D01*
G01X46008D02*
X46633Y240800D01*
G01X47883Y241175D02*
X48133Y240967D01*
X48425Y240842D01*
X48800Y240800D01*
X49175Y240883D01*
X49467Y241050D01*
X49675Y241342D01*
X49717Y241675D01*
X49633Y242008D01*
X49425Y242217D01*
X49133Y242383D01*
X48842Y242425D01*
X48550Y242383D01*
X48175Y242217D01*
X48300Y243300D01*
X49425D01*
G01X50883Y241175D02*
X51133Y240967D01*
X51425Y240842D01*
X51800Y240800D01*
X52175Y240883D01*
X52467Y241050D01*
X52675Y241342D01*
X52717Y241675D01*
X52633Y242008D01*
X52425Y242217D01*
X52133Y242383D01*
X51842Y242425D01*
X51550Y242383D01*
X51175Y242217D01*
X51300Y243300D01*
X52425D01*
G01X44967Y236600D02*
Y239100D01*
X46008D01*
X46342Y238975D01*
X46550Y238808D01*
X46633Y238475D01*
X46550Y238142D01*
X46300Y237933D01*
X46008Y237808D01*
X44967D01*
G01X46008D02*
X46633Y236600D01*
G01X47883Y236975D02*
X48133Y236767D01*
X48425Y236642D01*
X48800Y236600D01*
X49175Y236683D01*
X49467Y236850D01*
X49675Y237142D01*
X49717Y237475D01*
X49633Y237808D01*
X49425Y238017D01*
X49133Y238183D01*
X48842Y238225D01*
X48550Y238183D01*
X48175Y238017D01*
X48300Y239100D01*
X49425D01*
G01X52300Y236600D02*
Y239100D01*
X50758Y237308D01*
X52842D01*
G01X41667Y261500D02*
Y264000D01*
X42708D01*
X43042Y263875D01*
X43250Y263708D01*
X43333Y263375D01*
X43250Y263042D01*
X43000Y262833D01*
X42708Y262708D01*
X41667D01*
G01X42708D02*
X43333Y261500D01*
G01X45500D02*
Y264000D01*
X45000Y263500D01*
G01Y261500D02*
X46000D01*
G01X48500Y264000D02*
X48167Y263917D01*
X47917Y263708D01*
X47750Y263458D01*
X47625Y263125D01*
X47583Y262750D01*
X47625Y262375D01*
X47750Y262042D01*
X47917Y261792D01*
X48167Y261583D01*
X48500Y261500D01*
X48833Y261583D01*
X49083Y261792D01*
X49250Y262042D01*
X49375Y262375D01*
X49417Y262750D01*
X49375Y263125D01*
X49250Y263458D01*
X49083Y263708D01*
X48833Y263917D01*
X48500Y264000D01*
G01X50583Y262000D02*
X50833Y261708D01*
X51167Y261542D01*
X51542Y261500D01*
X51875Y261542D01*
X52208Y261750D01*
X52417Y262000D01*
X52458Y262250D01*
X52375Y262542D01*
X52083Y262750D01*
X51792Y262833D01*
X51417D01*
G01X51792D02*
X52042Y262958D01*
X52250Y263167D01*
X52333Y263417D01*
X52250Y263667D01*
X52042Y263875D01*
X51667Y264000D01*
X51292Y263958D01*
X50917Y263792D01*
G01X63267Y222300D02*
Y224800D01*
X64267D01*
X64600Y224675D01*
X64850Y224383D01*
X64933Y224050D01*
X64850Y223717D01*
X64642Y223467D01*
X64267Y223342D01*
X63267D01*
G01X66267Y222300D02*
Y224800D01*
X67308D01*
X67642Y224675D01*
X67850Y224508D01*
X67933Y224175D01*
X67850Y223842D01*
X67600Y223633D01*
X67308Y223508D01*
X66267D01*
G01X67308D02*
X67933Y222300D01*
G01X69308Y223342D02*
X69600Y223633D01*
X69850Y223800D01*
X70183Y223883D01*
X70475Y223800D01*
X70683Y223633D01*
X70850Y223383D01*
X70892Y223092D01*
X70850Y222842D01*
X70683Y222592D01*
X70433Y222383D01*
X70142Y222300D01*
X69808Y222383D01*
X69517Y222633D01*
X69350Y223008D01*
X69308Y223425D01*
X69392Y223967D01*
X69517Y224258D01*
X69725Y224550D01*
X70017Y224758D01*
X70308Y224800D01*
X70600Y224717D01*
X70808Y224508D01*
G01X72308Y223342D02*
X72600Y223633D01*
X72850Y223800D01*
X73183Y223883D01*
X73475Y223800D01*
X73683Y223633D01*
X73850Y223383D01*
X73892Y223092D01*
X73850Y222842D01*
X73683Y222592D01*
X73433Y222383D01*
X73142Y222300D01*
X72808Y222383D01*
X72517Y222633D01*
X72350Y223008D01*
X72308Y223425D01*
X72392Y223967D01*
X72517Y224258D01*
X72725Y224550D01*
X73017Y224758D01*
X73308Y224800D01*
X73600Y224717D01*
X73808Y224508D01*
G01X71700Y244500D02*
X74200D01*
G01X71700Y243542D02*
Y245458D01*
G01X74200Y246667D02*
X71700D01*
Y247667D01*
X71825Y248000D01*
X72117Y248250D01*
X72450Y248333D01*
X72783Y248250D01*
X73033Y248042D01*
X73158Y247667D01*
Y246667D01*
G01X74200Y250500D02*
X71700D01*
X72200Y250000D01*
G01X74200D02*
Y251000D01*
G01X73700Y252583D02*
X73992Y252833D01*
X74158Y253167D01*
X74200Y253542D01*
X74158Y253875D01*
X73950Y254208D01*
X73700Y254417D01*
X73450Y254458D01*
X73158Y254375D01*
X72950Y254083D01*
X72867Y253792D01*
Y253417D01*
G01Y253792D02*
X72742Y254042D01*
X72533Y254250D01*
X72283Y254333D01*
X72033Y254250D01*
X71825Y254042D01*
X71700Y253667D01*
X71742Y253292D01*
X71908Y252917D01*
G01X73700Y255583D02*
X73992Y255833D01*
X74158Y256167D01*
X74200Y256542D01*
X74158Y256875D01*
X73950Y257208D01*
X73700Y257417D01*
X73450Y257458D01*
X73158Y257375D01*
X72950Y257083D01*
X72867Y256792D01*
Y256417D01*
G01Y256792D02*
X72742Y257042D01*
X72533Y257250D01*
X72283Y257333D01*
X72033Y257250D01*
X71825Y257042D01*
X71700Y256667D01*
X71742Y256292D01*
X71908Y255917D01*
G01X43847Y310402D02*
X43722Y310152D01*
X43639Y309860D01*
Y309527D01*
X43764Y309152D01*
X43972Y308860D01*
X44222Y308652D01*
X44639Y308485D01*
X45014Y308443D01*
X45389Y308527D01*
X45639Y308652D01*
X45889Y308902D01*
X46056Y309193D01*
X46139Y309485D01*
Y309777D01*
X46056Y310068D01*
X45931Y310318D01*
X45764Y310527D01*
G01X46139Y311527D02*
X43639D01*
X46139Y313443D01*
X43639D01*
G01X46139Y315485D02*
X46097Y315777D01*
X45972Y316110D01*
X45764Y316318D01*
X45472Y316402D01*
X45181Y316318D01*
X44931Y316068D01*
X44806Y315693D01*
Y315277D01*
X44722Y315027D01*
X44514Y314818D01*
X44222Y314735D01*
X43931Y314860D01*
X43722Y315152D01*
X43639Y315485D01*
X43722Y315818D01*
X43931Y316110D01*
X44222Y316235D01*
X44514Y316152D01*
X44722Y315943D01*
X44806Y315693D01*
Y315277D01*
X44931Y314902D01*
X45181Y314652D01*
X45472Y314568D01*
X45764Y314652D01*
X45972Y314860D01*
X46097Y315193D01*
X46139Y315485D01*
G01X43767Y292700D02*
Y295200D01*
X44808D01*
X45142Y295075D01*
X45350Y294908D01*
X45433Y294575D01*
X45350Y294242D01*
X45100Y294033D01*
X44808Y293908D01*
X43767D01*
G01X44808D02*
X45433Y292700D01*
G01X46808Y293742D02*
X47100Y294033D01*
X47350Y294200D01*
X47683Y294283D01*
X47975Y294200D01*
X48183Y294033D01*
X48350Y293783D01*
X48392Y293492D01*
X48350Y293242D01*
X48183Y292992D01*
X47933Y292783D01*
X47642Y292700D01*
X47308Y292783D01*
X47017Y293033D01*
X46850Y293408D01*
X46808Y293825D01*
X46892Y294367D01*
X47017Y294658D01*
X47225Y294950D01*
X47517Y295158D01*
X47808Y295200D01*
X48100Y295117D01*
X48308Y294908D01*
G01X50600Y292700D02*
X50892Y292742D01*
X51225Y292867D01*
X51433Y293075D01*
X51517Y293367D01*
X51433Y293658D01*
X51183Y293908D01*
X50808Y294033D01*
X50392D01*
X50142Y294117D01*
X49933Y294325D01*
X49850Y294617D01*
X49975Y294908D01*
X50267Y295117D01*
X50600Y295200D01*
X50933Y295117D01*
X51225Y294908D01*
X51350Y294617D01*
X51267Y294325D01*
X51058Y294117D01*
X50808Y294033D01*
X50392D01*
X50017Y293908D01*
X49767Y293658D01*
X49683Y293367D01*
X49767Y293075D01*
X49975Y292867D01*
X50308Y292742D01*
X50600Y292700D01*
G01X43767Y288700D02*
Y291200D01*
X44808D01*
X45142Y291075D01*
X45350Y290908D01*
X45433Y290575D01*
X45350Y290242D01*
X45100Y290033D01*
X44808Y289908D01*
X43767D01*
G01X44808D02*
X45433Y288700D01*
G01X46808Y289742D02*
X47100Y290033D01*
X47350Y290200D01*
X47683Y290283D01*
X47975Y290200D01*
X48183Y290033D01*
X48350Y289783D01*
X48392Y289492D01*
X48350Y289242D01*
X48183Y288992D01*
X47933Y288783D01*
X47642Y288700D01*
X47308Y288783D01*
X47017Y289033D01*
X46850Y289408D01*
X46808Y289825D01*
X46892Y290367D01*
X47017Y290658D01*
X47225Y290950D01*
X47517Y291158D01*
X47808Y291200D01*
X48100Y291117D01*
X48308Y290908D01*
G01X50517Y288700D02*
X50600Y289242D01*
X50725Y289700D01*
X50892Y290117D01*
X51100Y290575D01*
X51433Y291200D01*
X49767D01*
G01X32867Y283700D02*
Y286200D01*
X33908D01*
X34242Y286075D01*
X34450Y285908D01*
X34533Y285575D01*
X34450Y285242D01*
X34200Y285033D01*
X33908Y284908D01*
X32867D01*
G01X33908D02*
X34533Y283700D01*
G01X35908Y284742D02*
X36200Y285033D01*
X36450Y285200D01*
X36783Y285283D01*
X37075Y285200D01*
X37283Y285033D01*
X37450Y284783D01*
X37492Y284492D01*
X37450Y284242D01*
X37283Y283992D01*
X37033Y283783D01*
X36742Y283700D01*
X36408Y283783D01*
X36117Y284033D01*
X35950Y284408D01*
X35908Y284825D01*
X35992Y285367D01*
X36117Y285658D01*
X36325Y285950D01*
X36617Y286158D01*
X36908Y286200D01*
X37200Y286117D01*
X37408Y285908D01*
G01X38908Y284742D02*
X39200Y285033D01*
X39450Y285200D01*
X39783Y285283D01*
X40075Y285200D01*
X40283Y285033D01*
X40450Y284783D01*
X40492Y284492D01*
X40450Y284242D01*
X40283Y283992D01*
X40033Y283783D01*
X39742Y283700D01*
X39408Y283783D01*
X39117Y284033D01*
X38950Y284408D01*
X38908Y284825D01*
X38992Y285367D01*
X39117Y285658D01*
X39325Y285950D01*
X39617Y286158D01*
X39908Y286200D01*
X40200Y286117D01*
X40408Y285908D01*
G01X43667Y283700D02*
Y286200D01*
X44708D01*
X45042Y286075D01*
X45250Y285908D01*
X45333Y285575D01*
X45250Y285242D01*
X45000Y285033D01*
X44708Y284908D01*
X43667D01*
G01X44708D02*
X45333Y283700D01*
G01X46708Y284742D02*
X47000Y285033D01*
X47250Y285200D01*
X47583Y285283D01*
X47875Y285200D01*
X48083Y285033D01*
X48250Y284783D01*
X48292Y284492D01*
X48250Y284242D01*
X48083Y283992D01*
X47833Y283783D01*
X47542Y283700D01*
X47208Y283783D01*
X46917Y284033D01*
X46750Y284408D01*
X46708Y284825D01*
X46792Y285367D01*
X46917Y285658D01*
X47125Y285950D01*
X47417Y286158D01*
X47708Y286200D01*
X48000Y286117D01*
X48208Y285908D01*
G01X49583Y284075D02*
X49833Y283867D01*
X50125Y283742D01*
X50500Y283700D01*
X50875Y283783D01*
X51167Y283950D01*
X51375Y284242D01*
X51417Y284575D01*
X51333Y284908D01*
X51125Y285117D01*
X50833Y285283D01*
X50542Y285325D01*
X50250Y285283D01*
X49875Y285117D01*
X50000Y286200D01*
X51125D01*
G01X43667Y279700D02*
Y282200D01*
X44708D01*
X45042Y282075D01*
X45250Y281908D01*
X45333Y281575D01*
X45250Y281242D01*
X45000Y281033D01*
X44708Y280908D01*
X43667D01*
G01X44708D02*
X45333Y279700D01*
G01X46708Y280742D02*
X47000Y281033D01*
X47250Y281200D01*
X47583Y281283D01*
X47875Y281200D01*
X48083Y281033D01*
X48250Y280783D01*
X48292Y280492D01*
X48250Y280242D01*
X48083Y279992D01*
X47833Y279783D01*
X47542Y279700D01*
X47208Y279783D01*
X46917Y280033D01*
X46750Y280408D01*
X46708Y280825D01*
X46792Y281367D01*
X46917Y281658D01*
X47125Y281950D01*
X47417Y282158D01*
X47708Y282200D01*
X48000Y282117D01*
X48208Y281908D01*
G01X51000Y279700D02*
Y282200D01*
X49458Y280408D01*
X51542D01*
G01X32867Y276000D02*
Y278500D01*
X33908D01*
X34242Y278375D01*
X34450Y278208D01*
X34533Y277875D01*
X34450Y277542D01*
X34200Y277333D01*
X33908Y277208D01*
X32867D01*
G01X33908D02*
X34533Y276000D01*
G01X35908Y277042D02*
X36200Y277333D01*
X36450Y277500D01*
X36783Y277583D01*
X37075Y277500D01*
X37283Y277333D01*
X37450Y277083D01*
X37492Y276792D01*
X37450Y276542D01*
X37283Y276292D01*
X37033Y276083D01*
X36742Y276000D01*
X36408Y276083D01*
X36117Y276333D01*
X35950Y276708D01*
X35908Y277125D01*
X35992Y277667D01*
X36117Y277958D01*
X36325Y278250D01*
X36617Y278458D01*
X36908Y278500D01*
X37200Y278417D01*
X37408Y278208D01*
G01X38783Y276500D02*
X39033Y276208D01*
X39367Y276042D01*
X39742Y276000D01*
X40075Y276042D01*
X40408Y276250D01*
X40617Y276500D01*
X40658Y276750D01*
X40575Y277042D01*
X40283Y277250D01*
X39992Y277333D01*
X39617D01*
G01X39992D02*
X40242Y277458D01*
X40450Y277667D01*
X40533Y277917D01*
X40450Y278167D01*
X40242Y278375D01*
X39867Y278500D01*
X39492Y278458D01*
X39117Y278292D01*
G01X41900Y371767D02*
X39400D01*
Y372808D01*
X39525Y373142D01*
X39692Y373350D01*
X40025Y373433D01*
X40358Y373350D01*
X40567Y373100D01*
X40692Y372808D01*
Y371767D01*
G01Y372808D02*
X41900Y373433D01*
G01Y376100D02*
X39400D01*
X41192Y374558D01*
Y376642D01*
G01X41400Y377683D02*
X41692Y377933D01*
X41858Y378267D01*
X41900Y378642D01*
X41858Y378975D01*
X41650Y379308D01*
X41400Y379517D01*
X41150Y379558D01*
X40858Y379475D01*
X40650Y379183D01*
X40567Y378892D01*
Y378517D01*
G01Y378892D02*
X40442Y379142D01*
X40233Y379350D01*
X39983Y379433D01*
X39733Y379350D01*
X39525Y379142D01*
X39400Y378767D01*
X39442Y378392D01*
X39608Y378017D01*
G01X34600Y392367D02*
X32100D01*
Y393408D01*
X32225Y393742D01*
X32392Y393950D01*
X32725Y394033D01*
X33058Y393950D01*
X33267Y393700D01*
X33392Y393408D01*
Y392367D01*
G01Y393408D02*
X34600Y394033D01*
G01Y396117D02*
X34058Y396200D01*
X33600Y396325D01*
X33183Y396492D01*
X32725Y396700D01*
X32100Y397033D01*
Y395367D01*
G01Y399200D02*
X32183Y398867D01*
X32392Y398617D01*
X32642Y398450D01*
X32975Y398325D01*
X33350Y398283D01*
X33725Y398325D01*
X34058Y398450D01*
X34308Y398617D01*
X34517Y398867D01*
X34600Y399200D01*
X34517Y399533D01*
X34308Y399783D01*
X34058Y399950D01*
X33725Y400075D01*
X33350Y400117D01*
X32975Y400075D01*
X32642Y399950D01*
X32392Y399783D01*
X32183Y399533D01*
X32100Y399200D01*
G01X38400Y371767D02*
X35900D01*
Y372808D01*
X36025Y373142D01*
X36192Y373350D01*
X36525Y373433D01*
X36858Y373350D01*
X37067Y373100D01*
X37192Y372808D01*
Y371767D01*
G01Y372808D02*
X38400Y373433D01*
G01Y376100D02*
X35900D01*
X37692Y374558D01*
Y376642D01*
G01X36317Y377808D02*
X36067Y378058D01*
X35942Y378350D01*
X35900Y378683D01*
X35983Y379100D01*
X36192Y379392D01*
X36442Y379475D01*
X36692Y379433D01*
X36900Y379267D01*
X37317Y378433D01*
X37608Y378058D01*
X38025Y377808D01*
X38400Y377725D01*
Y379475D01*
G01X67130Y357876D02*
X64630D01*
Y358917D01*
X64755Y359251D01*
X64922Y359459D01*
X65255Y359542D01*
X65588Y359459D01*
X65797Y359209D01*
X65922Y358917D01*
Y357876D01*
G01Y358917D02*
X67130Y359542D01*
G01Y362209D02*
X64630D01*
X66422Y360667D01*
Y362751D01*
G01X64630Y364709D02*
X64713Y364376D01*
X64922Y364126D01*
X65172Y363959D01*
X65505Y363834D01*
X65880Y363792D01*
X66255Y363834D01*
X66588Y363959D01*
X66838Y364126D01*
X67047Y364376D01*
X67130Y364709D01*
X67047Y365042D01*
X66838Y365292D01*
X66588Y365459D01*
X66255Y365584D01*
X65880Y365626D01*
X65505Y365584D01*
X65172Y365459D01*
X64922Y365292D01*
X64713Y365042D01*
X64630Y364709D01*
G01X38200Y392467D02*
X35700D01*
Y393508D01*
X35825Y393842D01*
X35992Y394050D01*
X36325Y394133D01*
X36658Y394050D01*
X36867Y393800D01*
X36992Y393508D01*
Y392467D01*
G01Y393508D02*
X38200Y394133D01*
G01X37700Y395383D02*
X37992Y395633D01*
X38158Y395967D01*
X38200Y396342D01*
X38158Y396675D01*
X37950Y397008D01*
X37700Y397217D01*
X37450Y397258D01*
X37158Y397175D01*
X36950Y396883D01*
X36867Y396592D01*
Y396217D01*
G01Y396592D02*
X36742Y396842D01*
X36533Y397050D01*
X36283Y397133D01*
X36033Y397050D01*
X35825Y396842D01*
X35700Y396467D01*
X35742Y396092D01*
X35908Y395717D01*
G01X36117Y398508D02*
X35867Y398758D01*
X35742Y399050D01*
X35700Y399383D01*
X35783Y399800D01*
X35992Y400092D01*
X36242Y400175D01*
X36492Y400133D01*
X36700Y399967D01*
X37117Y399133D01*
X37408Y398758D01*
X37825Y398508D01*
X38200Y398425D01*
Y400175D01*
G01X38300Y381967D02*
X35800D01*
Y383008D01*
X35925Y383342D01*
X36092Y383550D01*
X36425Y383633D01*
X36758Y383550D01*
X36967Y383300D01*
X37092Y383008D01*
Y381967D01*
G01Y383008D02*
X38300Y383633D01*
G01X36217Y385008D02*
X35967Y385258D01*
X35842Y385550D01*
X35800Y385883D01*
X35883Y386300D01*
X36092Y386592D01*
X36342Y386675D01*
X36592Y386633D01*
X36800Y386467D01*
X37217Y385633D01*
X37508Y385258D01*
X37925Y385008D01*
X38300Y384925D01*
Y386675D01*
G01X36217Y388008D02*
X35967Y388258D01*
X35842Y388550D01*
X35800Y388883D01*
X35883Y389300D01*
X36092Y389592D01*
X36342Y389675D01*
X36592Y389633D01*
X36800Y389467D01*
X37217Y388633D01*
X37508Y388258D01*
X37925Y388008D01*
X38300Y387925D01*
Y389675D01*
G01X34500Y381967D02*
X32000D01*
Y383008D01*
X32125Y383342D01*
X32292Y383550D01*
X32625Y383633D01*
X32958Y383550D01*
X33167Y383300D01*
X33292Y383008D01*
Y381967D01*
G01Y383008D02*
X34500Y383633D01*
G01X33458Y385008D02*
X33167Y385300D01*
X33000Y385550D01*
X32917Y385883D01*
X33000Y386175D01*
X33167Y386383D01*
X33417Y386550D01*
X33708Y386592D01*
X33958Y386550D01*
X34208Y386383D01*
X34417Y386133D01*
X34500Y385842D01*
X34417Y385508D01*
X34167Y385217D01*
X33792Y385050D01*
X33375Y385008D01*
X32833Y385092D01*
X32542Y385217D01*
X32250Y385425D01*
X32042Y385717D01*
X32000Y386008D01*
X32083Y386300D01*
X32292Y386508D01*
G01X32417Y388008D02*
X32167Y388258D01*
X32042Y388550D01*
X32000Y388883D01*
X32083Y389300D01*
X32292Y389592D01*
X32542Y389675D01*
X32792Y389633D01*
X33000Y389467D01*
X33417Y388633D01*
X33708Y388258D01*
X34125Y388008D01*
X34500Y387925D01*
Y389675D01*
G01X40567Y367600D02*
Y370100D01*
X41608D01*
X41942Y369975D01*
X42150Y369808D01*
X42233Y369475D01*
X42150Y369142D01*
X41900Y368933D01*
X41608Y368808D01*
X40567D01*
G01X41608D02*
X42233Y367600D01*
G01X43483Y368100D02*
X43733Y367808D01*
X44067Y367642D01*
X44442Y367600D01*
X44775Y367642D01*
X45108Y367850D01*
X45317Y368100D01*
X45358Y368350D01*
X45275Y368642D01*
X44983Y368850D01*
X44692Y368933D01*
X44317D01*
G01X44692D02*
X44942Y369058D01*
X45150Y369267D01*
X45233Y369517D01*
X45150Y369767D01*
X44942Y369975D01*
X44567Y370100D01*
X44192Y370058D01*
X43817Y369892D01*
G01X46608Y368642D02*
X46900Y368933D01*
X47150Y369100D01*
X47483Y369183D01*
X47775Y369100D01*
X47983Y368933D01*
X48150Y368683D01*
X48192Y368392D01*
X48150Y368142D01*
X47983Y367892D01*
X47733Y367683D01*
X47442Y367600D01*
X47108Y367683D01*
X46817Y367933D01*
X46650Y368308D01*
X46608Y368725D01*
X46692Y369267D01*
X46817Y369558D01*
X47025Y369850D01*
X47317Y370058D01*
X47608Y370100D01*
X47900Y370017D01*
X48108Y369808D01*
G01X62634Y357967D02*
X60134D01*
Y359008D01*
X60259Y359342D01*
X60426Y359550D01*
X60759Y359633D01*
X61092Y359550D01*
X61301Y359300D01*
X61426Y359008D01*
Y357967D01*
G01Y359008D02*
X62634Y359633D01*
G01X62134Y360883D02*
X62426Y361133D01*
X62592Y361467D01*
X62634Y361842D01*
X62592Y362175D01*
X62384Y362508D01*
X62134Y362717D01*
X61884Y362758D01*
X61592Y362675D01*
X61384Y362383D01*
X61301Y362092D01*
Y361717D01*
G01Y362092D02*
X61176Y362342D01*
X60967Y362550D01*
X60717Y362633D01*
X60467Y362550D01*
X60259Y362342D01*
X60134Y361967D01*
X60176Y361592D01*
X60342Y361217D01*
G01X62259Y363883D02*
X62467Y364133D01*
X62592Y364425D01*
X62634Y364800D01*
X62551Y365175D01*
X62384Y365467D01*
X62092Y365675D01*
X61759Y365717D01*
X61426Y365633D01*
X61217Y365425D01*
X61051Y365133D01*
X61009Y364842D01*
X61051Y364550D01*
X61217Y364175D01*
X60134Y364300D01*
Y365425D01*
G01X55100Y404600D02*
X57600D01*
G01X55100Y403642D02*
Y405558D01*
G01X57600Y406767D02*
X55100D01*
Y407767D01*
X55225Y408100D01*
X55517Y408350D01*
X55850Y408433D01*
X56183Y408350D01*
X56433Y408142D01*
X56558Y407767D01*
Y406767D01*
G01X57308Y409892D02*
X57517Y410183D01*
X57600Y410517D01*
X57517Y410850D01*
X57267Y411142D01*
X56892Y411350D01*
X56517Y411433D01*
X56058D01*
X55683Y411350D01*
X55350Y411142D01*
X55183Y410892D01*
X55100Y410600D01*
X55183Y410267D01*
X55350Y410017D01*
X55600Y409850D01*
X55933Y409767D01*
X56225Y409850D01*
X56517Y410058D01*
X56683Y410308D01*
X56725Y410600D01*
X56642Y410933D01*
X56433Y411183D01*
X56058Y411433D01*
G01X57600Y413517D02*
X57058Y413600D01*
X56600Y413725D01*
X56183Y413892D01*
X55725Y414100D01*
X55100Y414433D01*
Y412767D01*
G01X46600Y404000D02*
X49100D01*
G01X46600Y403042D02*
Y404958D01*
G01X49100Y406167D02*
X46600D01*
Y407167D01*
X46725Y407500D01*
X47017Y407750D01*
X47350Y407833D01*
X47683Y407750D01*
X47933Y407542D01*
X48058Y407167D01*
Y406167D01*
G01X49100Y410000D02*
X46600D01*
X47100Y409500D01*
G01X49100D02*
Y410500D01*
G01X46600Y413000D02*
X46683Y412667D01*
X46892Y412417D01*
X47142Y412250D01*
X47475Y412125D01*
X47850Y412083D01*
X48225Y412125D01*
X48558Y412250D01*
X48808Y412417D01*
X49017Y412667D01*
X49100Y413000D01*
X49017Y413333D01*
X48808Y413583D01*
X48558Y413750D01*
X48225Y413875D01*
X47850Y413917D01*
X47475Y413875D01*
X47142Y413750D01*
X46892Y413583D01*
X46683Y413333D01*
X46600Y413000D01*
G01X48600Y415083D02*
X48892Y415333D01*
X49058Y415667D01*
X49100Y416042D01*
X49058Y416375D01*
X48850Y416708D01*
X48600Y416917D01*
X48350Y416958D01*
X48058Y416875D01*
X47850Y416583D01*
X47767Y416292D01*
Y415917D01*
G01Y416292D02*
X47642Y416542D01*
X47433Y416750D01*
X47183Y416833D01*
X46933Y416750D01*
X46725Y416542D01*
X46600Y416167D01*
X46642Y415792D01*
X46808Y415417D01*
G01X28200Y392900D02*
X30700D01*
G01X28200Y391942D02*
Y393858D01*
G01X30700Y395067D02*
X28200D01*
Y396067D01*
X28325Y396400D01*
X28617Y396650D01*
X28950Y396733D01*
X29283Y396650D01*
X29533Y396442D01*
X29658Y396067D01*
Y395067D01*
G01X30700Y398900D02*
X28200D01*
X28700Y398400D01*
G01X30700D02*
Y399400D01*
G01X28200Y401900D02*
X28283Y401567D01*
X28492Y401317D01*
X28742Y401150D01*
X29075Y401025D01*
X29450Y400983D01*
X29825Y401025D01*
X30158Y401150D01*
X30408Y401317D01*
X30617Y401567D01*
X30700Y401900D01*
X30617Y402233D01*
X30408Y402483D01*
X30158Y402650D01*
X29825Y402775D01*
X29450Y402817D01*
X29075Y402775D01*
X28742Y402650D01*
X28492Y402483D01*
X28283Y402233D01*
X28200Y401900D01*
G01X30700Y405400D02*
X28200D01*
X29992Y403858D01*
Y405942D01*
G01X75400Y369400D02*
X77900D01*
G01X75400Y368442D02*
Y370358D01*
G01X77900Y371567D02*
X75400D01*
Y372567D01*
X75525Y372900D01*
X75817Y373150D01*
X76150Y373233D01*
X76483Y373150D01*
X76733Y372942D01*
X76858Y372567D01*
Y371567D01*
G01X77900Y375317D02*
X77358Y375400D01*
X76900Y375525D01*
X76483Y375692D01*
X76025Y375900D01*
X75400Y376233D01*
Y374567D01*
G01X77400Y377483D02*
X77692Y377733D01*
X77858Y378067D01*
X77900Y378442D01*
X77858Y378775D01*
X77650Y379108D01*
X77400Y379317D01*
X77150Y379358D01*
X76858Y379275D01*
X76650Y378983D01*
X76567Y378692D01*
Y378317D01*
G01Y378692D02*
X76442Y378942D01*
X76233Y379150D01*
X75983Y379233D01*
X75733Y379150D01*
X75525Y378942D01*
X75400Y378567D01*
X75442Y378192D01*
X75608Y377817D01*
G01X23717Y474292D02*
X23467Y474417D01*
X23175Y474500D01*
X22842D01*
X22467Y474375D01*
X22175Y474167D01*
X21967Y473917D01*
X21800Y473500D01*
X21758Y473125D01*
X21842Y472750D01*
X21967Y472500D01*
X22217Y472250D01*
X22508Y472083D01*
X22800Y472000D01*
X23092D01*
X23383Y472083D01*
X23633Y472208D01*
X23842Y472375D01*
G01X25800Y472000D02*
Y474500D01*
X25300Y474000D01*
G01Y472000D02*
X26300D01*
G01X27883Y472375D02*
X28133Y472167D01*
X28425Y472042D01*
X28800Y472000D01*
X29175Y472083D01*
X29467Y472250D01*
X29675Y472542D01*
X29717Y472875D01*
X29633Y473208D01*
X29425Y473417D01*
X29133Y473583D01*
X28842Y473625D01*
X28550Y473583D01*
X28175Y473417D01*
X28300Y474500D01*
X29425D01*
G01X31008Y474083D02*
X31258Y474333D01*
X31550Y474458D01*
X31883Y474500D01*
X32300Y474417D01*
X32592Y474208D01*
X32675Y473958D01*
X32633Y473708D01*
X32467Y473500D01*
X31633Y473083D01*
X31258Y472792D01*
X31008Y472375D01*
X30925Y472000D01*
X32675D01*
G01X23917Y469892D02*
X23667Y470017D01*
X23375Y470100D01*
X23042D01*
X22667Y469975D01*
X22375Y469767D01*
X22167Y469517D01*
X22000Y469100D01*
X21958Y468725D01*
X22042Y468350D01*
X22167Y468100D01*
X22417Y467850D01*
X22708Y467683D01*
X23000Y467600D01*
X23292D01*
X23583Y467683D01*
X23833Y467808D01*
X24042Y467975D01*
G01X26000Y467600D02*
Y470100D01*
X25500Y469600D01*
G01Y467600D02*
X26500D01*
G01X28083Y467975D02*
X28333Y467767D01*
X28625Y467642D01*
X29000Y467600D01*
X29375Y467683D01*
X29667Y467850D01*
X29875Y468142D01*
X29917Y468475D01*
X29833Y468808D01*
X29625Y469017D01*
X29333Y469183D01*
X29042Y469225D01*
X28750Y469183D01*
X28375Y469017D01*
X28500Y470100D01*
X29625D01*
G01X31083Y468100D02*
X31333Y467808D01*
X31667Y467642D01*
X32042Y467600D01*
X32375Y467642D01*
X32708Y467850D01*
X32917Y468100D01*
X32958Y468350D01*
X32875Y468642D01*
X32583Y468850D01*
X32292Y468933D01*
X31917D01*
G01X32292D02*
X32542Y469058D01*
X32750Y469267D01*
X32833Y469517D01*
X32750Y469767D01*
X32542Y469975D01*
X32167Y470100D01*
X31792Y470058D01*
X31417Y469892D01*
G01X23917Y466292D02*
X23667Y466417D01*
X23375Y466500D01*
X23042D01*
X22667Y466375D01*
X22375Y466167D01*
X22167Y465917D01*
X22000Y465500D01*
X21958Y465125D01*
X22042Y464750D01*
X22167Y464500D01*
X22417Y464250D01*
X22708Y464083D01*
X23000Y464000D01*
X23292D01*
X23583Y464083D01*
X23833Y464208D01*
X24042Y464375D01*
G01X26000Y464000D02*
Y466500D01*
X25500Y466000D01*
G01Y464000D02*
X26500D01*
G01X28083Y464375D02*
X28333Y464167D01*
X28625Y464042D01*
X29000Y464000D01*
X29375Y464083D01*
X29667Y464250D01*
X29875Y464542D01*
X29917Y464875D01*
X29833Y465208D01*
X29625Y465417D01*
X29333Y465583D01*
X29042Y465625D01*
X28750Y465583D01*
X28375Y465417D01*
X28500Y466500D01*
X29625D01*
G01X32500Y464000D02*
Y466500D01*
X30958Y464708D01*
X33042D01*
G01X23917Y462792D02*
X23667Y462917D01*
X23375Y463000D01*
X23042D01*
X22667Y462875D01*
X22375Y462667D01*
X22167Y462417D01*
X22000Y462000D01*
X21958Y461625D01*
X22042Y461250D01*
X22167Y461000D01*
X22417Y460750D01*
X22708Y460583D01*
X23000Y460500D01*
X23292D01*
X23583Y460583D01*
X23833Y460708D01*
X24042Y460875D01*
G01X26000Y460500D02*
Y463000D01*
X25500Y462500D01*
G01Y460500D02*
X26500D01*
G01X28083Y460875D02*
X28333Y460667D01*
X28625Y460542D01*
X29000Y460500D01*
X29375Y460583D01*
X29667Y460750D01*
X29875Y461042D01*
X29917Y461375D01*
X29833Y461708D01*
X29625Y461917D01*
X29333Y462083D01*
X29042Y462125D01*
X28750Y462083D01*
X28375Y461917D01*
X28500Y463000D01*
X29625D01*
G01X31083Y460875D02*
X31333Y460667D01*
X31625Y460542D01*
X32000Y460500D01*
X32375Y460583D01*
X32667Y460750D01*
X32875Y461042D01*
X32917Y461375D01*
X32833Y461708D01*
X32625Y461917D01*
X32333Y462083D01*
X32042Y462125D01*
X31750Y462083D01*
X31375Y461917D01*
X31500Y463000D01*
X32625D01*
G01X54800Y483900D02*
X57300D01*
G01X54800Y482942D02*
Y484858D01*
G01X57300Y486067D02*
X54800D01*
Y487067D01*
X54925Y487400D01*
X55217Y487650D01*
X55550Y487733D01*
X55883Y487650D01*
X56133Y487442D01*
X56258Y487067D01*
Y486067D01*
G01X57300Y489900D02*
X54800D01*
X55300Y489400D01*
G01X57300D02*
Y490400D01*
G01Y492900D02*
X54800D01*
X55300Y492400D01*
G01X57300D02*
Y493400D01*
G01X55217Y495108D02*
X54967Y495358D01*
X54842Y495650D01*
X54800Y495983D01*
X54883Y496400D01*
X55092Y496692D01*
X55342Y496775D01*
X55592Y496733D01*
X55800Y496567D01*
X56217Y495733D01*
X56508Y495358D01*
X56925Y495108D01*
X57300Y495025D01*
Y496775D01*
G01X39433Y487819D02*
Y485319D01*
G01X38475Y487819D02*
X40391D01*
G01X41600Y485319D02*
Y487819D01*
X42600D01*
X42933Y487694D01*
X43183Y487402D01*
X43266Y487069D01*
X43183Y486736D01*
X42975Y486486D01*
X42600Y486361D01*
X41600D01*
G01X45433Y485319D02*
Y487819D01*
X44933Y487319D01*
G01Y485319D02*
X45933D01*
G01X48433D02*
Y487819D01*
X47933Y487319D01*
G01Y485319D02*
X48933D01*
G01X50516Y485694D02*
X50766Y485486D01*
X51058Y485361D01*
X51433Y485319D01*
X51808Y485402D01*
X52100Y485569D01*
X52308Y485861D01*
X52350Y486194D01*
X52266Y486527D01*
X52058Y486736D01*
X51766Y486902D01*
X51475Y486944D01*
X51183Y486902D01*
X50808Y486736D01*
X50933Y487819D01*
X52058D01*
G01X39974Y479530D02*
Y477030D01*
G01X39016Y479530D02*
X40932D01*
G01X42141Y477030D02*
Y479530D01*
X43141D01*
X43474Y479405D01*
X43724Y479113D01*
X43807Y478780D01*
X43724Y478447D01*
X43516Y478197D01*
X43141Y478072D01*
X42141D01*
G01X45182Y479113D02*
X45432Y479363D01*
X45724Y479488D01*
X46057Y479530D01*
X46474Y479447D01*
X46766Y479238D01*
X46849Y478988D01*
X46807Y478738D01*
X46641Y478530D01*
X45807Y478113D01*
X45432Y477822D01*
X45182Y477405D01*
X45099Y477030D01*
X46849D01*
G01X76160Y534236D02*
X76035Y533986D01*
X75952Y533694D01*
Y533361D01*
X76077Y532986D01*
X76285Y532694D01*
X76535Y532486D01*
X76952Y532319D01*
X77327Y532277D01*
X77702Y532361D01*
X77952Y532486D01*
X78202Y532736D01*
X78369Y533027D01*
X78452Y533319D01*
Y533611D01*
X78369Y533902D01*
X78244Y534152D01*
X78077Y534361D01*
G01Y535402D02*
X78285Y535652D01*
X78410Y535944D01*
X78452Y536319D01*
X78369Y536694D01*
X78202Y536986D01*
X77910Y537194D01*
X77577Y537236D01*
X77244Y537152D01*
X77035Y536944D01*
X76869Y536652D01*
X76827Y536361D01*
X76869Y536069D01*
X77035Y535694D01*
X75952Y535819D01*
Y536944D01*
G01X78452Y539319D02*
X75952D01*
X76452Y538819D01*
G01X78452D02*
Y539819D01*
G01X69502Y539440D02*
X69377Y539190D01*
X69294Y538898D01*
Y538565D01*
X69419Y538190D01*
X69627Y537898D01*
X69877Y537690D01*
X70294Y537523D01*
X70669Y537481D01*
X71044Y537565D01*
X71294Y537690D01*
X71544Y537940D01*
X71711Y538231D01*
X71794Y538523D01*
Y538815D01*
X71711Y539106D01*
X71586Y539356D01*
X71419Y539565D01*
G01Y540606D02*
X71627Y540856D01*
X71752Y541148D01*
X71794Y541523D01*
X71711Y541898D01*
X71544Y542190D01*
X71252Y542398D01*
X70919Y542440D01*
X70586Y542356D01*
X70377Y542148D01*
X70211Y541856D01*
X70169Y541565D01*
X70211Y541273D01*
X70377Y540898D01*
X69294Y541023D01*
Y542148D01*
G01X69711Y543731D02*
X69461Y543981D01*
X69336Y544273D01*
X69294Y544606D01*
X69377Y545023D01*
X69586Y545315D01*
X69836Y545398D01*
X70086Y545356D01*
X70294Y545190D01*
X70711Y544356D01*
X71002Y543981D01*
X71419Y543731D01*
X71794Y543648D01*
Y545398D01*
G01X65443Y539521D02*
X65318Y539271D01*
X65235Y538979D01*
Y538646D01*
X65360Y538271D01*
X65568Y537979D01*
X65818Y537771D01*
X66235Y537604D01*
X66610Y537562D01*
X66985Y537646D01*
X67235Y537771D01*
X67485Y538021D01*
X67652Y538312D01*
X67735Y538604D01*
Y538896D01*
X67652Y539187D01*
X67527Y539437D01*
X67360Y539646D01*
G01Y540687D02*
X67568Y540937D01*
X67693Y541229D01*
X67735Y541604D01*
X67652Y541979D01*
X67485Y542271D01*
X67193Y542479D01*
X66860Y542521D01*
X66527Y542437D01*
X66318Y542229D01*
X66152Y541937D01*
X66110Y541646D01*
X66152Y541354D01*
X66318Y540979D01*
X65235Y541104D01*
Y542229D01*
G01X67235Y543687D02*
X67527Y543937D01*
X67693Y544271D01*
X67735Y544646D01*
X67693Y544979D01*
X67485Y545312D01*
X67235Y545521D01*
X66985Y545562D01*
X66693Y545479D01*
X66485Y545187D01*
X66402Y544896D01*
Y544521D01*
G01Y544896D02*
X66277Y545146D01*
X66068Y545354D01*
X65818Y545437D01*
X65568Y545354D01*
X65360Y545146D01*
X65235Y544771D01*
X65277Y544396D01*
X65443Y544021D01*
G01X56337Y542107D02*
X56212Y541857D01*
X56129Y541565D01*
Y541232D01*
X56254Y540857D01*
X56462Y540565D01*
X56712Y540357D01*
X57129Y540190D01*
X57504Y540148D01*
X57879Y540232D01*
X58129Y540357D01*
X58379Y540607D01*
X58546Y540898D01*
X58629Y541190D01*
Y541482D01*
X58546Y541773D01*
X58421Y542023D01*
X58254Y542232D01*
G01Y543273D02*
X58462Y543523D01*
X58587Y543815D01*
X58629Y544190D01*
X58546Y544565D01*
X58379Y544857D01*
X58087Y545065D01*
X57754Y545107D01*
X57421Y545023D01*
X57212Y544815D01*
X57046Y544523D01*
X57004Y544232D01*
X57046Y543940D01*
X57212Y543565D01*
X56129Y543690D01*
Y544815D01*
G01X58629Y547690D02*
X56129D01*
X57921Y546148D01*
Y548232D01*
G01X51953Y542107D02*
X51828Y541857D01*
X51745Y541565D01*
Y541232D01*
X51870Y540857D01*
X52078Y540565D01*
X52328Y540357D01*
X52745Y540190D01*
X53120Y540148D01*
X53495Y540232D01*
X53745Y540357D01*
X53995Y540607D01*
X54162Y540898D01*
X54245Y541190D01*
Y541482D01*
X54162Y541773D01*
X54037Y542023D01*
X53870Y542232D01*
G01Y543273D02*
X54078Y543523D01*
X54203Y543815D01*
X54245Y544190D01*
X54162Y544565D01*
X53995Y544857D01*
X53703Y545065D01*
X53370Y545107D01*
X53037Y545023D01*
X52828Y544815D01*
X52662Y544523D01*
X52620Y544232D01*
X52662Y543940D01*
X52828Y543565D01*
X51745Y543690D01*
Y544815D01*
G01X53870Y546273D02*
X54078Y546523D01*
X54203Y546815D01*
X54245Y547190D01*
X54162Y547565D01*
X53995Y547857D01*
X53703Y548065D01*
X53370Y548107D01*
X53037Y548023D01*
X52828Y547815D01*
X52662Y547523D01*
X52620Y547232D01*
X52662Y546940D01*
X52828Y546565D01*
X51745Y546690D01*
Y547815D01*
G01X40908Y531817D02*
X40783Y531567D01*
X40700Y531275D01*
Y530942D01*
X40825Y530567D01*
X41033Y530275D01*
X41283Y530067D01*
X41700Y529900D01*
X42075Y529858D01*
X42450Y529942D01*
X42700Y530067D01*
X42950Y530317D01*
X43117Y530608D01*
X43200Y530900D01*
Y531192D01*
X43117Y531483D01*
X42992Y531733D01*
X42825Y531942D01*
G01Y532983D02*
X43033Y533233D01*
X43158Y533525D01*
X43200Y533900D01*
X43117Y534275D01*
X42950Y534567D01*
X42658Y534775D01*
X42325Y534817D01*
X41992Y534733D01*
X41783Y534525D01*
X41617Y534233D01*
X41575Y533942D01*
X41617Y533650D01*
X41783Y533275D01*
X40700Y533400D01*
Y534525D01*
G01X42158Y536108D02*
X41867Y536400D01*
X41700Y536650D01*
X41617Y536983D01*
X41700Y537275D01*
X41867Y537483D01*
X42117Y537650D01*
X42408Y537692D01*
X42658Y537650D01*
X42908Y537483D01*
X43117Y537233D01*
X43200Y536942D01*
X43117Y536608D01*
X42867Y536317D01*
X42492Y536150D01*
X42075Y536108D01*
X41533Y536192D01*
X41242Y536317D01*
X40950Y536525D01*
X40742Y536817D01*
X40700Y537108D01*
X40783Y537400D01*
X40992Y537608D01*
G01X36008Y531917D02*
X35883Y531667D01*
X35800Y531375D01*
Y531042D01*
X35925Y530667D01*
X36133Y530375D01*
X36383Y530167D01*
X36800Y530000D01*
X37175Y529958D01*
X37550Y530042D01*
X37800Y530167D01*
X38050Y530417D01*
X38217Y530708D01*
X38300Y531000D01*
Y531292D01*
X38217Y531583D01*
X38092Y531833D01*
X37925Y532042D01*
G01Y533083D02*
X38133Y533333D01*
X38258Y533625D01*
X38300Y534000D01*
X38217Y534375D01*
X38050Y534667D01*
X37758Y534875D01*
X37425Y534917D01*
X37092Y534833D01*
X36883Y534625D01*
X36717Y534333D01*
X36675Y534042D01*
X36717Y533750D01*
X36883Y533375D01*
X35800Y533500D01*
Y534625D01*
G01X38300Y536917D02*
X37758Y537000D01*
X37300Y537125D01*
X36883Y537292D01*
X36425Y537500D01*
X35800Y537833D01*
Y536167D01*
G01X22395Y501951D02*
X19895D01*
Y502992D01*
X20020Y503326D01*
X20187Y503534D01*
X20520Y503617D01*
X20853Y503534D01*
X21062Y503284D01*
X21187Y502992D01*
Y501951D01*
G01Y502992D02*
X22395Y503617D01*
G01X22103Y505076D02*
X22312Y505367D01*
X22395Y505701D01*
X22312Y506034D01*
X22062Y506326D01*
X21687Y506534D01*
X21312Y506617D01*
X20853D01*
X20478Y506534D01*
X20145Y506326D01*
X19978Y506076D01*
X19895Y505784D01*
X19978Y505451D01*
X20145Y505201D01*
X20395Y505034D01*
X20728Y504951D01*
X21020Y505034D01*
X21312Y505242D01*
X21478Y505492D01*
X21520Y505784D01*
X21437Y506117D01*
X21228Y506367D01*
X20853Y506617D01*
G01X22395Y508784D02*
X19895D01*
X20395Y508284D01*
G01X22395D02*
Y509284D01*
G01X68167Y510000D02*
Y507500D01*
X69833D01*
G01X71083Y507875D02*
X71333Y507667D01*
X71625Y507542D01*
X72000Y507500D01*
X72375Y507583D01*
X72667Y507750D01*
X72875Y508042D01*
X72917Y508375D01*
X72833Y508708D01*
X72625Y508917D01*
X72333Y509083D01*
X72042Y509125D01*
X71750Y509083D01*
X71375Y508917D01*
X71500Y510000D01*
X72625D01*
G01X74083Y507875D02*
X74333Y507667D01*
X74625Y507542D01*
X75000Y507500D01*
X75375Y507583D01*
X75667Y507750D01*
X75875Y508042D01*
X75917Y508375D01*
X75833Y508708D01*
X75625Y508917D01*
X75333Y509083D01*
X75042Y509125D01*
X74750Y509083D01*
X74375Y508917D01*
X74500Y510000D01*
X75625D01*
G01X57767Y534500D02*
Y532000D01*
X59433D01*
G01X60683Y532375D02*
X60933Y532167D01*
X61225Y532042D01*
X61600Y532000D01*
X61975Y532083D01*
X62267Y532250D01*
X62475Y532542D01*
X62517Y532875D01*
X62433Y533208D01*
X62225Y533417D01*
X61933Y533583D01*
X61642Y533625D01*
X61350Y533583D01*
X60975Y533417D01*
X61100Y534500D01*
X62225D01*
G01X65100Y532000D02*
Y534500D01*
X63558Y532708D01*
X65642D01*
G01X55467Y538600D02*
Y536100D01*
X57133D01*
G01X58383Y536475D02*
X58633Y536267D01*
X58925Y536142D01*
X59300Y536100D01*
X59675Y536183D01*
X59967Y536350D01*
X60175Y536642D01*
X60217Y536975D01*
X60133Y537308D01*
X59925Y537517D01*
X59633Y537683D01*
X59342Y537725D01*
X59050Y537683D01*
X58675Y537517D01*
X58800Y538600D01*
X59925D01*
G01X61383Y536600D02*
X61633Y536308D01*
X61967Y536142D01*
X62342Y536100D01*
X62675Y536142D01*
X63008Y536350D01*
X63217Y536600D01*
X63258Y536850D01*
X63175Y537142D01*
X62883Y537350D01*
X62592Y537433D01*
X62217D01*
G01X62592D02*
X62842Y537558D01*
X63050Y537767D01*
X63133Y538017D01*
X63050Y538267D01*
X62842Y538475D01*
X62467Y538600D01*
X62092Y538558D01*
X61717Y538392D01*
G01X45567Y531400D02*
Y528900D01*
X47233D01*
G01X48483Y529275D02*
X48733Y529067D01*
X49025Y528942D01*
X49400Y528900D01*
X49775Y528983D01*
X50067Y529150D01*
X50275Y529442D01*
X50317Y529775D01*
X50233Y530108D01*
X50025Y530317D01*
X49733Y530483D01*
X49442Y530525D01*
X49150Y530483D01*
X48775Y530317D01*
X48900Y531400D01*
X50025D01*
G01X51608Y530983D02*
X51858Y531233D01*
X52150Y531358D01*
X52483Y531400D01*
X52900Y531317D01*
X53192Y531108D01*
X53275Y530858D01*
X53233Y530608D01*
X53067Y530400D01*
X52233Y529983D01*
X51858Y529692D01*
X51608Y529275D01*
X51525Y528900D01*
X53275D01*
G01X45967Y514500D02*
Y512000D01*
X47633D01*
G01X48883Y512375D02*
X49133Y512167D01*
X49425Y512042D01*
X49800Y512000D01*
X50175Y512083D01*
X50467Y512250D01*
X50675Y512542D01*
X50717Y512875D01*
X50633Y513208D01*
X50425Y513417D01*
X50133Y513583D01*
X49842Y513625D01*
X49550Y513583D01*
X49175Y513417D01*
X49300Y514500D01*
X50425D01*
G01X52800Y512000D02*
Y514500D01*
X52300Y514000D01*
G01Y512000D02*
X53300D01*
G01X34532Y514182D02*
X37032D01*
Y515848D01*
G01X36657Y517098D02*
X36865Y517348D01*
X36990Y517640D01*
X37032Y518015D01*
X36949Y518390D01*
X36782Y518682D01*
X36490Y518890D01*
X36157Y518932D01*
X35824Y518848D01*
X35615Y518640D01*
X35449Y518348D01*
X35407Y518057D01*
X35449Y517765D01*
X35615Y517390D01*
X34532Y517515D01*
Y518640D01*
G01Y521015D02*
X34615Y520682D01*
X34824Y520432D01*
X35074Y520265D01*
X35407Y520140D01*
X35782Y520098D01*
X36157Y520140D01*
X36490Y520265D01*
X36740Y520432D01*
X36949Y520682D01*
X37032Y521015D01*
X36949Y521348D01*
X36740Y521598D01*
X36490Y521765D01*
X36157Y521890D01*
X35782Y521932D01*
X35407Y521890D01*
X35074Y521765D01*
X34824Y521598D01*
X34615Y521348D01*
X34532Y521015D01*
G01X68367Y513800D02*
Y511300D01*
X70033D01*
G01X72700D02*
Y513800D01*
X71158Y512008D01*
X73242D01*
G01X74492Y511592D02*
X74783Y511383D01*
X75117Y511300D01*
X75450Y511383D01*
X75742Y511633D01*
X75950Y512008D01*
X76033Y512383D01*
Y512842D01*
X75950Y513217D01*
X75742Y513550D01*
X75492Y513717D01*
X75200Y513800D01*
X74867Y513717D01*
X74617Y513550D01*
X74450Y513300D01*
X74367Y512967D01*
X74450Y512675D01*
X74658Y512383D01*
X74908Y512217D01*
X75200Y512175D01*
X75533Y512258D01*
X75783Y512467D01*
X76033Y512842D01*
G01X25228Y501204D02*
X27728D01*
Y502870D01*
G01X26686Y504245D02*
X26395Y504537D01*
X26228Y504787D01*
X26145Y505120D01*
X26228Y505412D01*
X26395Y505620D01*
X26645Y505787D01*
X26936Y505829D01*
X27186Y505787D01*
X27436Y505620D01*
X27645Y505370D01*
X27728Y505079D01*
X27645Y504745D01*
X27395Y504454D01*
X27020Y504287D01*
X26603Y504245D01*
X26061Y504329D01*
X25770Y504454D01*
X25478Y504662D01*
X25270Y504954D01*
X25228Y505245D01*
X25311Y505537D01*
X25520Y505745D01*
G01X27228Y507120D02*
X27520Y507370D01*
X27686Y507704D01*
X27728Y508079D01*
X27686Y508412D01*
X27478Y508745D01*
X27228Y508954D01*
X26978Y508995D01*
X26686Y508912D01*
X26478Y508620D01*
X26395Y508329D01*
Y507954D01*
G01Y508329D02*
X26270Y508579D01*
X26061Y508787D01*
X25811Y508870D01*
X25561Y508787D01*
X25353Y508579D01*
X25228Y508204D01*
X25270Y507829D01*
X25436Y507454D01*
G01X48500Y509000D02*
Y506500D01*
G01X47542Y509000D02*
X49458D01*
G01X50667Y506500D02*
Y509000D01*
X51667D01*
X52000Y508875D01*
X52250Y508583D01*
X52333Y508250D01*
X52250Y507917D01*
X52042Y507667D01*
X51667Y507542D01*
X50667D01*
G01X54500Y506500D02*
Y509000D01*
X54000Y508500D01*
G01Y506500D02*
X55000D01*
G01X57500D02*
Y509000D01*
X57000Y508500D01*
G01Y506500D02*
X58000D01*
G01X60500D02*
X60792Y506542D01*
X61125Y506667D01*
X61333Y506875D01*
X61417Y507167D01*
X61333Y507458D01*
X61083Y507708D01*
X60708Y507833D01*
X60292D01*
X60042Y507917D01*
X59833Y508125D01*
X59750Y508417D01*
X59875Y508708D01*
X60167Y508917D01*
X60500Y509000D01*
X60833Y508917D01*
X61125Y508708D01*
X61250Y508417D01*
X61167Y508125D01*
X60958Y507917D01*
X60708Y507833D01*
X60292D01*
X59917Y507708D01*
X59667Y507458D01*
X59583Y507167D01*
X59667Y506875D01*
X59875Y506667D01*
X60208Y506542D01*
X60500Y506500D01*
G01X40022Y496494D02*
Y493994D01*
G01X39064Y496494D02*
X40980D01*
G01X42189Y493994D02*
Y496494D01*
X43189D01*
X43522Y496369D01*
X43772Y496077D01*
X43855Y495744D01*
X43772Y495411D01*
X43564Y495161D01*
X43189Y495036D01*
X42189D01*
G01X45230D02*
X45522Y495327D01*
X45772Y495494D01*
X46105Y495577D01*
X46397Y495494D01*
X46605Y495327D01*
X46772Y495077D01*
X46814Y494786D01*
X46772Y494536D01*
X46605Y494286D01*
X46355Y494077D01*
X46064Y493994D01*
X45730Y494077D01*
X45439Y494327D01*
X45272Y494702D01*
X45230Y495119D01*
X45314Y495661D01*
X45439Y495952D01*
X45647Y496244D01*
X45939Y496452D01*
X46230Y496494D01*
X46522Y496411D01*
X46730Y496202D01*
G01X11982Y547181D02*
Y544681D01*
X13648D01*
G01X16648D02*
X14982D01*
Y547181D01*
X16648D01*
G01X15982Y545973D02*
X14982D01*
G01X17898Y544681D02*
Y547181D01*
X18732D01*
X19065Y547056D01*
X19315Y546889D01*
X19523Y546639D01*
X19690Y546348D01*
X19732Y545931D01*
X19690Y545514D01*
X19523Y545223D01*
X19315Y544973D01*
X19065Y544806D01*
X18732Y544681D01*
X17898D01*
G01X21107Y544973D02*
X21398Y544764D01*
X21732Y544681D01*
X22065Y544764D01*
X22357Y545014D01*
X22565Y545389D01*
X22648Y545764D01*
Y546223D01*
X22565Y546598D01*
X22357Y546931D01*
X22107Y547098D01*
X21815Y547181D01*
X21482Y547098D01*
X21232Y546931D01*
X21065Y546681D01*
X20982Y546348D01*
X21065Y546056D01*
X21273Y545764D01*
X21523Y545598D01*
X21815Y545556D01*
X22148Y545639D01*
X22398Y545848D01*
X22648Y546223D01*
G01X60800Y624967D02*
X58300D01*
Y626008D01*
X58425Y626342D01*
X58592Y626550D01*
X58925Y626633D01*
X59258Y626550D01*
X59467Y626300D01*
X59592Y626008D01*
Y624967D01*
G01Y626008D02*
X60800Y626633D01*
G01X58717Y628008D02*
X58467Y628258D01*
X58342Y628550D01*
X58300Y628883D01*
X58383Y629300D01*
X58592Y629592D01*
X58842Y629675D01*
X59092Y629633D01*
X59300Y629467D01*
X59717Y628633D01*
X60008Y628258D01*
X60425Y628008D01*
X60800Y627925D01*
Y629675D01*
G01X58717Y631008D02*
X58467Y631258D01*
X58342Y631550D01*
X58300Y631883D01*
X58383Y632300D01*
X58592Y632592D01*
X58842Y632675D01*
X59092Y632633D01*
X59300Y632467D01*
X59717Y631633D01*
X60008Y631258D01*
X60425Y631008D01*
X60800Y630925D01*
Y632675D01*
G01X60300Y633883D02*
X60592Y634133D01*
X60758Y634467D01*
X60800Y634842D01*
X60758Y635175D01*
X60550Y635508D01*
X60300Y635717D01*
X60050Y635758D01*
X59758Y635675D01*
X59550Y635383D01*
X59467Y635092D01*
Y634717D01*
G01Y635092D02*
X59342Y635342D01*
X59133Y635550D01*
X58883Y635633D01*
X58633Y635550D01*
X58425Y635342D01*
X58300Y634967D01*
X58342Y634592D01*
X58508Y634217D01*
G01X46067Y627300D02*
Y629800D01*
X47108D01*
X47442Y629675D01*
X47650Y629508D01*
X47733Y629175D01*
X47650Y628842D01*
X47400Y628633D01*
X47108Y628508D01*
X46067D01*
G01X47108D02*
X47733Y627300D01*
G01X48983Y627800D02*
X49233Y627508D01*
X49567Y627342D01*
X49942Y627300D01*
X50275Y627342D01*
X50608Y627550D01*
X50817Y627800D01*
X50858Y628050D01*
X50775Y628342D01*
X50483Y628550D01*
X50192Y628633D01*
X49817D01*
G01X50192D02*
X50442Y628758D01*
X50650Y628967D01*
X50733Y629217D01*
X50650Y629467D01*
X50442Y629675D01*
X50067Y629800D01*
X49692Y629758D01*
X49317Y629592D01*
G01X53400Y627300D02*
Y629800D01*
X51858Y628008D01*
X53942D01*
G01X56400Y627300D02*
Y629800D01*
X54858Y628008D01*
X56942D01*
G01X65455Y627482D02*
X65122Y627524D01*
X64830Y627690D01*
X64580Y627940D01*
X64413Y628232D01*
X64330Y628565D01*
Y628899D01*
X64413Y629232D01*
X64580Y629524D01*
X64830Y629774D01*
X65122Y629940D01*
X65455Y629982D01*
X65788Y629940D01*
X66080Y629774D01*
X66330Y629524D01*
X66497Y629232D01*
X66580Y628899D01*
Y628565D01*
X66497Y628232D01*
X66330Y627940D01*
X66080Y627690D01*
X65788Y627524D01*
X65455Y627482D01*
G01X65788Y628149D02*
X66288Y627482D01*
G01X67538Y627857D02*
X67788Y627649D01*
X68080Y627524D01*
X68455Y627482D01*
X68830Y627565D01*
X69122Y627732D01*
X69330Y628024D01*
X69372Y628357D01*
X69288Y628690D01*
X69080Y628899D01*
X68788Y629065D01*
X68497Y629107D01*
X68205Y629065D01*
X67830Y628899D01*
X67955Y629982D01*
X69080D01*
G01X45467Y661900D02*
Y664400D01*
X46508D01*
X46842Y664275D01*
X47050Y664108D01*
X47133Y663775D01*
X47050Y663442D01*
X46800Y663233D01*
X46508Y663108D01*
X45467D01*
G01X46508D02*
X47133Y661900D01*
G01X48508Y663983D02*
X48758Y664233D01*
X49050Y664358D01*
X49383Y664400D01*
X49800Y664317D01*
X50092Y664108D01*
X50175Y663858D01*
X50133Y663608D01*
X49967Y663400D01*
X49133Y662983D01*
X48758Y662692D01*
X48508Y662275D01*
X48425Y661900D01*
X50175D01*
G01X51508Y663983D02*
X51758Y664233D01*
X52050Y664358D01*
X52383Y664400D01*
X52800Y664317D01*
X53092Y664108D01*
X53175Y663858D01*
X53133Y663608D01*
X52967Y663400D01*
X52133Y662983D01*
X51758Y662692D01*
X51508Y662275D01*
X51425Y661900D01*
X53175D01*
G01X54508Y663983D02*
X54758Y664233D01*
X55050Y664358D01*
X55383Y664400D01*
X55800Y664317D01*
X56092Y664108D01*
X56175Y663858D01*
X56133Y663608D01*
X55967Y663400D01*
X55133Y662983D01*
X54758Y662692D01*
X54508Y662275D01*
X54425Y661900D01*
X56175D01*
G01X48767Y650400D02*
Y652900D01*
X49808D01*
X50142Y652775D01*
X50350Y652608D01*
X50433Y652275D01*
X50350Y651942D01*
X50100Y651733D01*
X49808Y651608D01*
X48767D01*
G01X49808D02*
X50433Y650400D01*
G01X51683Y650900D02*
X51933Y650608D01*
X52267Y650442D01*
X52642Y650400D01*
X52975Y650442D01*
X53308Y650650D01*
X53517Y650900D01*
X53558Y651150D01*
X53475Y651442D01*
X53183Y651650D01*
X52892Y651733D01*
X52517D01*
G01X52892D02*
X53142Y651858D01*
X53350Y652067D01*
X53433Y652317D01*
X53350Y652567D01*
X53142Y652775D01*
X52767Y652900D01*
X52392Y652858D01*
X52017Y652692D01*
G01X56100Y650400D02*
Y652900D01*
X54558Y651108D01*
X56642D01*
G01X57683Y650900D02*
X57933Y650608D01*
X58267Y650442D01*
X58642Y650400D01*
X58975Y650442D01*
X59308Y650650D01*
X59517Y650900D01*
X59558Y651150D01*
X59475Y651442D01*
X59183Y651650D01*
X58892Y651733D01*
X58517D01*
G01X58892D02*
X59142Y651858D01*
X59350Y652067D01*
X59433Y652317D01*
X59350Y652567D01*
X59142Y652775D01*
X58767Y652900D01*
X58392Y652858D01*
X58017Y652692D01*
G01X22428Y664300D02*
Y661800D01*
X24094D01*
G01X27094D02*
X25428D01*
Y664300D01*
X27094D01*
G01X26428Y663092D02*
X25428D01*
G01X28344Y661800D02*
Y664300D01*
X29178D01*
X29511Y664175D01*
X29761Y664008D01*
X29969Y663758D01*
X30136Y663467D01*
X30178Y663050D01*
X30136Y662633D01*
X29969Y662342D01*
X29761Y662092D01*
X29511Y661925D01*
X29178Y661800D01*
X28344D01*
G01X32178D02*
X32261Y662342D01*
X32386Y662800D01*
X32553Y663217D01*
X32761Y663675D01*
X33094Y664300D01*
X31428D01*
G01X51800Y654800D02*
X51467Y654842D01*
X51175Y655008D01*
X50925Y655258D01*
X50758Y655550D01*
X50675Y655883D01*
Y656217D01*
X50758Y656550D01*
X50925Y656842D01*
X51175Y657092D01*
X51467Y657258D01*
X51800Y657300D01*
X52133Y657258D01*
X52425Y657092D01*
X52675Y656842D01*
X52842Y656550D01*
X52925Y656217D01*
Y655883D01*
X52842Y655550D01*
X52675Y655258D01*
X52425Y655008D01*
X52133Y654842D01*
X51800Y654800D01*
G01X52133Y655467D02*
X52633Y654800D01*
G01X55300D02*
Y657300D01*
X53758Y655508D01*
X55842D01*
G01X56100Y764967D02*
X53600D01*
Y766008D01*
X53725Y766342D01*
X53892Y766550D01*
X54225Y766633D01*
X54558Y766550D01*
X54767Y766300D01*
X54892Y766008D01*
Y764967D01*
G01Y766008D02*
X56100Y766633D01*
G01X54017Y768008D02*
X53767Y768258D01*
X53642Y768550D01*
X53600Y768883D01*
X53683Y769300D01*
X53892Y769592D01*
X54142Y769675D01*
X54392Y769633D01*
X54600Y769467D01*
X55017Y768633D01*
X55308Y768258D01*
X55725Y768008D01*
X56100Y767925D01*
Y769675D01*
G01Y771800D02*
X53600D01*
X54100Y771300D01*
G01X56100D02*
Y772300D01*
G01X55808Y774092D02*
X56017Y774383D01*
X56100Y774717D01*
X56017Y775050D01*
X55767Y775342D01*
X55392Y775550D01*
X55017Y775633D01*
X54558D01*
X54183Y775550D01*
X53850Y775342D01*
X53683Y775092D01*
X53600Y774800D01*
X53683Y774467D01*
X53850Y774217D01*
X54100Y774050D01*
X54433Y773967D01*
X54725Y774050D01*
X55017Y774258D01*
X55183Y774508D01*
X55225Y774800D01*
X55142Y775133D01*
X54933Y775383D01*
X54558Y775633D01*
G01X52100Y764067D02*
X49600D01*
Y765108D01*
X49725Y765442D01*
X49892Y765650D01*
X50225Y765733D01*
X50558Y765650D01*
X50767Y765400D01*
X50892Y765108D01*
Y764067D01*
G01Y765108D02*
X52100Y765733D01*
G01X51600Y766983D02*
X51892Y767233D01*
X52058Y767567D01*
X52100Y767942D01*
X52058Y768275D01*
X51850Y768608D01*
X51600Y768817D01*
X51350Y768858D01*
X51058Y768775D01*
X50850Y768483D01*
X50767Y768192D01*
Y767817D01*
G01Y768192D02*
X50642Y768442D01*
X50433Y768650D01*
X50183Y768733D01*
X49933Y768650D01*
X49725Y768442D01*
X49600Y768067D01*
X49642Y767692D01*
X49808Y767317D01*
G01X52100Y771400D02*
X49600D01*
X51392Y769858D01*
Y771942D01*
G01X52100Y773817D02*
X51558Y773900D01*
X51100Y774025D01*
X50683Y774192D01*
X50225Y774400D01*
X49600Y774733D01*
Y773067D01*
G01X59567Y778300D02*
Y780800D01*
X60608D01*
X60942Y780675D01*
X61150Y780508D01*
X61233Y780175D01*
X61150Y779842D01*
X60900Y779633D01*
X60608Y779508D01*
X59567D01*
G01X60608D02*
X61233Y778300D01*
G01X62608Y780383D02*
X62858Y780633D01*
X63150Y780758D01*
X63483Y780800D01*
X63900Y780717D01*
X64192Y780508D01*
X64275Y780258D01*
X64233Y780008D01*
X64067Y779800D01*
X63233Y779383D01*
X62858Y779092D01*
X62608Y778675D01*
X62525Y778300D01*
X64275D01*
G01X65692Y778592D02*
X65983Y778383D01*
X66317Y778300D01*
X66650Y778383D01*
X66942Y778633D01*
X67150Y779008D01*
X67233Y779383D01*
Y779842D01*
X67150Y780217D01*
X66942Y780550D01*
X66692Y780717D01*
X66400Y780800D01*
X66067Y780717D01*
X65817Y780550D01*
X65650Y780300D01*
X65567Y779967D01*
X65650Y779675D01*
X65858Y779383D01*
X66108Y779217D01*
X66400Y779175D01*
X66733Y779258D01*
X66983Y779467D01*
X67233Y779842D01*
G01X68608Y779342D02*
X68900Y779633D01*
X69150Y779800D01*
X69483Y779883D01*
X69775Y779800D01*
X69983Y779633D01*
X70150Y779383D01*
X70192Y779092D01*
X70150Y778842D01*
X69983Y778592D01*
X69733Y778383D01*
X69442Y778300D01*
X69108Y778383D01*
X68817Y778633D01*
X68650Y779008D01*
X68608Y779425D01*
X68692Y779967D01*
X68817Y780258D01*
X69025Y780550D01*
X69317Y780758D01*
X69608Y780800D01*
X69900Y780717D01*
X70108Y780508D01*
G01X27604Y782435D02*
Y779935D01*
X29270D01*
G01X32270D02*
X30604D01*
Y782435D01*
X32270D01*
G01X31604Y781227D02*
X30604D01*
G01X33520Y779935D02*
Y782435D01*
X34354D01*
X34687Y782310D01*
X34937Y782143D01*
X35145Y781893D01*
X35312Y781602D01*
X35354Y781185D01*
X35312Y780768D01*
X35145Y780477D01*
X34937Y780227D01*
X34687Y780060D01*
X34354Y779935D01*
X33520D01*
G01X36520Y780310D02*
X36770Y780102D01*
X37062Y779977D01*
X37437Y779935D01*
X37812Y780018D01*
X38104Y780185D01*
X38312Y780477D01*
X38354Y780810D01*
X38270Y781143D01*
X38062Y781352D01*
X37770Y781518D01*
X37479Y781560D01*
X37187Y781518D01*
X36812Y781352D01*
X36937Y782435D01*
X38062D01*
G01X60500Y783400D02*
X60167Y783442D01*
X59875Y783608D01*
X59625Y783858D01*
X59458Y784150D01*
X59375Y784483D01*
Y784817D01*
X59458Y785150D01*
X59625Y785442D01*
X59875Y785692D01*
X60167Y785858D01*
X60500Y785900D01*
X60833Y785858D01*
X61125Y785692D01*
X61375Y785442D01*
X61542Y785150D01*
X61625Y784817D01*
Y784483D01*
X61542Y784150D01*
X61375Y783858D01*
X61125Y783608D01*
X60833Y783442D01*
X60500Y783400D01*
G01X60833Y784067D02*
X61333Y783400D01*
G01X62708Y785483D02*
X62958Y785733D01*
X63250Y785858D01*
X63583Y785900D01*
X64000Y785817D01*
X64292Y785608D01*
X64375Y785358D01*
X64333Y785108D01*
X64167Y784900D01*
X63333Y784483D01*
X62958Y784192D01*
X62708Y783775D01*
X62625Y783400D01*
X64375D01*
G01X149747Y38187D02*
X147247D01*
Y39187D01*
X147372Y39520D01*
X147664Y39770D01*
X147997Y39853D01*
X148330Y39770D01*
X148580Y39562D01*
X148705Y39187D01*
Y38187D01*
G01X147455Y42937D02*
X147330Y42687D01*
X147247Y42395D01*
Y42062D01*
X147372Y41687D01*
X147580Y41395D01*
X147830Y41187D01*
X148247Y41020D01*
X148622Y40978D01*
X148997Y41062D01*
X149247Y41187D01*
X149497Y41437D01*
X149664Y41728D01*
X149747Y42020D01*
Y42312D01*
X149664Y42603D01*
X149539Y42853D01*
X149372Y43062D01*
G01X147664Y44228D02*
X147414Y44478D01*
X147289Y44770D01*
X147247Y45103D01*
X147330Y45520D01*
X147539Y45812D01*
X147789Y45895D01*
X148039Y45853D01*
X148247Y45687D01*
X148664Y44853D01*
X148955Y44478D01*
X149372Y44228D01*
X149747Y44145D01*
Y45895D01*
G01X147664Y47228D02*
X147414Y47478D01*
X147289Y47770D01*
X147247Y48103D01*
X147330Y48520D01*
X147539Y48812D01*
X147789Y48895D01*
X148039Y48853D01*
X148247Y48687D01*
X148664Y47853D01*
X148955Y47478D01*
X149372Y47228D01*
X149747Y47145D01*
Y48895D01*
G01X118400Y38467D02*
X115900D01*
Y39467D01*
X116025Y39800D01*
X116317Y40050D01*
X116650Y40133D01*
X116983Y40050D01*
X117233Y39842D01*
X117358Y39467D01*
Y38467D01*
G01X116108Y43217D02*
X115983Y42967D01*
X115900Y42675D01*
Y42342D01*
X116025Y41967D01*
X116233Y41675D01*
X116483Y41467D01*
X116900Y41300D01*
X117275Y41258D01*
X117650Y41342D01*
X117900Y41467D01*
X118150Y41717D01*
X118317Y42008D01*
X118400Y42300D01*
Y42592D01*
X118317Y42883D01*
X118192Y43133D01*
X118025Y43342D01*
G01X116317Y44508D02*
X116067Y44758D01*
X115942Y45050D01*
X115900Y45383D01*
X115983Y45800D01*
X116192Y46092D01*
X116442Y46175D01*
X116692Y46133D01*
X116900Y45967D01*
X117317Y45133D01*
X117608Y44758D01*
X118025Y44508D01*
X118400Y44425D01*
Y46175D01*
G01Y48300D02*
X115900D01*
X116400Y47800D01*
G01X118400D02*
Y48800D01*
G01X102000Y38067D02*
X99500D01*
Y39067D01*
X99625Y39400D01*
X99917Y39650D01*
X100250Y39733D01*
X100583Y39650D01*
X100833Y39442D01*
X100958Y39067D01*
Y38067D01*
G01X99708Y42817D02*
X99583Y42567D01*
X99500Y42275D01*
Y41942D01*
X99625Y41567D01*
X99833Y41275D01*
X100083Y41067D01*
X100500Y40900D01*
X100875Y40858D01*
X101250Y40942D01*
X101500Y41067D01*
X101750Y41317D01*
X101917Y41608D01*
X102000Y41900D01*
Y42192D01*
X101917Y42483D01*
X101792Y42733D01*
X101625Y42942D01*
G01X99917Y44108D02*
X99667Y44358D01*
X99542Y44650D01*
X99500Y44983D01*
X99583Y45400D01*
X99792Y45692D01*
X100042Y45775D01*
X100292Y45733D01*
X100500Y45567D01*
X100917Y44733D01*
X101208Y44358D01*
X101625Y44108D01*
X102000Y44025D01*
Y45775D01*
G01X99500Y47900D02*
X99583Y47567D01*
X99792Y47317D01*
X100042Y47150D01*
X100375Y47025D01*
X100750Y46983D01*
X101125Y47025D01*
X101458Y47150D01*
X101708Y47317D01*
X101917Y47567D01*
X102000Y47900D01*
X101917Y48233D01*
X101708Y48483D01*
X101458Y48650D01*
X101125Y48775D01*
X100750Y48817D01*
X100375Y48775D01*
X100042Y48650D01*
X99792Y48483D01*
X99583Y48233D01*
X99500Y47900D01*
G01X136362Y32656D02*
X133862D01*
Y33656D01*
X133987Y33989D01*
X134279Y34239D01*
X134612Y34322D01*
X134945Y34239D01*
X135195Y34031D01*
X135320Y33656D01*
Y32656D01*
G01X134070Y37406D02*
X133945Y37156D01*
X133862Y36864D01*
Y36531D01*
X133987Y36156D01*
X134195Y35864D01*
X134445Y35656D01*
X134862Y35489D01*
X135237Y35447D01*
X135612Y35531D01*
X135862Y35656D01*
X136112Y35906D01*
X136279Y36197D01*
X136362Y36489D01*
Y36781D01*
X136279Y37072D01*
X136154Y37322D01*
X135987Y37531D01*
G01X134279Y38697D02*
X134029Y38947D01*
X133904Y39239D01*
X133862Y39572D01*
X133945Y39989D01*
X134154Y40281D01*
X134404Y40364D01*
X134654Y40322D01*
X134862Y40156D01*
X135279Y39322D01*
X135570Y38947D01*
X135987Y38697D01*
X136362Y38614D01*
Y40364D01*
G01X135862Y41572D02*
X136154Y41822D01*
X136320Y42156D01*
X136362Y42531D01*
X136320Y42864D01*
X136112Y43197D01*
X135862Y43406D01*
X135612Y43447D01*
X135320Y43364D01*
X135112Y43072D01*
X135029Y42781D01*
Y42406D01*
G01Y42781D02*
X134904Y43031D01*
X134695Y43239D01*
X134445Y43322D01*
X134195Y43239D01*
X133987Y43031D01*
X133862Y42656D01*
X133904Y42281D01*
X134070Y41906D01*
G01X81682Y87452D02*
Y85660D01*
X81849Y85285D01*
X82182Y85035D01*
X82599Y84952D01*
X83016Y85035D01*
X83349Y85285D01*
X83516Y85660D01*
Y87452D01*
G01X84807Y87035D02*
X85057Y87285D01*
X85349Y87410D01*
X85682Y87452D01*
X86099Y87369D01*
X86391Y87160D01*
X86474Y86910D01*
X86432Y86660D01*
X86266Y86452D01*
X85432Y86035D01*
X85057Y85744D01*
X84807Y85327D01*
X84724Y84952D01*
X86474D01*
G01X88599Y87452D02*
X88266Y87369D01*
X88016Y87160D01*
X87849Y86910D01*
X87724Y86577D01*
X87682Y86202D01*
X87724Y85827D01*
X87849Y85494D01*
X88016Y85244D01*
X88266Y85035D01*
X88599Y84952D01*
X88932Y85035D01*
X89182Y85244D01*
X89349Y85494D01*
X89474Y85827D01*
X89516Y86202D01*
X89474Y86577D01*
X89349Y86910D01*
X89182Y87160D01*
X88932Y87369D01*
X88599Y87452D01*
G01X103179Y80061D02*
X100679D01*
Y81061D01*
X100804Y81394D01*
X101096Y81644D01*
X101429Y81727D01*
X101762Y81644D01*
X102012Y81436D01*
X102137Y81061D01*
Y80061D01*
G01X103179Y83061D02*
X100679D01*
Y84102D01*
X100804Y84436D01*
X100971Y84644D01*
X101304Y84727D01*
X101637Y84644D01*
X101846Y84394D01*
X101971Y84102D01*
Y83061D01*
G01Y84102D02*
X103179Y84727D01*
G01X101096Y86102D02*
X100846Y86352D01*
X100721Y86644D01*
X100679Y86977D01*
X100762Y87394D01*
X100971Y87686D01*
X101221Y87769D01*
X101471Y87727D01*
X101679Y87561D01*
X102096Y86727D01*
X102387Y86352D01*
X102804Y86102D01*
X103179Y86019D01*
Y87769D01*
G01X102679Y88977D02*
X102971Y89227D01*
X103137Y89561D01*
X103179Y89936D01*
X103137Y90269D01*
X102929Y90602D01*
X102679Y90811D01*
X102429Y90852D01*
X102137Y90769D01*
X101929Y90477D01*
X101846Y90186D01*
Y89811D01*
G01Y90186D02*
X101721Y90436D01*
X101512Y90644D01*
X101262Y90727D01*
X101012Y90644D01*
X100804Y90436D01*
X100679Y90061D01*
X100721Y89686D01*
X100887Y89311D01*
G01X92267Y106100D02*
Y108600D01*
X93267D01*
X93600Y108475D01*
X93850Y108183D01*
X93933Y107850D01*
X93850Y107517D01*
X93642Y107267D01*
X93267Y107142D01*
X92267D01*
G01X95183Y108600D02*
Y106808D01*
X95350Y106433D01*
X95683Y106183D01*
X96100Y106100D01*
X96517Y106183D01*
X96850Y106433D01*
X97017Y106808D01*
Y108600D01*
G01X99017Y106100D02*
X99100Y106642D01*
X99225Y107100D01*
X99392Y107517D01*
X99600Y107975D01*
X99933Y108600D01*
X98267D01*
G01X143300Y109467D02*
X140800D01*
Y110467D01*
X140925Y110800D01*
X141217Y111050D01*
X141550Y111133D01*
X141883Y111050D01*
X142133Y110842D01*
X142258Y110467D01*
Y109467D01*
G01X140800Y112467D02*
X143300D01*
Y114133D01*
G01X141217Y115508D02*
X140967Y115758D01*
X140842Y116050D01*
X140800Y116383D01*
X140883Y116800D01*
X141092Y117092D01*
X141342Y117175D01*
X141592Y117133D01*
X141800Y116967D01*
X142217Y116133D01*
X142508Y115758D01*
X142925Y115508D01*
X143300Y115425D01*
Y117175D01*
G01X135467Y125900D02*
Y128400D01*
X136467D01*
X136800Y128275D01*
X137050Y127983D01*
X137133Y127650D01*
X137050Y127317D01*
X136842Y127067D01*
X136467Y126942D01*
X135467D01*
G01X138467Y128400D02*
Y125900D01*
X140133D01*
G01X142800D02*
Y128400D01*
X141258Y126608D01*
X143342D01*
G01X117108Y97543D02*
X114608D01*
Y98543D01*
X114733Y98876D01*
X115025Y99126D01*
X115358Y99209D01*
X115691Y99126D01*
X115941Y98918D01*
X116066Y98543D01*
Y97543D01*
G01X117108Y100543D02*
X114608D01*
Y101584D01*
X114733Y101918D01*
X114900Y102126D01*
X115233Y102209D01*
X115566Y102126D01*
X115775Y101876D01*
X115900Y101584D01*
Y100543D01*
G01Y101584D02*
X117108Y102209D01*
G01X116733Y103459D02*
X116941Y103709D01*
X117066Y104001D01*
X117108Y104376D01*
X117025Y104751D01*
X116858Y105043D01*
X116566Y105251D01*
X116233Y105293D01*
X115900Y105209D01*
X115691Y105001D01*
X115525Y104709D01*
X115483Y104418D01*
X115525Y104126D01*
X115691Y103751D01*
X114608Y103876D01*
Y105001D01*
G01X115025Y106584D02*
X114775Y106834D01*
X114650Y107126D01*
X114608Y107459D01*
X114691Y107876D01*
X114900Y108168D01*
X115150Y108251D01*
X115400Y108209D01*
X115608Y108043D01*
X116025Y107209D01*
X116316Y106834D01*
X116733Y106584D01*
X117108Y106501D01*
Y108251D01*
G01X107308Y97543D02*
X104808D01*
Y98543D01*
X104933Y98876D01*
X105225Y99126D01*
X105558Y99209D01*
X105891Y99126D01*
X106141Y98918D01*
X106266Y98543D01*
Y97543D01*
G01X107308Y100543D02*
X104808D01*
Y101584D01*
X104933Y101918D01*
X105100Y102126D01*
X105433Y102209D01*
X105766Y102126D01*
X105975Y101876D01*
X106100Y101584D01*
Y100543D01*
G01Y101584D02*
X107308Y102209D01*
G01X106933Y103459D02*
X107141Y103709D01*
X107266Y104001D01*
X107308Y104376D01*
X107225Y104751D01*
X107058Y105043D01*
X106766Y105251D01*
X106433Y105293D01*
X106100Y105209D01*
X105891Y105001D01*
X105725Y104709D01*
X105683Y104418D01*
X105725Y104126D01*
X105891Y103751D01*
X104808Y103876D01*
Y105001D01*
G01X106808Y106459D02*
X107100Y106709D01*
X107266Y107043D01*
X107308Y107418D01*
X107266Y107751D01*
X107058Y108084D01*
X106808Y108293D01*
X106558Y108334D01*
X106266Y108251D01*
X106058Y107959D01*
X105975Y107668D01*
Y107293D01*
G01Y107668D02*
X105850Y107918D01*
X105641Y108126D01*
X105391Y108209D01*
X105141Y108126D01*
X104933Y107918D01*
X104808Y107543D01*
X104850Y107168D01*
X105016Y106793D01*
G01X99567Y184100D02*
Y186600D01*
X100567D01*
X100900Y186475D01*
X101150Y186183D01*
X101233Y185850D01*
X101150Y185517D01*
X100942Y185267D01*
X100567Y185142D01*
X99567D01*
G01X102483Y186600D02*
Y184808D01*
X102650Y184433D01*
X102983Y184183D01*
X103400Y184100D01*
X103817Y184183D01*
X104150Y184433D01*
X104317Y184808D01*
Y186600D01*
G01X105483Y184475D02*
X105733Y184267D01*
X106025Y184142D01*
X106400Y184100D01*
X106775Y184183D01*
X107067Y184350D01*
X107275Y184642D01*
X107317Y184975D01*
X107233Y185308D01*
X107025Y185517D01*
X106733Y185683D01*
X106442Y185725D01*
X106150Y185683D01*
X105775Y185517D01*
X105900Y186600D01*
X107025D01*
G01X133767Y176200D02*
Y178700D01*
X134767D01*
X135100Y178575D01*
X135350Y178283D01*
X135433Y177950D01*
X135350Y177617D01*
X135142Y177367D01*
X134767Y177242D01*
X133767D01*
G01X137600Y176200D02*
X137267Y176242D01*
X136975Y176408D01*
X136725Y176658D01*
X136558Y176950D01*
X136475Y177283D01*
Y177617D01*
X136558Y177950D01*
X136725Y178242D01*
X136975Y178492D01*
X137267Y178658D01*
X137600Y178700D01*
X137933Y178658D01*
X138225Y178492D01*
X138475Y178242D01*
X138642Y177950D01*
X138725Y177617D01*
Y177283D01*
X138642Y176950D01*
X138475Y176658D01*
X138225Y176408D01*
X137933Y176242D01*
X137600Y176200D01*
G01X137933Y176867D02*
X138433Y176200D01*
G01X139808Y178283D02*
X140058Y178533D01*
X140350Y178658D01*
X140683Y178700D01*
X141100Y178617D01*
X141392Y178408D01*
X141475Y178158D01*
X141433Y177908D01*
X141267Y177700D01*
X140433Y177283D01*
X140058Y176992D01*
X139808Y176575D01*
X139725Y176200D01*
X141475D01*
G01X95100Y156667D02*
X92600D01*
Y157667D01*
X92725Y158000D01*
X93017Y158250D01*
X93350Y158333D01*
X93683Y158250D01*
X93933Y158042D01*
X94058Y157667D01*
Y156667D01*
G01X95100Y159667D02*
X92600D01*
Y160708D01*
X92725Y161042D01*
X92892Y161250D01*
X93225Y161333D01*
X93558Y161250D01*
X93767Y161000D01*
X93892Y160708D01*
Y159667D01*
G01Y160708D02*
X95100Y161333D01*
G01X94600Y162583D02*
X94892Y162833D01*
X95058Y163167D01*
X95100Y163542D01*
X95058Y163875D01*
X94850Y164208D01*
X94600Y164417D01*
X94350Y164458D01*
X94058Y164375D01*
X93850Y164083D01*
X93767Y163792D01*
Y163417D01*
G01Y163792D02*
X93642Y164042D01*
X93433Y164250D01*
X93183Y164333D01*
X92933Y164250D01*
X92725Y164042D01*
X92600Y163667D01*
X92642Y163292D01*
X92808Y162917D01*
G01X94600Y165583D02*
X94892Y165833D01*
X95058Y166167D01*
X95100Y166542D01*
X95058Y166875D01*
X94850Y167208D01*
X94600Y167417D01*
X94350Y167458D01*
X94058Y167375D01*
X93850Y167083D01*
X93767Y166792D01*
Y166417D01*
G01Y166792D02*
X93642Y167042D01*
X93433Y167250D01*
X93183Y167333D01*
X92933Y167250D01*
X92725Y167042D01*
X92600Y166667D01*
X92642Y166292D01*
X92808Y165917D01*
G01X86467Y184400D02*
Y186900D01*
X87467D01*
X87800Y186775D01*
X88050Y186483D01*
X88133Y186150D01*
X88050Y185817D01*
X87842Y185567D01*
X87467Y185442D01*
X86467D01*
G01X89467Y184400D02*
Y186900D01*
X90508D01*
X90842Y186775D01*
X91050Y186608D01*
X91133Y186275D01*
X91050Y185942D01*
X90800Y185733D01*
X90508Y185608D01*
X89467D01*
G01X90508D02*
X91133Y184400D01*
G01X93800D02*
Y186900D01*
X92258Y185108D01*
X94342D01*
G01X96300Y184400D02*
X96592Y184442D01*
X96925Y184567D01*
X97133Y184775D01*
X97217Y185067D01*
X97133Y185358D01*
X96883Y185608D01*
X96508Y185733D01*
X96092D01*
X95842Y185817D01*
X95633Y186025D01*
X95550Y186317D01*
X95675Y186608D01*
X95967Y186817D01*
X96300Y186900D01*
X96633Y186817D01*
X96925Y186608D01*
X97050Y186317D01*
X96967Y186025D01*
X96758Y185817D01*
X96508Y185733D01*
X96092D01*
X95717Y185608D01*
X95467Y185358D01*
X95383Y185067D01*
X95467Y184775D01*
X95675Y184567D01*
X96008Y184442D01*
X96300Y184400D01*
G01X104267Y172700D02*
Y175200D01*
X105267D01*
X105600Y175075D01*
X105850Y174783D01*
X105933Y174450D01*
X105850Y174117D01*
X105642Y173867D01*
X105267Y173742D01*
X104267D01*
G01X107267Y172700D02*
Y175200D01*
X108308D01*
X108642Y175075D01*
X108850Y174908D01*
X108933Y174575D01*
X108850Y174242D01*
X108600Y174033D01*
X108308Y173908D01*
X107267D01*
G01X108308D02*
X108933Y172700D01*
G01X111600D02*
Y175200D01*
X110058Y173408D01*
X112142D01*
G01X113308Y173742D02*
X113600Y174033D01*
X113850Y174200D01*
X114183Y174283D01*
X114475Y174200D01*
X114683Y174033D01*
X114850Y173783D01*
X114892Y173492D01*
X114850Y173242D01*
X114683Y172992D01*
X114433Y172783D01*
X114142Y172700D01*
X113808Y172783D01*
X113517Y173033D01*
X113350Y173408D01*
X113308Y173825D01*
X113392Y174367D01*
X113517Y174658D01*
X113725Y174950D01*
X114017Y175158D01*
X114308Y175200D01*
X114600Y175117D01*
X114808Y174908D01*
G01X107367Y176300D02*
Y178800D01*
X108367D01*
X108700Y178675D01*
X108950Y178383D01*
X109033Y178050D01*
X108950Y177717D01*
X108742Y177467D01*
X108367Y177342D01*
X107367D01*
G01X110367Y176300D02*
Y178800D01*
X111408D01*
X111742Y178675D01*
X111950Y178508D01*
X112033Y178175D01*
X111950Y177842D01*
X111700Y177633D01*
X111408Y177508D01*
X110367D01*
G01X111408D02*
X112033Y176300D01*
G01X114700D02*
Y178800D01*
X113158Y177008D01*
X115242D01*
G01X116283Y176675D02*
X116533Y176467D01*
X116825Y176342D01*
X117200Y176300D01*
X117575Y176383D01*
X117867Y176550D01*
X118075Y176842D01*
X118117Y177175D01*
X118033Y177508D01*
X117825Y177717D01*
X117533Y177883D01*
X117242Y177925D01*
X116950Y177883D01*
X116575Y177717D01*
X116700Y178800D01*
X117825D01*
G01X84100Y146367D02*
X81600D01*
Y147367D01*
X81725Y147700D01*
X82017Y147950D01*
X82350Y148033D01*
X82683Y147950D01*
X82933Y147742D01*
X83058Y147367D01*
Y146367D01*
G01X84100Y149367D02*
X81600D01*
Y150408D01*
X81725Y150742D01*
X81892Y150950D01*
X82225Y151033D01*
X82558Y150950D01*
X82767Y150700D01*
X82892Y150408D01*
Y149367D01*
G01Y150408D02*
X84100Y151033D01*
G01X83725Y152283D02*
X83933Y152533D01*
X84058Y152825D01*
X84100Y153200D01*
X84017Y153575D01*
X83850Y153867D01*
X83558Y154075D01*
X83225Y154117D01*
X82892Y154033D01*
X82683Y153825D01*
X82517Y153533D01*
X82475Y153242D01*
X82517Y152950D01*
X82683Y152575D01*
X81600Y152700D01*
Y153825D01*
G01X84100Y156700D02*
X81600D01*
X83392Y155158D01*
Y157242D01*
G01X86367Y181100D02*
Y183600D01*
X87367D01*
X87700Y183475D01*
X87950Y183183D01*
X88033Y182850D01*
X87950Y182517D01*
X87742Y182267D01*
X87367Y182142D01*
X86367D01*
G01X91117Y183392D02*
X90867Y183517D01*
X90575Y183600D01*
X90242D01*
X89867Y183475D01*
X89575Y183267D01*
X89367Y183017D01*
X89200Y182600D01*
X89158Y182225D01*
X89242Y181850D01*
X89367Y181600D01*
X89617Y181350D01*
X89908Y181183D01*
X90200Y181100D01*
X90492D01*
X90783Y181183D01*
X91033Y181308D01*
X91242Y181475D01*
G01X93700Y181100D02*
Y183600D01*
X92158Y181808D01*
X94242D01*
G01X95283Y181600D02*
X95533Y181308D01*
X95867Y181142D01*
X96242Y181100D01*
X96575Y181142D01*
X96908Y181350D01*
X97117Y181600D01*
X97158Y181850D01*
X97075Y182142D01*
X96783Y182350D01*
X96492Y182433D01*
X96117D01*
G01X96492D02*
X96742Y182558D01*
X96950Y182767D01*
X97033Y183017D01*
X96950Y183267D01*
X96742Y183475D01*
X96367Y183600D01*
X95992Y183558D01*
X95617Y183392D01*
G01X100100Y158267D02*
X97600D01*
Y159267D01*
X97725Y159600D01*
X98017Y159850D01*
X98350Y159933D01*
X98683Y159850D01*
X98933Y159642D01*
X99058Y159267D01*
Y158267D01*
G01X97808Y163017D02*
X97683Y162767D01*
X97600Y162475D01*
Y162142D01*
X97725Y161767D01*
X97933Y161475D01*
X98183Y161267D01*
X98600Y161100D01*
X98975Y161058D01*
X99350Y161142D01*
X99600Y161267D01*
X99850Y161517D01*
X100017Y161808D01*
X100100Y162100D01*
Y162392D01*
X100017Y162683D01*
X99892Y162933D01*
X99725Y163142D01*
G01X99600Y164183D02*
X99892Y164433D01*
X100058Y164767D01*
X100100Y165142D01*
X100058Y165475D01*
X99850Y165808D01*
X99600Y166017D01*
X99350Y166058D01*
X99058Y165975D01*
X98850Y165683D01*
X98767Y165392D01*
Y165017D01*
G01Y165392D02*
X98642Y165642D01*
X98433Y165850D01*
X98183Y165933D01*
X97933Y165850D01*
X97725Y165642D01*
X97600Y165267D01*
X97642Y164892D01*
X97808Y164517D01*
G01X100100Y168017D02*
X99558Y168100D01*
X99100Y168225D01*
X98683Y168392D01*
X98225Y168600D01*
X97600Y168933D01*
Y167267D01*
G01X126700Y157167D02*
X124200D01*
Y158167D01*
X124325Y158500D01*
X124617Y158750D01*
X124950Y158833D01*
X125283Y158750D01*
X125533Y158542D01*
X125658Y158167D01*
Y157167D01*
G01X124408Y161917D02*
X124283Y161667D01*
X124200Y161375D01*
Y161042D01*
X124325Y160667D01*
X124533Y160375D01*
X124783Y160167D01*
X125200Y160000D01*
X125575Y159958D01*
X125950Y160042D01*
X126200Y160167D01*
X126450Y160417D01*
X126617Y160708D01*
X126700Y161000D01*
Y161292D01*
X126617Y161583D01*
X126492Y161833D01*
X126325Y162042D01*
G01X126200Y163083D02*
X126492Y163333D01*
X126658Y163667D01*
X126700Y164042D01*
X126658Y164375D01*
X126450Y164708D01*
X126200Y164917D01*
X125950Y164958D01*
X125658Y164875D01*
X125450Y164583D01*
X125367Y164292D01*
Y163917D01*
G01Y164292D02*
X125242Y164542D01*
X125033Y164750D01*
X124783Y164833D01*
X124533Y164750D01*
X124325Y164542D01*
X124200Y164167D01*
X124242Y163792D01*
X124408Y163417D01*
G01X125658Y166208D02*
X125367Y166500D01*
X125200Y166750D01*
X125117Y167083D01*
X125200Y167375D01*
X125367Y167583D01*
X125617Y167750D01*
X125908Y167792D01*
X126158Y167750D01*
X126408Y167583D01*
X126617Y167333D01*
X126700Y167042D01*
X126617Y166708D01*
X126367Y166417D01*
X125992Y166250D01*
X125575Y166208D01*
X125033Y166292D01*
X124742Y166417D01*
X124450Y166625D01*
X124242Y166917D01*
X124200Y167208D01*
X124283Y167500D01*
X124492Y167708D01*
G01X118500Y156367D02*
X116000D01*
Y157367D01*
X116125Y157700D01*
X116417Y157950D01*
X116750Y158033D01*
X117083Y157950D01*
X117333Y157742D01*
X117458Y157367D01*
Y156367D01*
G01X116208Y161117D02*
X116083Y160867D01*
X116000Y160575D01*
Y160242D01*
X116125Y159867D01*
X116333Y159575D01*
X116583Y159367D01*
X117000Y159200D01*
X117375Y159158D01*
X117750Y159242D01*
X118000Y159367D01*
X118250Y159617D01*
X118417Y159908D01*
X118500Y160200D01*
Y160492D01*
X118417Y160783D01*
X118292Y161033D01*
X118125Y161242D01*
G01X118000Y162283D02*
X118292Y162533D01*
X118458Y162867D01*
X118500Y163242D01*
X118458Y163575D01*
X118250Y163908D01*
X118000Y164117D01*
X117750Y164158D01*
X117458Y164075D01*
X117250Y163783D01*
X117167Y163492D01*
Y163117D01*
G01Y163492D02*
X117042Y163742D01*
X116833Y163950D01*
X116583Y164033D01*
X116333Y163950D01*
X116125Y163742D01*
X116000Y163367D01*
X116042Y162992D01*
X116208Y162617D01*
G01X118125Y165283D02*
X118333Y165533D01*
X118458Y165825D01*
X118500Y166200D01*
X118417Y166575D01*
X118250Y166867D01*
X117958Y167075D01*
X117625Y167117D01*
X117292Y167033D01*
X117083Y166825D01*
X116917Y166533D01*
X116875Y166242D01*
X116917Y165950D01*
X117083Y165575D01*
X116000Y165700D01*
Y166825D01*
G01X108700Y158867D02*
X106200D01*
Y159867D01*
X106325Y160200D01*
X106617Y160450D01*
X106950Y160533D01*
X107283Y160450D01*
X107533Y160242D01*
X107658Y159867D01*
Y158867D01*
G01X106408Y163617D02*
X106283Y163367D01*
X106200Y163075D01*
Y162742D01*
X106325Y162367D01*
X106533Y162075D01*
X106783Y161867D01*
X107200Y161700D01*
X107575Y161658D01*
X107950Y161742D01*
X108200Y161867D01*
X108450Y162117D01*
X108617Y162408D01*
X108700Y162700D01*
Y162992D01*
X108617Y163283D01*
X108492Y163533D01*
X108325Y163742D01*
G01X108200Y164783D02*
X108492Y165033D01*
X108658Y165367D01*
X108700Y165742D01*
X108658Y166075D01*
X108450Y166408D01*
X108200Y166617D01*
X107950Y166658D01*
X107658Y166575D01*
X107450Y166283D01*
X107367Y165992D01*
Y165617D01*
G01Y165992D02*
X107242Y166242D01*
X107033Y166450D01*
X106783Y166533D01*
X106533Y166450D01*
X106325Y166242D01*
X106200Y165867D01*
X106242Y165492D01*
X106408Y165117D01*
G01X108700Y169200D02*
X106200D01*
X107992Y167658D01*
Y169742D01*
G01X133500Y164400D02*
Y161900D01*
G01X132542Y164400D02*
X134458D01*
G01X135667Y161900D02*
Y164400D01*
X136667D01*
X137000Y164275D01*
X137250Y163983D01*
X137333Y163650D01*
X137250Y163317D01*
X137042Y163067D01*
X136667Y162942D01*
X135667D01*
G01X140000Y161900D02*
Y164400D01*
X138458Y162608D01*
X140542D01*
G01X142500Y161900D02*
X142792Y161942D01*
X143125Y162067D01*
X143333Y162275D01*
X143417Y162567D01*
X143333Y162858D01*
X143083Y163108D01*
X142708Y163233D01*
X142292D01*
X142042Y163317D01*
X141833Y163525D01*
X141750Y163817D01*
X141875Y164108D01*
X142167Y164317D01*
X142500Y164400D01*
X142833Y164317D01*
X143125Y164108D01*
X143250Y163817D01*
X143167Y163525D01*
X142958Y163317D01*
X142708Y163233D01*
X142292D01*
X141917Y163108D01*
X141667Y162858D01*
X141583Y162567D01*
X141667Y162275D01*
X141875Y162067D01*
X142208Y161942D01*
X142500Y161900D01*
G01X119100Y175200D02*
Y172700D01*
G01X118142Y175200D02*
X120058D01*
G01X121267Y172700D02*
Y175200D01*
X122267D01*
X122600Y175075D01*
X122850Y174783D01*
X122933Y174450D01*
X122850Y174117D01*
X122642Y173867D01*
X122267Y173742D01*
X121267D01*
G01X124183Y173075D02*
X124433Y172867D01*
X124725Y172742D01*
X125100Y172700D01*
X125475Y172783D01*
X125767Y172950D01*
X125975Y173242D01*
X126017Y173575D01*
X125933Y173908D01*
X125725Y174117D01*
X125433Y174283D01*
X125142Y174325D01*
X124850Y174283D01*
X124475Y174117D01*
X124600Y175200D01*
X125725D01*
G01X128100Y172700D02*
Y175200D01*
X127600Y174700D01*
G01Y172700D02*
X128600D01*
G01X104400Y230167D02*
X101900D01*
Y231167D01*
X102025Y231500D01*
X102317Y231750D01*
X102650Y231833D01*
X102983Y231750D01*
X103233Y231542D01*
X103358Y231167D01*
Y230167D01*
G01X104400Y233167D02*
X101900D01*
Y234208D01*
X102025Y234542D01*
X102192Y234750D01*
X102525Y234833D01*
X102858Y234750D01*
X103067Y234500D01*
X103192Y234208D01*
Y233167D01*
G01Y234208D02*
X104400Y234833D01*
G01Y237500D02*
X101900D01*
X103692Y235958D01*
Y238042D01*
G01X104400Y240000D02*
X101900D01*
X102400Y239500D01*
G01X104400D02*
Y240500D01*
G01X96267Y225300D02*
Y227800D01*
X97267D01*
X97600Y227675D01*
X97850Y227383D01*
X97933Y227050D01*
X97850Y226717D01*
X97642Y226467D01*
X97267Y226342D01*
X96267D01*
G01X99267Y225300D02*
Y227800D01*
X100308D01*
X100642Y227675D01*
X100850Y227508D01*
X100933Y227175D01*
X100850Y226842D01*
X100600Y226633D01*
X100308Y226508D01*
X99267D01*
G01X100308D02*
X100933Y225300D01*
G01X103600D02*
Y227800D01*
X102058Y226008D01*
X104142D01*
G01X105183Y225800D02*
X105433Y225508D01*
X105767Y225342D01*
X106142Y225300D01*
X106475Y225342D01*
X106808Y225550D01*
X107017Y225800D01*
X107058Y226050D01*
X106975Y226342D01*
X106683Y226550D01*
X106392Y226633D01*
X106017D01*
G01X106392D02*
X106642Y226758D01*
X106850Y226967D01*
X106933Y227217D01*
X106850Y227467D01*
X106642Y227675D01*
X106267Y227800D01*
X105892Y227758D01*
X105517Y227592D01*
G01X100500Y229967D02*
X98000D01*
Y230967D01*
X98125Y231300D01*
X98417Y231550D01*
X98750Y231633D01*
X99083Y231550D01*
X99333Y231342D01*
X99458Y230967D01*
Y229967D01*
G01X100500Y232967D02*
X98000D01*
Y234008D01*
X98125Y234342D01*
X98292Y234550D01*
X98625Y234633D01*
X98958Y234550D01*
X99167Y234300D01*
X99292Y234008D01*
Y232967D01*
G01Y234008D02*
X100500Y234633D01*
G01Y237300D02*
X98000D01*
X99792Y235758D01*
Y237842D01*
G01X98000Y239800D02*
X98083Y239467D01*
X98292Y239217D01*
X98542Y239050D01*
X98875Y238925D01*
X99250Y238883D01*
X99625Y238925D01*
X99958Y239050D01*
X100208Y239217D01*
X100417Y239467D01*
X100500Y239800D01*
X100417Y240133D01*
X100208Y240383D01*
X99958Y240550D01*
X99625Y240675D01*
X99250Y240717D01*
X98875Y240675D01*
X98542Y240550D01*
X98292Y240383D01*
X98083Y240133D01*
X98000Y239800D01*
G01X105867Y221200D02*
Y223700D01*
X106867D01*
X107200Y223575D01*
X107450Y223283D01*
X107533Y222950D01*
X107450Y222617D01*
X107242Y222367D01*
X106867Y222242D01*
X105867D01*
G01X110617Y223492D02*
X110367Y223617D01*
X110075Y223700D01*
X109742D01*
X109367Y223575D01*
X109075Y223367D01*
X108867Y223117D01*
X108700Y222700D01*
X108658Y222325D01*
X108742Y221950D01*
X108867Y221700D01*
X109117Y221450D01*
X109408Y221283D01*
X109700Y221200D01*
X109992D01*
X110283Y221283D01*
X110533Y221408D01*
X110742Y221575D01*
G01X113200Y221200D02*
Y223700D01*
X111658Y221908D01*
X113742D01*
G01X115700Y221200D02*
Y223700D01*
X115200Y223200D01*
G01Y221200D02*
X116200D01*
G01X93267D02*
Y223700D01*
X94267D01*
X94600Y223575D01*
X94850Y223283D01*
X94933Y222950D01*
X94850Y222617D01*
X94642Y222367D01*
X94267Y222242D01*
X93267D01*
G01X98017Y223492D02*
X97767Y223617D01*
X97475Y223700D01*
X97142D01*
X96767Y223575D01*
X96475Y223367D01*
X96267Y223117D01*
X96100Y222700D01*
X96058Y222325D01*
X96142Y221950D01*
X96267Y221700D01*
X96517Y221450D01*
X96808Y221283D01*
X97100Y221200D01*
X97392D01*
X97683Y221283D01*
X97933Y221408D01*
X98142Y221575D01*
G01X100600Y221200D02*
Y223700D01*
X99058Y221908D01*
X101142D01*
G01X102308Y223283D02*
X102558Y223533D01*
X102850Y223658D01*
X103183Y223700D01*
X103600Y223617D01*
X103892Y223408D01*
X103975Y223158D01*
X103933Y222908D01*
X103767Y222700D01*
X102933Y222283D01*
X102558Y221992D01*
X102308Y221575D01*
X102225Y221200D01*
X103975D01*
G01X119067Y218200D02*
Y220700D01*
X120067D01*
X120400Y220575D01*
X120650Y220283D01*
X120733Y219950D01*
X120650Y219617D01*
X120442Y219367D01*
X120067Y219242D01*
X119067D01*
G01X123817Y220492D02*
X123567Y220617D01*
X123275Y220700D01*
X122942D01*
X122567Y220575D01*
X122275Y220367D01*
X122067Y220117D01*
X121900Y219700D01*
X121858Y219325D01*
X121942Y218950D01*
X122067Y218700D01*
X122317Y218450D01*
X122608Y218283D01*
X122900Y218200D01*
X123192D01*
X123483Y218283D01*
X123733Y218408D01*
X123942Y218575D01*
G01X126400Y218200D02*
Y220700D01*
X124858Y218908D01*
X126942D01*
G01X128900Y220700D02*
X128567Y220617D01*
X128317Y220408D01*
X128150Y220158D01*
X128025Y219825D01*
X127983Y219450D01*
X128025Y219075D01*
X128150Y218742D01*
X128317Y218492D01*
X128567Y218283D01*
X128900Y218200D01*
X129233Y218283D01*
X129483Y218492D01*
X129650Y218742D01*
X129775Y219075D01*
X129817Y219450D01*
X129775Y219825D01*
X129650Y220158D01*
X129483Y220408D01*
X129233Y220617D01*
X128900Y220700D01*
G01X142817Y238692D02*
X142567Y238817D01*
X142275Y238900D01*
X141942D01*
X141567Y238775D01*
X141275Y238567D01*
X141067Y238317D01*
X140900Y237900D01*
X140858Y237525D01*
X140942Y237150D01*
X141067Y236900D01*
X141317Y236650D01*
X141608Y236483D01*
X141900Y236400D01*
X142192D01*
X142483Y236483D01*
X142733Y236608D01*
X142942Y236775D01*
G01X144108Y238483D02*
X144358Y238733D01*
X144650Y238858D01*
X144983Y238900D01*
X145400Y238817D01*
X145692Y238608D01*
X145775Y238358D01*
X145733Y238108D01*
X145567Y237900D01*
X144733Y237483D01*
X144358Y237192D01*
X144108Y236775D01*
X144025Y236400D01*
X145775D01*
G01X146983Y236775D02*
X147233Y236567D01*
X147525Y236442D01*
X147900Y236400D01*
X148275Y236483D01*
X148567Y236650D01*
X148775Y236942D01*
X148817Y237275D01*
X148733Y237608D01*
X148525Y237817D01*
X148233Y237983D01*
X147942Y238025D01*
X147650Y237983D01*
X147275Y237817D01*
X147400Y238900D01*
X148525D01*
G01X151400Y236400D02*
Y238900D01*
X149858Y237108D01*
X151942D01*
G01X119167Y221800D02*
Y224300D01*
X120167D01*
X120500Y224175D01*
X120750Y223883D01*
X120833Y223550D01*
X120750Y223217D01*
X120542Y222967D01*
X120167Y222842D01*
X119167D01*
G01X122167Y221800D02*
Y224300D01*
X123208D01*
X123542Y224175D01*
X123750Y224008D01*
X123833Y223675D01*
X123750Y223342D01*
X123500Y223133D01*
X123208Y223008D01*
X122167D01*
G01X123208D02*
X123833Y221800D01*
G01X125083Y222175D02*
X125333Y221967D01*
X125625Y221842D01*
X126000Y221800D01*
X126375Y221883D01*
X126667Y222050D01*
X126875Y222342D01*
X126917Y222675D01*
X126833Y223008D01*
X126625Y223217D01*
X126333Y223383D01*
X126042Y223425D01*
X125750Y223383D01*
X125375Y223217D01*
X125500Y224300D01*
X126625D01*
G01X129000D02*
X128667Y224217D01*
X128417Y224008D01*
X128250Y223758D01*
X128125Y223425D01*
X128083Y223050D01*
X128125Y222675D01*
X128250Y222342D01*
X128417Y222092D01*
X128667Y221883D01*
X129000Y221800D01*
X129333Y221883D01*
X129583Y222092D01*
X129750Y222342D01*
X129875Y222675D01*
X129917Y223050D01*
X129875Y223425D01*
X129750Y223758D01*
X129583Y224008D01*
X129333Y224217D01*
X129000Y224300D01*
G01X80367Y221200D02*
Y223700D01*
X81367D01*
X81700Y223575D01*
X81950Y223283D01*
X82033Y222950D01*
X81950Y222617D01*
X81742Y222367D01*
X81367Y222242D01*
X80367D01*
G01X83367Y221200D02*
Y223700D01*
X84408D01*
X84742Y223575D01*
X84950Y223408D01*
X85033Y223075D01*
X84950Y222742D01*
X84700Y222533D01*
X84408Y222408D01*
X83367D01*
G01X84408D02*
X85033Y221200D01*
G01X87700D02*
Y223700D01*
X86158Y221908D01*
X88242D01*
G01X89492Y221492D02*
X89783Y221283D01*
X90117Y221200D01*
X90450Y221283D01*
X90742Y221533D01*
X90950Y221908D01*
X91033Y222283D01*
Y222742D01*
X90950Y223117D01*
X90742Y223450D01*
X90492Y223617D01*
X90200Y223700D01*
X89867Y223617D01*
X89617Y223450D01*
X89450Y223200D01*
X89367Y222867D01*
X89450Y222575D01*
X89658Y222283D01*
X89908Y222117D01*
X90200Y222075D01*
X90533Y222158D01*
X90783Y222367D01*
X91033Y222742D01*
G01X89300Y225167D02*
X86800D01*
Y226167D01*
X86925Y226500D01*
X87217Y226750D01*
X87550Y226833D01*
X87883Y226750D01*
X88133Y226542D01*
X88258Y226167D01*
Y225167D01*
G01X89300Y228167D02*
X86800D01*
Y229208D01*
X86925Y229542D01*
X87092Y229750D01*
X87425Y229833D01*
X87758Y229750D01*
X87967Y229500D01*
X88092Y229208D01*
Y228167D01*
G01Y229208D02*
X89300Y229833D01*
G01Y232500D02*
X86800D01*
X88592Y230958D01*
Y233042D01*
G01X89300Y234917D02*
X88758Y235000D01*
X88300Y235125D01*
X87883Y235292D01*
X87425Y235500D01*
X86800Y235833D01*
Y234167D01*
G01X119067Y214600D02*
Y217100D01*
X120067D01*
X120400Y216975D01*
X120650Y216683D01*
X120733Y216350D01*
X120650Y216017D01*
X120442Y215767D01*
X120067Y215642D01*
X119067D01*
G01X122067Y214600D02*
Y217100D01*
X123108D01*
X123442Y216975D01*
X123650Y216808D01*
X123733Y216475D01*
X123650Y216142D01*
X123400Y215933D01*
X123108Y215808D01*
X122067D01*
G01X123108D02*
X123733Y214600D01*
G01X126400D02*
Y217100D01*
X124858Y215308D01*
X126942D01*
G01X128108Y216683D02*
X128358Y216933D01*
X128650Y217058D01*
X128983Y217100D01*
X129400Y217017D01*
X129692Y216808D01*
X129775Y216558D01*
X129733Y216308D01*
X129567Y216100D01*
X128733Y215683D01*
X128358Y215392D01*
X128108Y214975D01*
X128025Y214600D01*
X129775D01*
G01X118967Y210900D02*
Y213400D01*
X119967D01*
X120300Y213275D01*
X120550Y212983D01*
X120633Y212650D01*
X120550Y212317D01*
X120342Y212067D01*
X119967Y211942D01*
X118967D01*
G01X121967Y210900D02*
Y213400D01*
X123008D01*
X123342Y213275D01*
X123550Y213108D01*
X123633Y212775D01*
X123550Y212442D01*
X123300Y212233D01*
X123008Y212108D01*
X121967D01*
G01X123008D02*
X123633Y210900D01*
G01X126300D02*
Y213400D01*
X124758Y211608D01*
X126842D01*
G01X129300Y210900D02*
Y213400D01*
X127758Y211608D01*
X129842D01*
G01X142467Y211300D02*
Y213800D01*
X143467D01*
X143800Y213675D01*
X144050Y213383D01*
X144133Y213050D01*
X144050Y212717D01*
X143842Y212467D01*
X143467Y212342D01*
X142467D01*
G01X145467Y211300D02*
Y213800D01*
X146508D01*
X146842Y213675D01*
X147050Y213508D01*
X147133Y213175D01*
X147050Y212842D01*
X146800Y212633D01*
X146508Y212508D01*
X145467D01*
G01X146508D02*
X147133Y211300D01*
G01X148383Y211800D02*
X148633Y211508D01*
X148967Y211342D01*
X149342Y211300D01*
X149675Y211342D01*
X150008Y211550D01*
X150217Y211800D01*
X150258Y212050D01*
X150175Y212342D01*
X149883Y212550D01*
X149592Y212633D01*
X149217D01*
G01X149592D02*
X149842Y212758D01*
X150050Y212967D01*
X150133Y213217D01*
X150050Y213467D01*
X149842Y213675D01*
X149467Y213800D01*
X149092Y213758D01*
X148717Y213592D01*
G01X151592Y211592D02*
X151883Y211383D01*
X152217Y211300D01*
X152550Y211383D01*
X152842Y211633D01*
X153050Y212008D01*
X153133Y212383D01*
Y212842D01*
X153050Y213217D01*
X152842Y213550D01*
X152592Y213717D01*
X152300Y213800D01*
X151967Y213717D01*
X151717Y213550D01*
X151550Y213300D01*
X151467Y212967D01*
X151550Y212675D01*
X151758Y212383D01*
X152008Y212217D01*
X152300Y212175D01*
X152633Y212258D01*
X152883Y212467D01*
X153133Y212842D01*
G01X97883Y298400D02*
Y296608D01*
X98050Y296233D01*
X98383Y295983D01*
X98800Y295900D01*
X99217Y295983D01*
X99550Y296233D01*
X99717Y296608D01*
Y298400D01*
G01X100883Y296400D02*
X101133Y296108D01*
X101467Y295942D01*
X101842Y295900D01*
X102175Y295942D01*
X102508Y296150D01*
X102717Y296400D01*
X102758Y296650D01*
X102675Y296942D01*
X102383Y297150D01*
X102092Y297233D01*
X101717D01*
G01X102092D02*
X102342Y297358D01*
X102550Y297567D01*
X102633Y297817D01*
X102550Y298067D01*
X102342Y298275D01*
X101967Y298400D01*
X101592Y298358D01*
X101217Y298192D01*
G01X146608Y317517D02*
X146483Y317267D01*
X146400Y316975D01*
Y316642D01*
X146525Y316267D01*
X146733Y315975D01*
X146983Y315767D01*
X147400Y315600D01*
X147775Y315558D01*
X148150Y315642D01*
X148400Y315767D01*
X148650Y316017D01*
X148817Y316308D01*
X148900Y316600D01*
Y316892D01*
X148817Y317183D01*
X148692Y317433D01*
X148525Y317642D01*
G01X148608Y318892D02*
X148817Y319183D01*
X148900Y319517D01*
X148817Y319850D01*
X148567Y320142D01*
X148192Y320350D01*
X147817Y320433D01*
X147358D01*
X146983Y320350D01*
X146650Y320142D01*
X146483Y319892D01*
X146400Y319600D01*
X146483Y319267D01*
X146650Y319017D01*
X146900Y318850D01*
X147233Y318767D01*
X147525Y318850D01*
X147817Y319058D01*
X147983Y319308D01*
X148025Y319600D01*
X147942Y319933D01*
X147733Y320183D01*
X147358Y320433D01*
G01X143008Y317517D02*
X142883Y317267D01*
X142800Y316975D01*
Y316642D01*
X142925Y316267D01*
X143133Y315975D01*
X143383Y315767D01*
X143800Y315600D01*
X144175Y315558D01*
X144550Y315642D01*
X144800Y315767D01*
X145050Y316017D01*
X145217Y316308D01*
X145300Y316600D01*
Y316892D01*
X145217Y317183D01*
X145092Y317433D01*
X144925Y317642D01*
G01X145300Y319600D02*
X145258Y319892D01*
X145133Y320225D01*
X144925Y320433D01*
X144633Y320517D01*
X144342Y320433D01*
X144092Y320183D01*
X143967Y319808D01*
Y319392D01*
X143883Y319142D01*
X143675Y318933D01*
X143383Y318850D01*
X143092Y318975D01*
X142883Y319267D01*
X142800Y319600D01*
X142883Y319933D01*
X143092Y320225D01*
X143383Y320350D01*
X143675Y320267D01*
X143883Y320058D01*
X143967Y319808D01*
Y319392D01*
X144092Y319017D01*
X144342Y318767D01*
X144633Y318683D01*
X144925Y318767D01*
X145133Y318975D01*
X145258Y319308D01*
X145300Y319600D01*
G01X134808Y322517D02*
X134683Y322267D01*
X134600Y321975D01*
Y321642D01*
X134725Y321267D01*
X134933Y320975D01*
X135183Y320767D01*
X135600Y320600D01*
X135975Y320558D01*
X136350Y320642D01*
X136600Y320767D01*
X136850Y321017D01*
X137017Y321308D01*
X137100Y321600D01*
Y321892D01*
X137017Y322183D01*
X136892Y322433D01*
X136725Y322642D01*
G01X137100Y324517D02*
X136558Y324600D01*
X136100Y324725D01*
X135683Y324892D01*
X135225Y325100D01*
X134600Y325433D01*
Y323767D01*
G01X130908Y322617D02*
X130783Y322367D01*
X130700Y322075D01*
Y321742D01*
X130825Y321367D01*
X131033Y321075D01*
X131283Y320867D01*
X131700Y320700D01*
X132075Y320658D01*
X132450Y320742D01*
X132700Y320867D01*
X132950Y321117D01*
X133117Y321408D01*
X133200Y321700D01*
Y321992D01*
X133117Y322283D01*
X132992Y322533D01*
X132825Y322742D01*
G01X132158Y323908D02*
X131867Y324200D01*
X131700Y324450D01*
X131617Y324783D01*
X131700Y325075D01*
X131867Y325283D01*
X132117Y325450D01*
X132408Y325492D01*
X132658Y325450D01*
X132908Y325283D01*
X133117Y325033D01*
X133200Y324742D01*
X133117Y324408D01*
X132867Y324117D01*
X132492Y323950D01*
X132075Y323908D01*
X131533Y323992D01*
X131242Y324117D01*
X130950Y324325D01*
X130742Y324617D01*
X130700Y324908D01*
X130783Y325200D01*
X130992Y325408D01*
G01X124008Y318217D02*
X123883Y317967D01*
X123800Y317675D01*
Y317342D01*
X123925Y316967D01*
X124133Y316675D01*
X124383Y316467D01*
X124800Y316300D01*
X125175Y316258D01*
X125550Y316342D01*
X125800Y316467D01*
X126050Y316717D01*
X126217Y317008D01*
X126300Y317300D01*
Y317592D01*
X126217Y317883D01*
X126092Y318133D01*
X125925Y318342D01*
G01Y319383D02*
X126133Y319633D01*
X126258Y319925D01*
X126300Y320300D01*
X126217Y320675D01*
X126050Y320967D01*
X125758Y321175D01*
X125425Y321217D01*
X125092Y321133D01*
X124883Y320925D01*
X124717Y320633D01*
X124675Y320342D01*
X124717Y320050D01*
X124883Y319675D01*
X123800Y319800D01*
Y320925D01*
G01X120008Y318417D02*
X119883Y318167D01*
X119800Y317875D01*
Y317542D01*
X119925Y317167D01*
X120133Y316875D01*
X120383Y316667D01*
X120800Y316500D01*
X121175Y316458D01*
X121550Y316542D01*
X121800Y316667D01*
X122050Y316917D01*
X122217Y317208D01*
X122300Y317500D01*
Y317792D01*
X122217Y318083D01*
X122092Y318333D01*
X121925Y318542D01*
G01X122300Y321000D02*
X119800D01*
X121592Y319458D01*
Y321542D01*
G01X138700Y321867D02*
X141200D01*
Y323533D01*
G01X140158Y324908D02*
X139867Y325200D01*
X139700Y325450D01*
X139617Y325783D01*
X139700Y326075D01*
X139867Y326283D01*
X140117Y326450D01*
X140408Y326492D01*
X140658Y326450D01*
X140908Y326283D01*
X141117Y326033D01*
X141200Y325742D01*
X141117Y325408D01*
X140867Y325117D01*
X140492Y324950D01*
X140075Y324908D01*
X139533Y324992D01*
X139242Y325117D01*
X138950Y325325D01*
X138742Y325617D01*
X138700Y325908D01*
X138783Y326200D01*
X138992Y326408D01*
G01X136067Y341800D02*
Y339300D01*
X137733D01*
G01X138983Y339675D02*
X139233Y339467D01*
X139525Y339342D01*
X139900Y339300D01*
X140275Y339383D01*
X140567Y339550D01*
X140775Y339842D01*
X140817Y340175D01*
X140733Y340508D01*
X140525Y340717D01*
X140233Y340883D01*
X139942Y340925D01*
X139650Y340883D01*
X139275Y340717D01*
X139400Y341800D01*
X140525D01*
G01X126867Y341600D02*
Y339100D01*
X128533D01*
G01X131200D02*
Y341600D01*
X129658Y339808D01*
X131742D01*
G01X127000Y324067D02*
X129500D01*
Y325733D01*
G01X129000Y326983D02*
X129292Y327233D01*
X129458Y327567D01*
X129500Y327942D01*
X129458Y328275D01*
X129250Y328608D01*
X129000Y328817D01*
X128750Y328858D01*
X128458Y328775D01*
X128250Y328483D01*
X128167Y328192D01*
Y327817D01*
G01Y328192D02*
X128042Y328442D01*
X127833Y328650D01*
X127583Y328733D01*
X127333Y328650D01*
X127125Y328442D01*
X127000Y328067D01*
X127042Y327692D01*
X127208Y327317D01*
G01X109467Y332900D02*
Y330400D01*
X111133D01*
G01X112508Y332483D02*
X112758Y332733D01*
X113050Y332858D01*
X113383Y332900D01*
X113800Y332817D01*
X114092Y332608D01*
X114175Y332358D01*
X114133Y332108D01*
X113967Y331900D01*
X113133Y331483D01*
X112758Y331192D01*
X112508Y330775D01*
X112425Y330400D01*
X114175D01*
G01X121783Y503900D02*
Y502108D01*
X121950Y501733D01*
X122283Y501483D01*
X122700Y501400D01*
X123117Y501483D01*
X123450Y501733D01*
X123617Y502108D01*
Y503900D01*
G01X125700Y501400D02*
Y503900D01*
X125200Y503400D01*
G01Y501400D02*
X126200D01*
G01X135982Y530166D02*
X135857Y529916D01*
X135774Y529624D01*
Y529291D01*
X135899Y528916D01*
X136107Y528624D01*
X136357Y528416D01*
X136774Y528249D01*
X137149Y528207D01*
X137524Y528291D01*
X137774Y528416D01*
X138024Y528666D01*
X138191Y528957D01*
X138274Y529249D01*
Y529541D01*
X138191Y529832D01*
X138066Y530082D01*
X137899Y530291D01*
G01X136191Y531457D02*
X135941Y531707D01*
X135816Y531999D01*
X135774Y532332D01*
X135857Y532749D01*
X136066Y533041D01*
X136316Y533124D01*
X136566Y533082D01*
X136774Y532916D01*
X137191Y532082D01*
X137482Y531707D01*
X137899Y531457D01*
X138274Y531374D01*
Y533124D01*
G01Y535749D02*
X135774D01*
X137566Y534207D01*
Y536291D01*
G01X138274Y538166D02*
X137732Y538249D01*
X137274Y538374D01*
X136857Y538541D01*
X136399Y538749D01*
X135774Y539082D01*
Y537416D01*
G01X132085Y530409D02*
X131960Y530159D01*
X131877Y529867D01*
Y529534D01*
X132002Y529159D01*
X132210Y528867D01*
X132460Y528659D01*
X132877Y528492D01*
X133252Y528450D01*
X133627Y528534D01*
X133877Y528659D01*
X134127Y528909D01*
X134294Y529200D01*
X134377Y529492D01*
Y529784D01*
X134294Y530075D01*
X134169Y530325D01*
X134002Y530534D01*
G01X132294Y531700D02*
X132044Y531950D01*
X131919Y532242D01*
X131877Y532575D01*
X131960Y532992D01*
X132169Y533284D01*
X132419Y533367D01*
X132669Y533325D01*
X132877Y533159D01*
X133294Y532325D01*
X133585Y531950D01*
X134002Y531700D01*
X134377Y531617D01*
Y533367D01*
G01X134002Y534575D02*
X134210Y534825D01*
X134335Y535117D01*
X134377Y535492D01*
X134294Y535867D01*
X134127Y536159D01*
X133835Y536367D01*
X133502Y536409D01*
X133169Y536325D01*
X132960Y536117D01*
X132794Y535825D01*
X132752Y535534D01*
X132794Y535242D01*
X132960Y534867D01*
X131877Y534992D01*
Y536117D01*
G01X132294Y537700D02*
X132044Y537950D01*
X131919Y538242D01*
X131877Y538575D01*
X131960Y538992D01*
X132169Y539284D01*
X132419Y539367D01*
X132669Y539325D01*
X132877Y539159D01*
X133294Y538325D01*
X133585Y537950D01*
X134002Y537700D01*
X134377Y537617D01*
Y539367D01*
G01X147295Y534151D02*
X147170Y533901D01*
X147087Y533609D01*
Y533276D01*
X147212Y532901D01*
X147420Y532609D01*
X147670Y532401D01*
X148087Y532234D01*
X148462Y532192D01*
X148837Y532276D01*
X149087Y532401D01*
X149337Y532651D01*
X149504Y532942D01*
X149587Y533234D01*
Y533526D01*
X149504Y533817D01*
X149379Y534067D01*
X149212Y534276D01*
G01X149587Y536734D02*
X147087D01*
X148879Y535192D01*
Y537276D01*
G01X147087Y539234D02*
X147170Y538901D01*
X147379Y538651D01*
X147629Y538484D01*
X147962Y538359D01*
X148337Y538317D01*
X148712Y538359D01*
X149045Y538484D01*
X149295Y538651D01*
X149504Y538901D01*
X149587Y539234D01*
X149504Y539567D01*
X149295Y539817D01*
X149045Y539984D01*
X148712Y540109D01*
X148337Y540151D01*
X147962Y540109D01*
X147629Y539984D01*
X147379Y539817D01*
X147170Y539567D01*
X147087Y539234D01*
G01X142667Y534314D02*
X142542Y534064D01*
X142459Y533772D01*
Y533439D01*
X142584Y533064D01*
X142792Y532772D01*
X143042Y532564D01*
X143459Y532397D01*
X143834Y532355D01*
X144209Y532439D01*
X144459Y532564D01*
X144709Y532814D01*
X144876Y533105D01*
X144959Y533397D01*
Y533689D01*
X144876Y533980D01*
X144751Y534230D01*
X144584Y534439D01*
G01X144959Y536897D02*
X142459D01*
X144251Y535355D01*
Y537439D01*
G01X144959Y539397D02*
X142459D01*
X142959Y538897D01*
G01X144959D02*
Y539897D01*
G01X124800Y534422D02*
X124675Y534172D01*
X124592Y533880D01*
Y533547D01*
X124717Y533172D01*
X124925Y532880D01*
X125175Y532672D01*
X125592Y532505D01*
X125967Y532463D01*
X126342Y532547D01*
X126592Y532672D01*
X126842Y532922D01*
X127009Y533213D01*
X127092Y533505D01*
Y533797D01*
X127009Y534088D01*
X126884Y534338D01*
X126717Y534547D01*
G01X127092Y537005D02*
X124592D01*
X126384Y535463D01*
Y537547D01*
G01X125009Y538713D02*
X124759Y538963D01*
X124634Y539255D01*
X124592Y539588D01*
X124675Y540005D01*
X124884Y540297D01*
X125134Y540380D01*
X125384Y540338D01*
X125592Y540172D01*
X126009Y539338D01*
X126300Y538963D01*
X126717Y538713D01*
X127092Y538630D01*
Y540380D01*
G01X120578Y534666D02*
X120453Y534416D01*
X120370Y534124D01*
Y533791D01*
X120495Y533416D01*
X120703Y533124D01*
X120953Y532916D01*
X121370Y532749D01*
X121745Y532707D01*
X122120Y532791D01*
X122370Y532916D01*
X122620Y533166D01*
X122787Y533457D01*
X122870Y533749D01*
Y534041D01*
X122787Y534332D01*
X122662Y534582D01*
X122495Y534791D01*
G01X122870Y537249D02*
X120370D01*
X122162Y535707D01*
Y537791D01*
G01X122370Y538832D02*
X122662Y539082D01*
X122828Y539416D01*
X122870Y539791D01*
X122828Y540124D01*
X122620Y540457D01*
X122370Y540666D01*
X122120Y540707D01*
X121828Y540624D01*
X121620Y540332D01*
X121537Y540041D01*
Y539666D01*
G01Y540041D02*
X121412Y540291D01*
X121203Y540499D01*
X120953Y540582D01*
X120703Y540499D01*
X120495Y540291D01*
X120370Y539916D01*
X120412Y539541D01*
X120578Y539166D01*
G01X113108Y530617D02*
X112983Y530367D01*
X112900Y530075D01*
Y529742D01*
X113025Y529367D01*
X113233Y529075D01*
X113483Y528867D01*
X113900Y528700D01*
X114275Y528658D01*
X114650Y528742D01*
X114900Y528867D01*
X115150Y529117D01*
X115317Y529408D01*
X115400Y529700D01*
Y529992D01*
X115317Y530283D01*
X115192Y530533D01*
X115025Y530742D01*
G01X115400Y533200D02*
X112900D01*
X114692Y531658D01*
Y533742D01*
G01X115400Y536200D02*
X112900D01*
X114692Y534658D01*
Y536742D01*
G01X109108Y530617D02*
X108983Y530367D01*
X108900Y530075D01*
Y529742D01*
X109025Y529367D01*
X109233Y529075D01*
X109483Y528867D01*
X109900Y528700D01*
X110275Y528658D01*
X110650Y528742D01*
X110900Y528867D01*
X111150Y529117D01*
X111317Y529408D01*
X111400Y529700D01*
Y529992D01*
X111317Y530283D01*
X111192Y530533D01*
X111025Y530742D01*
G01X111400Y533200D02*
X108900D01*
X110692Y531658D01*
Y533742D01*
G01X111025Y534783D02*
X111233Y535033D01*
X111358Y535325D01*
X111400Y535700D01*
X111317Y536075D01*
X111150Y536367D01*
X110858Y536575D01*
X110525Y536617D01*
X110192Y536533D01*
X109983Y536325D01*
X109817Y536033D01*
X109775Y535742D01*
X109817Y535450D01*
X109983Y535075D01*
X108900Y535200D01*
Y536325D01*
G01X102008Y534317D02*
X101883Y534067D01*
X101800Y533775D01*
Y533442D01*
X101925Y533067D01*
X102133Y532775D01*
X102383Y532567D01*
X102800Y532400D01*
X103175Y532358D01*
X103550Y532442D01*
X103800Y532567D01*
X104050Y532817D01*
X104217Y533108D01*
X104300Y533400D01*
Y533692D01*
X104217Y533983D01*
X104092Y534233D01*
X103925Y534442D01*
G01X104300Y536900D02*
X101800D01*
X103592Y535358D01*
Y537442D01*
G01X103258Y538608D02*
X102967Y538900D01*
X102800Y539150D01*
X102717Y539483D01*
X102800Y539775D01*
X102967Y539983D01*
X103217Y540150D01*
X103508Y540192D01*
X103758Y540150D01*
X104008Y539983D01*
X104217Y539733D01*
X104300Y539442D01*
X104217Y539108D01*
X103967Y538817D01*
X103592Y538650D01*
X103175Y538608D01*
X102633Y538692D01*
X102342Y538817D01*
X102050Y539025D01*
X101842Y539317D01*
X101800Y539608D01*
X101883Y539900D01*
X102092Y540108D01*
G01X98508Y534217D02*
X98383Y533967D01*
X98300Y533675D01*
Y533342D01*
X98425Y532967D01*
X98633Y532675D01*
X98883Y532467D01*
X99300Y532300D01*
X99675Y532258D01*
X100050Y532342D01*
X100300Y532467D01*
X100550Y532717D01*
X100717Y533008D01*
X100800Y533300D01*
Y533592D01*
X100717Y533883D01*
X100592Y534133D01*
X100425Y534342D01*
G01X100800Y536800D02*
X98300D01*
X100092Y535258D01*
Y537342D01*
G01X100800Y539217D02*
X100258Y539300D01*
X99800Y539425D01*
X99383Y539592D01*
X98925Y539800D01*
X98300Y540133D01*
Y538467D01*
G01X91108Y530517D02*
X90983Y530267D01*
X90900Y529975D01*
Y529642D01*
X91025Y529267D01*
X91233Y528975D01*
X91483Y528767D01*
X91900Y528600D01*
X92275Y528558D01*
X92650Y528642D01*
X92900Y528767D01*
X93150Y529017D01*
X93317Y529308D01*
X93400Y529600D01*
Y529892D01*
X93317Y530183D01*
X93192Y530433D01*
X93025Y530642D01*
G01X93400Y533100D02*
X90900D01*
X92692Y531558D01*
Y533642D01*
G01X93400Y535600D02*
X93358Y535892D01*
X93233Y536225D01*
X93025Y536433D01*
X92733Y536517D01*
X92442Y536433D01*
X92192Y536183D01*
X92067Y535808D01*
Y535392D01*
X91983Y535142D01*
X91775Y534933D01*
X91483Y534850D01*
X91192Y534975D01*
X90983Y535267D01*
X90900Y535600D01*
X90983Y535933D01*
X91192Y536225D01*
X91483Y536350D01*
X91775Y536267D01*
X91983Y536058D01*
X92067Y535808D01*
Y535392D01*
X92192Y535017D01*
X92442Y534767D01*
X92733Y534683D01*
X93025Y534767D01*
X93233Y534975D01*
X93358Y535308D01*
X93400Y535600D01*
G01X87208Y530617D02*
X87083Y530367D01*
X87000Y530075D01*
Y529742D01*
X87125Y529367D01*
X87333Y529075D01*
X87583Y528867D01*
X88000Y528700D01*
X88375Y528658D01*
X88750Y528742D01*
X89000Y528867D01*
X89250Y529117D01*
X89417Y529408D01*
X89500Y529700D01*
Y529992D01*
X89417Y530283D01*
X89292Y530533D01*
X89125Y530742D01*
G01X89500Y533200D02*
X87000D01*
X88792Y531658D01*
Y533742D01*
G01X89208Y534992D02*
X89417Y535283D01*
X89500Y535617D01*
X89417Y535950D01*
X89167Y536242D01*
X88792Y536450D01*
X88417Y536533D01*
X87958D01*
X87583Y536450D01*
X87250Y536242D01*
X87083Y535992D01*
X87000Y535700D01*
X87083Y535367D01*
X87250Y535117D01*
X87500Y534950D01*
X87833Y534867D01*
X88125Y534950D01*
X88417Y535158D01*
X88583Y535408D01*
X88625Y535700D01*
X88542Y536033D01*
X88333Y536283D01*
X87958Y536533D01*
G01X79976Y533911D02*
X79851Y533661D01*
X79768Y533369D01*
Y533036D01*
X79893Y532661D01*
X80101Y532369D01*
X80351Y532161D01*
X80768Y531994D01*
X81143Y531952D01*
X81518Y532036D01*
X81768Y532161D01*
X82018Y532411D01*
X82185Y532702D01*
X82268Y532994D01*
Y533286D01*
X82185Y533577D01*
X82060Y533827D01*
X81893Y534036D01*
G01Y535077D02*
X82101Y535327D01*
X82226Y535619D01*
X82268Y535994D01*
X82185Y536369D01*
X82018Y536661D01*
X81726Y536869D01*
X81393Y536911D01*
X81060Y536827D01*
X80851Y536619D01*
X80685Y536327D01*
X80643Y536036D01*
X80685Y535744D01*
X80851Y535369D01*
X79768Y535494D01*
Y536619D01*
G01Y538994D02*
X79851Y538661D01*
X80060Y538411D01*
X80310Y538244D01*
X80643Y538119D01*
X81018Y538077D01*
X81393Y538119D01*
X81726Y538244D01*
X81976Y538411D01*
X82185Y538661D01*
X82268Y538994D01*
X82185Y539327D01*
X81976Y539577D01*
X81726Y539744D01*
X81393Y539869D01*
X81018Y539911D01*
X80643Y539869D01*
X80310Y539744D01*
X80060Y539577D01*
X79851Y539327D01*
X79768Y538994D01*
G01X126867Y510800D02*
Y508300D01*
X128533D01*
G01X129908Y509342D02*
X130200Y509633D01*
X130450Y509800D01*
X130783Y509883D01*
X131075Y509800D01*
X131283Y509633D01*
X131450Y509383D01*
X131492Y509092D01*
X131450Y508842D01*
X131283Y508592D01*
X131033Y508383D01*
X130742Y508300D01*
X130408Y508383D01*
X130117Y508633D01*
X129950Y509008D01*
X129908Y509425D01*
X129992Y509967D01*
X130117Y510258D01*
X130325Y510550D01*
X130617Y510758D01*
X130908Y510800D01*
X131200Y510717D01*
X131408Y510508D01*
G01X133617Y508300D02*
X133700Y508842D01*
X133825Y509300D01*
X133992Y509717D01*
X134200Y510175D01*
X134533Y510800D01*
X132867D01*
G01X136967D02*
Y508300D01*
X138633D01*
G01X140008Y509342D02*
X140300Y509633D01*
X140550Y509800D01*
X140883Y509883D01*
X141175Y509800D01*
X141383Y509633D01*
X141550Y509383D01*
X141592Y509092D01*
X141550Y508842D01*
X141383Y508592D01*
X141133Y508383D01*
X140842Y508300D01*
X140508Y508383D01*
X140217Y508633D01*
X140050Y509008D01*
X140008Y509425D01*
X140092Y509967D01*
X140217Y510258D01*
X140425Y510550D01*
X140717Y510758D01*
X141008Y510800D01*
X141300Y510717D01*
X141508Y510508D01*
G01X143008Y509342D02*
X143300Y509633D01*
X143550Y509800D01*
X143883Y509883D01*
X144175Y509800D01*
X144383Y509633D01*
X144550Y509383D01*
X144592Y509092D01*
X144550Y508842D01*
X144383Y508592D01*
X144133Y508383D01*
X143842Y508300D01*
X143508Y508383D01*
X143217Y508633D01*
X143050Y509008D01*
X143008Y509425D01*
X143092Y509967D01*
X143217Y510258D01*
X143425Y510550D01*
X143717Y510758D01*
X144008Y510800D01*
X144300Y510717D01*
X144508Y510508D01*
G01X81067Y514300D02*
Y511800D01*
X82733D01*
G01X85400D02*
Y514300D01*
X83858Y512508D01*
X85942D01*
G01X87900Y511800D02*
X88192Y511842D01*
X88525Y511967D01*
X88733Y512175D01*
X88817Y512467D01*
X88733Y512758D01*
X88483Y513008D01*
X88108Y513133D01*
X87692D01*
X87442Y513217D01*
X87233Y513425D01*
X87150Y513717D01*
X87275Y514008D01*
X87567Y514217D01*
X87900Y514300D01*
X88233Y514217D01*
X88525Y514008D01*
X88650Y513717D01*
X88567Y513425D01*
X88358Y513217D01*
X88108Y513133D01*
X87692D01*
X87317Y513008D01*
X87067Y512758D01*
X86983Y512467D01*
X87067Y512175D01*
X87275Y511967D01*
X87608Y511842D01*
X87900Y511800D01*
G01X81367Y510300D02*
Y507800D01*
X83033D01*
G01X85700D02*
Y510300D01*
X84158Y508508D01*
X86242D01*
G01X88117Y507800D02*
X88200Y508342D01*
X88325Y508800D01*
X88492Y509217D01*
X88700Y509675D01*
X89033Y510300D01*
X87367D01*
G01X93567Y510600D02*
Y508100D01*
X95233D01*
G01X97900D02*
Y510600D01*
X96358Y508808D01*
X98442D01*
G01X99608Y509142D02*
X99900Y509433D01*
X100150Y509600D01*
X100483Y509683D01*
X100775Y509600D01*
X100983Y509433D01*
X101150Y509183D01*
X101192Y508892D01*
X101150Y508642D01*
X100983Y508392D01*
X100733Y508183D01*
X100442Y508100D01*
X100108Y508183D01*
X99817Y508433D01*
X99650Y508808D01*
X99608Y509225D01*
X99692Y509767D01*
X99817Y510058D01*
X100025Y510350D01*
X100317Y510558D01*
X100608Y510600D01*
X100900Y510517D01*
X101108Y510308D01*
G01X93867Y514600D02*
Y512100D01*
X95533D01*
G01X98200D02*
Y514600D01*
X96658Y512808D01*
X98742D01*
G01X99783Y512475D02*
X100033Y512267D01*
X100325Y512142D01*
X100700Y512100D01*
X101075Y512183D01*
X101367Y512350D01*
X101575Y512642D01*
X101617Y512975D01*
X101533Y513308D01*
X101325Y513517D01*
X101033Y513683D01*
X100742Y513725D01*
X100450Y513683D01*
X100075Y513517D01*
X100200Y514600D01*
X101325D01*
G01X104767Y514500D02*
Y512000D01*
X106433D01*
G01X109100D02*
Y514500D01*
X107558Y512708D01*
X109642D01*
G01X112100Y512000D02*
Y514500D01*
X110558Y512708D01*
X112642D01*
G01X105467Y510800D02*
Y508300D01*
X107133D01*
G01X109800D02*
Y510800D01*
X108258Y509008D01*
X110342D01*
G01X111383Y508800D02*
X111633Y508508D01*
X111967Y508342D01*
X112342Y508300D01*
X112675Y508342D01*
X113008Y508550D01*
X113217Y508800D01*
X113258Y509050D01*
X113175Y509342D01*
X112883Y509550D01*
X112592Y509633D01*
X112217D01*
G01X112592D02*
X112842Y509758D01*
X113050Y509967D01*
X113133Y510217D01*
X113050Y510467D01*
X112842Y510675D01*
X112467Y510800D01*
X112092Y510758D01*
X111717Y510592D01*
G01X116267Y511000D02*
Y508500D01*
X117933D01*
G01X120600D02*
Y511000D01*
X119058Y509208D01*
X121142D01*
G01X122308Y510583D02*
X122558Y510833D01*
X122850Y510958D01*
X123183Y511000D01*
X123600Y510917D01*
X123892Y510708D01*
X123975Y510458D01*
X123933Y510208D01*
X123767Y510000D01*
X122933Y509583D01*
X122558Y509292D01*
X122308Y508875D01*
X122225Y508500D01*
X123975D01*
G01X117067Y514900D02*
Y512400D01*
X118733D01*
G01X121400D02*
Y514900D01*
X119858Y513108D01*
X121942D01*
G01X123900Y512400D02*
Y514900D01*
X123400Y514400D01*
G01Y512400D02*
X124400D01*
G01X126867Y514800D02*
Y512300D01*
X128533D01*
G01X131200D02*
Y514800D01*
X129658Y513008D01*
X131742D01*
G01X133700Y514800D02*
X133367Y514717D01*
X133117Y514508D01*
X132950Y514258D01*
X132825Y513925D01*
X132783Y513550D01*
X132825Y513175D01*
X132950Y512842D01*
X133117Y512592D01*
X133367Y512383D01*
X133700Y512300D01*
X134033Y512383D01*
X134283Y512592D01*
X134450Y512842D01*
X134575Y513175D01*
X134617Y513550D01*
X134575Y513925D01*
X134450Y514258D01*
X134283Y514508D01*
X134033Y514717D01*
X133700Y514800D01*
G01X137667Y514600D02*
Y512100D01*
X139333D01*
G01X140583Y512600D02*
X140833Y512308D01*
X141167Y512142D01*
X141542Y512100D01*
X141875Y512142D01*
X142208Y512350D01*
X142417Y512600D01*
X142458Y512850D01*
X142375Y513142D01*
X142083Y513350D01*
X141792Y513433D01*
X141417D01*
G01X141792D02*
X142042Y513558D01*
X142250Y513767D01*
X142333Y514017D01*
X142250Y514267D01*
X142042Y514475D01*
X141667Y514600D01*
X141292Y514558D01*
X140917Y514392D01*
G01X143792Y512392D02*
X144083Y512183D01*
X144417Y512100D01*
X144750Y512183D01*
X145042Y512433D01*
X145250Y512808D01*
X145333Y513183D01*
Y513642D01*
X145250Y514017D01*
X145042Y514350D01*
X144792Y514517D01*
X144500Y514600D01*
X144167Y514517D01*
X143917Y514350D01*
X143750Y514100D01*
X143667Y513767D01*
X143750Y513475D01*
X143958Y513183D01*
X144208Y513017D01*
X144500Y512975D01*
X144833Y513058D01*
X145083Y513267D01*
X145333Y513642D01*
G01X147967Y514700D02*
Y512200D01*
X149633D01*
G01X150883Y512700D02*
X151133Y512408D01*
X151467Y512242D01*
X151842Y512200D01*
X152175Y512242D01*
X152508Y512450D01*
X152717Y512700D01*
X152758Y512950D01*
X152675Y513242D01*
X152383Y513450D01*
X152092Y513533D01*
X151717D01*
G01X152092D02*
X152342Y513658D01*
X152550Y513867D01*
X152633Y514117D01*
X152550Y514367D01*
X152342Y514575D01*
X151967Y514700D01*
X151592Y514658D01*
X151217Y514492D01*
G01X154800Y512200D02*
X155092Y512242D01*
X155425Y512367D01*
X155633Y512575D01*
X155717Y512867D01*
X155633Y513158D01*
X155383Y513408D01*
X155008Y513533D01*
X154592D01*
X154342Y513617D01*
X154133Y513825D01*
X154050Y514117D01*
X154175Y514408D01*
X154467Y514617D01*
X154800Y514700D01*
X155133Y514617D01*
X155425Y514408D01*
X155550Y514117D01*
X155467Y513825D01*
X155258Y513617D01*
X155008Y513533D01*
X154592D01*
X154217Y513408D01*
X153967Y513158D01*
X153883Y512867D01*
X153967Y512575D01*
X154175Y512367D01*
X154508Y512242D01*
X154800Y512200D01*
G01X148867Y511000D02*
Y508500D01*
X150533D01*
G01X151783Y509000D02*
X152033Y508708D01*
X152367Y508542D01*
X152742Y508500D01*
X153075Y508542D01*
X153408Y508750D01*
X153617Y509000D01*
X153658Y509250D01*
X153575Y509542D01*
X153283Y509750D01*
X152992Y509833D01*
X152617D01*
G01X152992D02*
X153242Y509958D01*
X153450Y510167D01*
X153533Y510417D01*
X153450Y510667D01*
X153242Y510875D01*
X152867Y511000D01*
X152492Y510958D01*
X152117Y510792D01*
G01X155617Y508500D02*
X155700Y509042D01*
X155825Y509500D01*
X155992Y509917D01*
X156200Y510375D01*
X156533Y511000D01*
X154867D01*
G01X93299Y586332D02*
X93174Y586082D01*
X93091Y585790D01*
Y585457D01*
X93216Y585082D01*
X93424Y584790D01*
X93674Y584582D01*
X94091Y584415D01*
X94466Y584373D01*
X94841Y584457D01*
X95091Y584582D01*
X95341Y584832D01*
X95508Y585123D01*
X95591Y585415D01*
Y585707D01*
X95508Y585998D01*
X95383Y586248D01*
X95216Y586457D01*
G01X95591Y587457D02*
X93091D01*
X95591Y589373D01*
X93091D01*
G01X95091Y590498D02*
X95383Y590748D01*
X95549Y591082D01*
X95591Y591457D01*
X95549Y591790D01*
X95341Y592123D01*
X95091Y592332D01*
X94841Y592373D01*
X94549Y592290D01*
X94341Y591998D01*
X94258Y591707D01*
Y591332D01*
G01Y591707D02*
X94133Y591957D01*
X93924Y592165D01*
X93674Y592248D01*
X93424Y592165D01*
X93216Y591957D01*
X93091Y591582D01*
X93133Y591207D01*
X93299Y590832D01*
G01X86967Y632000D02*
Y634500D01*
X88008D01*
X88342Y634375D01*
X88550Y634208D01*
X88633Y633875D01*
X88550Y633542D01*
X88300Y633333D01*
X88008Y633208D01*
X86967D01*
G01X88008D02*
X88633Y632000D01*
G01X89883Y632500D02*
X90133Y632208D01*
X90467Y632042D01*
X90842Y632000D01*
X91175Y632042D01*
X91508Y632250D01*
X91717Y632500D01*
X91758Y632750D01*
X91675Y633042D01*
X91383Y633250D01*
X91092Y633333D01*
X90717D01*
G01X91092D02*
X91342Y633458D01*
X91550Y633667D01*
X91633Y633917D01*
X91550Y634167D01*
X91342Y634375D01*
X90967Y634500D01*
X90592Y634458D01*
X90217Y634292D01*
G01X94300Y632000D02*
Y634500D01*
X92758Y632708D01*
X94842D01*
G01X96008Y633042D02*
X96300Y633333D01*
X96550Y633500D01*
X96883Y633583D01*
X97175Y633500D01*
X97383Y633333D01*
X97550Y633083D01*
X97592Y632792D01*
X97550Y632542D01*
X97383Y632292D01*
X97133Y632083D01*
X96842Y632000D01*
X96508Y632083D01*
X96217Y632333D01*
X96050Y632708D01*
X96008Y633125D01*
X96092Y633667D01*
X96217Y633958D01*
X96425Y634250D01*
X96717Y634458D01*
X97008Y634500D01*
X97300Y634417D01*
X97508Y634208D01*
G01X90000Y657067D02*
X87500D01*
Y658108D01*
X87625Y658442D01*
X87792Y658650D01*
X88125Y658733D01*
X88458Y658650D01*
X88667Y658400D01*
X88792Y658108D01*
Y657067D01*
G01Y658108D02*
X90000Y658733D01*
G01X89500Y659983D02*
X89792Y660233D01*
X89958Y660567D01*
X90000Y660942D01*
X89958Y661275D01*
X89750Y661608D01*
X89500Y661817D01*
X89250Y661858D01*
X88958Y661775D01*
X88750Y661483D01*
X88667Y661192D01*
Y660817D01*
G01Y661192D02*
X88542Y661442D01*
X88333Y661650D01*
X88083Y661733D01*
X87833Y661650D01*
X87625Y661442D01*
X87500Y661067D01*
X87542Y660692D01*
X87708Y660317D01*
G01X90000Y664400D02*
X87500D01*
X89292Y662858D01*
Y664942D01*
G01X89625Y665983D02*
X89833Y666233D01*
X89958Y666525D01*
X90000Y666900D01*
X89917Y667275D01*
X89750Y667567D01*
X89458Y667775D01*
X89125Y667817D01*
X88792Y667733D01*
X88583Y667525D01*
X88417Y667233D01*
X88375Y666942D01*
X88417Y666650D01*
X88583Y666275D01*
X87500Y666400D01*
Y667525D01*
G01X86667Y636800D02*
Y639300D01*
X87708D01*
X88042Y639175D01*
X88250Y639008D01*
X88333Y638675D01*
X88250Y638342D01*
X88000Y638133D01*
X87708Y638008D01*
X86667D01*
G01X87708D02*
X88333Y636800D01*
G01X89583Y637300D02*
X89833Y637008D01*
X90167Y636842D01*
X90542Y636800D01*
X90875Y636842D01*
X91208Y637050D01*
X91417Y637300D01*
X91458Y637550D01*
X91375Y637842D01*
X91083Y638050D01*
X90792Y638133D01*
X90417D01*
G01X90792D02*
X91042Y638258D01*
X91250Y638467D01*
X91333Y638717D01*
X91250Y638967D01*
X91042Y639175D01*
X90667Y639300D01*
X90292Y639258D01*
X89917Y639092D01*
G01X92708Y638883D02*
X92958Y639133D01*
X93250Y639258D01*
X93583Y639300D01*
X94000Y639217D01*
X94292Y639008D01*
X94375Y638758D01*
X94333Y638508D01*
X94167Y638300D01*
X93333Y637883D01*
X92958Y637592D01*
X92708Y637175D01*
X92625Y636800D01*
X94375D01*
G01X96500D02*
X96792Y636842D01*
X97125Y636967D01*
X97333Y637175D01*
X97417Y637467D01*
X97333Y637758D01*
X97083Y638008D01*
X96708Y638133D01*
X96292D01*
X96042Y638217D01*
X95833Y638425D01*
X95750Y638717D01*
X95875Y639008D01*
X96167Y639217D01*
X96500Y639300D01*
X96833Y639217D01*
X97125Y639008D01*
X97250Y638717D01*
X97167Y638425D01*
X96958Y638217D01*
X96708Y638133D01*
X96292D01*
X95917Y638008D01*
X95667Y637758D01*
X95583Y637467D01*
X95667Y637175D01*
X95875Y636967D01*
X96208Y636842D01*
X96500Y636800D01*
G01X83267Y647500D02*
Y650000D01*
X84308D01*
X84642Y649875D01*
X84850Y649708D01*
X84933Y649375D01*
X84850Y649042D01*
X84600Y648833D01*
X84308Y648708D01*
X83267D01*
G01X84308D02*
X84933Y647500D01*
G01X86308Y649583D02*
X86558Y649833D01*
X86850Y649958D01*
X87183Y650000D01*
X87600Y649917D01*
X87892Y649708D01*
X87975Y649458D01*
X87933Y649208D01*
X87767Y649000D01*
X86933Y648583D01*
X86558Y648292D01*
X86308Y647875D01*
X86225Y647500D01*
X87975D01*
G01X89392Y647792D02*
X89683Y647583D01*
X90017Y647500D01*
X90350Y647583D01*
X90642Y647833D01*
X90850Y648208D01*
X90933Y648583D01*
Y649042D01*
X90850Y649417D01*
X90642Y649750D01*
X90392Y649917D01*
X90100Y650000D01*
X89767Y649917D01*
X89517Y649750D01*
X89350Y649500D01*
X89267Y649167D01*
X89350Y648875D01*
X89558Y648583D01*
X89808Y648417D01*
X90100Y648375D01*
X90433Y648458D01*
X90683Y648667D01*
X90933Y649042D01*
G01X92183Y647875D02*
X92433Y647667D01*
X92725Y647542D01*
X93100Y647500D01*
X93475Y647583D01*
X93767Y647750D01*
X93975Y648042D01*
X94017Y648375D01*
X93933Y648708D01*
X93725Y648917D01*
X93433Y649083D01*
X93142Y649125D01*
X92850Y649083D01*
X92475Y648917D01*
X92600Y650000D01*
X93725D01*
G01X89800Y749867D02*
X87300D01*
Y750908D01*
X87425Y751242D01*
X87592Y751450D01*
X87925Y751533D01*
X88258Y751450D01*
X88467Y751200D01*
X88592Y750908D01*
Y749867D01*
G01Y750908D02*
X89800Y751533D01*
G01X87717Y752908D02*
X87467Y753158D01*
X87342Y753450D01*
X87300Y753783D01*
X87383Y754200D01*
X87592Y754492D01*
X87842Y754575D01*
X88092Y754533D01*
X88300Y754367D01*
X88717Y753533D01*
X89008Y753158D01*
X89425Y752908D01*
X89800Y752825D01*
Y754575D01*
G01X87717Y755908D02*
X87467Y756158D01*
X87342Y756450D01*
X87300Y756783D01*
X87383Y757200D01*
X87592Y757492D01*
X87842Y757575D01*
X88092Y757533D01*
X88300Y757367D01*
X88717Y756533D01*
X89008Y756158D01*
X89425Y755908D01*
X89800Y755825D01*
Y757575D01*
G01Y759700D02*
X87300D01*
X87800Y759200D01*
G01X89800D02*
Y760200D01*
G01X96167Y749500D02*
Y752000D01*
X97208D01*
X97542Y751875D01*
X97750Y751708D01*
X97833Y751375D01*
X97750Y751042D01*
X97500Y750833D01*
X97208Y750708D01*
X96167D01*
G01X97208D02*
X97833Y749500D01*
G01X99083Y750000D02*
X99333Y749708D01*
X99667Y749542D01*
X100042Y749500D01*
X100375Y749542D01*
X100708Y749750D01*
X100917Y750000D01*
X100958Y750250D01*
X100875Y750542D01*
X100583Y750750D01*
X100292Y750833D01*
X99917D01*
G01X100292D02*
X100542Y750958D01*
X100750Y751167D01*
X100833Y751417D01*
X100750Y751667D01*
X100542Y751875D01*
X100167Y752000D01*
X99792Y751958D01*
X99417Y751792D01*
G01X103500Y749500D02*
Y752000D01*
X101958Y750208D01*
X104042D01*
G01X106000Y752000D02*
X105667Y751917D01*
X105417Y751708D01*
X105250Y751458D01*
X105125Y751125D01*
X105083Y750750D01*
X105125Y750375D01*
X105250Y750042D01*
X105417Y749792D01*
X105667Y749583D01*
X106000Y749500D01*
X106333Y749583D01*
X106583Y749792D01*
X106750Y750042D01*
X106875Y750375D01*
X106917Y750750D01*
X106875Y751125D01*
X106750Y751458D01*
X106583Y751708D01*
X106333Y751917D01*
X106000Y752000D01*
G01X89390Y764049D02*
Y766549D01*
X90431D01*
X90765Y766424D01*
X90973Y766257D01*
X91056Y765924D01*
X90973Y765591D01*
X90723Y765382D01*
X90431Y765257D01*
X89390D01*
G01X90431D02*
X91056Y764049D01*
G01X92306Y764549D02*
X92556Y764257D01*
X92890Y764091D01*
X93265Y764049D01*
X93598Y764091D01*
X93931Y764299D01*
X94140Y764549D01*
X94181Y764799D01*
X94098Y765091D01*
X93806Y765299D01*
X93515Y765382D01*
X93140D01*
G01X93515D02*
X93765Y765507D01*
X93973Y765716D01*
X94056Y765966D01*
X93973Y766216D01*
X93765Y766424D01*
X93390Y766549D01*
X93015Y766507D01*
X92640Y766341D01*
G01X96723Y764049D02*
Y766549D01*
X95181Y764757D01*
X97265D01*
G01X99223Y764049D02*
X99515Y764091D01*
X99848Y764216D01*
X100056Y764424D01*
X100140Y764716D01*
X100056Y765007D01*
X99806Y765257D01*
X99431Y765382D01*
X99015D01*
X98765Y765466D01*
X98556Y765674D01*
X98473Y765966D01*
X98598Y766257D01*
X98890Y766466D01*
X99223Y766549D01*
X99556Y766466D01*
X99848Y766257D01*
X99973Y765966D01*
X99890Y765674D01*
X99681Y765466D01*
X99431Y765382D01*
X99015D01*
X98640Y765257D01*
X98390Y765007D01*
X98306Y764716D01*
X98390Y764424D01*
X98598Y764216D01*
X98931Y764091D01*
X99223Y764049D01*
G01X95267Y756200D02*
Y758700D01*
X96308D01*
X96642Y758575D01*
X96850Y758408D01*
X96933Y758075D01*
X96850Y757742D01*
X96600Y757533D01*
X96308Y757408D01*
X95267D01*
G01X96308D02*
X96933Y756200D01*
G01X98183Y756700D02*
X98433Y756408D01*
X98767Y756242D01*
X99142Y756200D01*
X99475Y756242D01*
X99808Y756450D01*
X100017Y756700D01*
X100058Y756950D01*
X99975Y757242D01*
X99683Y757450D01*
X99392Y757533D01*
X99017D01*
G01X99392D02*
X99642Y757658D01*
X99850Y757867D01*
X99933Y758117D01*
X99850Y758367D01*
X99642Y758575D01*
X99267Y758700D01*
X98892Y758658D01*
X98517Y758492D01*
G01X101308Y758283D02*
X101558Y758533D01*
X101850Y758658D01*
X102183Y758700D01*
X102600Y758617D01*
X102892Y758408D01*
X102975Y758158D01*
X102933Y757908D01*
X102767Y757700D01*
X101933Y757283D01*
X101558Y756992D01*
X101308Y756575D01*
X101225Y756200D01*
X102975D01*
G01X104392Y756492D02*
X104683Y756283D01*
X105017Y756200D01*
X105350Y756283D01*
X105642Y756533D01*
X105850Y756908D01*
X105933Y757283D01*
Y757742D01*
X105850Y758117D01*
X105642Y758450D01*
X105392Y758617D01*
X105100Y758700D01*
X104767Y758617D01*
X104517Y758450D01*
X104350Y758200D01*
X104267Y757867D01*
X104350Y757575D01*
X104558Y757283D01*
X104808Y757117D01*
X105100Y757075D01*
X105433Y757158D01*
X105683Y757367D01*
X105933Y757742D01*
G01X93700Y751300D02*
X93658Y750967D01*
X93492Y750675D01*
X93242Y750425D01*
X92950Y750258D01*
X92617Y750175D01*
X92283D01*
X91950Y750258D01*
X91658Y750425D01*
X91408Y750675D01*
X91242Y750967D01*
X91200Y751300D01*
X91242Y751633D01*
X91408Y751925D01*
X91658Y752175D01*
X91950Y752342D01*
X92283Y752425D01*
X92617D01*
X92950Y752342D01*
X93242Y752175D01*
X93492Y751925D01*
X93658Y751633D01*
X93700Y751300D01*
G01X93033Y751633D02*
X93700Y752133D01*
G01X93200Y753383D02*
X93492Y753633D01*
X93658Y753967D01*
X93700Y754342D01*
X93658Y754675D01*
X93450Y755008D01*
X93200Y755217D01*
X92950Y755258D01*
X92658Y755175D01*
X92450Y754883D01*
X92367Y754592D01*
Y754217D01*
G01Y754592D02*
X92242Y754842D01*
X92033Y755050D01*
X91783Y755133D01*
X91533Y755050D01*
X91325Y754842D01*
X91200Y754467D01*
X91242Y754092D01*
X91408Y753717D01*
G01X93085Y710369D02*
X92960Y710119D01*
X92877Y709827D01*
Y709494D01*
X93002Y709119D01*
X93210Y708827D01*
X93460Y708619D01*
X93877Y708452D01*
X94252Y708410D01*
X94627Y708494D01*
X94877Y708619D01*
X95127Y708869D01*
X95294Y709160D01*
X95377Y709452D01*
Y709744D01*
X95294Y710035D01*
X95169Y710285D01*
X95002Y710494D01*
G01X95377Y711494D02*
X92877D01*
X95377Y713410D01*
X92877D01*
G01X93294Y714660D02*
X93044Y714910D01*
X92919Y715202D01*
X92877Y715535D01*
X92960Y715952D01*
X93169Y716244D01*
X93419Y716327D01*
X93669Y716285D01*
X93877Y716119D01*
X94294Y715285D01*
X94585Y714910D01*
X95002Y714660D01*
X95377Y714577D01*
Y716327D01*
G01X89090Y772454D02*
Y774954D01*
X90131D01*
X90465Y774829D01*
X90673Y774662D01*
X90756Y774329D01*
X90673Y773996D01*
X90423Y773787D01*
X90131Y773662D01*
X89090D01*
G01X90131D02*
X90756Y772454D01*
G01X92006Y772954D02*
X92256Y772662D01*
X92590Y772496D01*
X92965Y772454D01*
X93298Y772496D01*
X93631Y772704D01*
X93840Y772954D01*
X93881Y773204D01*
X93798Y773496D01*
X93506Y773704D01*
X93215Y773787D01*
X92840D01*
G01X93215D02*
X93465Y773912D01*
X93673Y774121D01*
X93756Y774371D01*
X93673Y774621D01*
X93465Y774829D01*
X93090Y774954D01*
X92715Y774912D01*
X92340Y774746D01*
G01X95006Y772954D02*
X95256Y772662D01*
X95590Y772496D01*
X95965Y772454D01*
X96298Y772496D01*
X96631Y772704D01*
X96840Y772954D01*
X96881Y773204D01*
X96798Y773496D01*
X96506Y773704D01*
X96215Y773787D01*
X95840D01*
G01X96215D02*
X96465Y773912D01*
X96673Y774121D01*
X96756Y774371D01*
X96673Y774621D01*
X96465Y774829D01*
X96090Y774954D01*
X95715Y774912D01*
X95340Y774746D01*
G01X98923Y774954D02*
X98590Y774871D01*
X98340Y774662D01*
X98173Y774412D01*
X98048Y774079D01*
X98006Y773704D01*
X98048Y773329D01*
X98173Y772996D01*
X98340Y772746D01*
X98590Y772537D01*
X98923Y772454D01*
X99256Y772537D01*
X99506Y772746D01*
X99673Y772996D01*
X99798Y773329D01*
X99840Y773704D01*
X99798Y774079D01*
X99673Y774412D01*
X99506Y774662D01*
X99256Y774871D01*
X98923Y774954D01*
G01X129725Y898000D02*
Y900500D01*
G01X131475D02*
Y898000D01*
G01Y899250D02*
X129725D01*
G01X133600Y898000D02*
Y900500D01*
X133100Y900000D01*
G01Y898000D02*
X134100D01*
G01X199600Y60367D02*
X197100D01*
Y61367D01*
X197225Y61700D01*
X197517Y61950D01*
X197850Y62033D01*
X198183Y61950D01*
X198433Y61742D01*
X198558Y61367D01*
Y60367D01*
G01X197308Y65117D02*
X197183Y64867D01*
X197100Y64575D01*
Y64242D01*
X197225Y63867D01*
X197433Y63575D01*
X197683Y63367D01*
X198100Y63200D01*
X198475Y63158D01*
X198850Y63242D01*
X199100Y63367D01*
X199350Y63617D01*
X199517Y63908D01*
X199600Y64200D01*
Y64492D01*
X199517Y64783D01*
X199392Y65033D01*
X199225Y65242D01*
G01X197517Y66408D02*
X197267Y66658D01*
X197142Y66950D01*
X197100Y67283D01*
X197183Y67700D01*
X197392Y67992D01*
X197642Y68075D01*
X197892Y68033D01*
X198100Y67867D01*
X198517Y67033D01*
X198808Y66658D01*
X199225Y66408D01*
X199600Y66325D01*
Y68075D01*
G01Y70117D02*
X199058Y70200D01*
X198600Y70325D01*
X198183Y70492D01*
X197725Y70700D01*
X197100Y71033D01*
Y69367D01*
G01X205900Y60367D02*
X203400D01*
Y61367D01*
X203525Y61700D01*
X203817Y61950D01*
X204150Y62033D01*
X204483Y61950D01*
X204733Y61742D01*
X204858Y61367D01*
Y60367D01*
G01X203608Y65117D02*
X203483Y64867D01*
X203400Y64575D01*
Y64242D01*
X203525Y63867D01*
X203733Y63575D01*
X203983Y63367D01*
X204400Y63200D01*
X204775Y63158D01*
X205150Y63242D01*
X205400Y63367D01*
X205650Y63617D01*
X205817Y63908D01*
X205900Y64200D01*
Y64492D01*
X205817Y64783D01*
X205692Y65033D01*
X205525Y65242D01*
G01X205900Y67200D02*
X203400D01*
X203900Y66700D01*
G01X205900D02*
Y67700D01*
G01Y70117D02*
X205358Y70200D01*
X204900Y70325D01*
X204483Y70492D01*
X204025Y70700D01*
X203400Y71033D01*
Y69367D01*
G01X210000Y60067D02*
X207500D01*
Y61108D01*
X207625Y61442D01*
X207792Y61650D01*
X208125Y61733D01*
X208458Y61650D01*
X208667Y61400D01*
X208792Y61108D01*
Y60067D01*
G01Y61108D02*
X210000Y61733D01*
G01X207917Y63108D02*
X207667Y63358D01*
X207542Y63650D01*
X207500Y63983D01*
X207583Y64400D01*
X207792Y64692D01*
X208042Y64775D01*
X208292Y64733D01*
X208500Y64567D01*
X208917Y63733D01*
X209208Y63358D01*
X209625Y63108D01*
X210000Y63025D01*
Y64775D01*
G01X207917Y66108D02*
X207667Y66358D01*
X207542Y66650D01*
X207500Y66983D01*
X207583Y67400D01*
X207792Y67692D01*
X208042Y67775D01*
X208292Y67733D01*
X208500Y67567D01*
X208917Y66733D01*
X209208Y66358D01*
X209625Y66108D01*
X210000Y66025D01*
Y67775D01*
G01Y69900D02*
X209958Y70192D01*
X209833Y70525D01*
X209625Y70733D01*
X209333Y70817D01*
X209042Y70733D01*
X208792Y70483D01*
X208667Y70108D01*
Y69692D01*
X208583Y69442D01*
X208375Y69233D01*
X208083Y69150D01*
X207792Y69275D01*
X207583Y69567D01*
X207500Y69900D01*
X207583Y70233D01*
X207792Y70525D01*
X208083Y70650D01*
X208375Y70567D01*
X208583Y70358D01*
X208667Y70108D01*
Y69692D01*
X208792Y69317D01*
X209042Y69067D01*
X209333Y68983D01*
X209625Y69067D01*
X209833Y69275D01*
X209958Y69608D01*
X210000Y69900D01*
G01X175018Y53586D02*
X172518D01*
Y54586D01*
X172643Y54919D01*
X172935Y55169D01*
X173268Y55252D01*
X173601Y55169D01*
X173851Y54961D01*
X173976Y54586D01*
Y53586D01*
G01X172726Y58336D02*
X172601Y58086D01*
X172518Y57794D01*
Y57461D01*
X172643Y57086D01*
X172851Y56794D01*
X173101Y56586D01*
X173518Y56419D01*
X173893Y56377D01*
X174268Y56461D01*
X174518Y56586D01*
X174768Y56836D01*
X174935Y57127D01*
X175018Y57419D01*
Y57711D01*
X174935Y58002D01*
X174810Y58252D01*
X174643Y58461D01*
G01X172935Y59627D02*
X172685Y59877D01*
X172560Y60169D01*
X172518Y60502D01*
X172601Y60919D01*
X172810Y61211D01*
X173060Y61294D01*
X173310Y61252D01*
X173518Y61086D01*
X173935Y60252D01*
X174226Y59877D01*
X174643Y59627D01*
X175018Y59544D01*
Y61294D01*
G01Y63919D02*
X172518D01*
X174310Y62377D01*
Y64461D01*
G01X212132Y57130D02*
Y54630D01*
G01X211174Y57130D02*
X213090D01*
G01X214299Y54630D02*
Y57130D01*
X215299D01*
X215632Y57005D01*
X215882Y56713D01*
X215965Y56380D01*
X215882Y56047D01*
X215674Y55797D01*
X215299Y55672D01*
X214299D01*
G01X218632Y54630D02*
Y57130D01*
X217090Y55338D01*
X219174D01*
G01X220340Y55672D02*
X220632Y55963D01*
X220882Y56130D01*
X221215Y56213D01*
X221507Y56130D01*
X221715Y55963D01*
X221882Y55713D01*
X221924Y55422D01*
X221882Y55172D01*
X221715Y54922D01*
X221465Y54713D01*
X221174Y54630D01*
X220840Y54713D01*
X220549Y54963D01*
X220382Y55338D01*
X220340Y55755D01*
X220424Y56297D01*
X220549Y56588D01*
X220757Y56880D01*
X221049Y57088D01*
X221340Y57130D01*
X221632Y57047D01*
X221840Y56838D01*
G01X202500Y115867D02*
X200000D01*
Y116867D01*
X200125Y117200D01*
X200417Y117450D01*
X200750Y117533D01*
X201083Y117450D01*
X201333Y117242D01*
X201458Y116867D01*
Y115867D01*
G01X200208Y120617D02*
X200083Y120367D01*
X200000Y120075D01*
Y119742D01*
X200125Y119367D01*
X200333Y119075D01*
X200583Y118867D01*
X201000Y118700D01*
X201375Y118658D01*
X201750Y118742D01*
X202000Y118867D01*
X202250Y119117D01*
X202417Y119408D01*
X202500Y119700D01*
Y119992D01*
X202417Y120283D01*
X202292Y120533D01*
X202125Y120742D01*
G01X202500Y122700D02*
X200000D01*
X200500Y122200D01*
G01X202500D02*
Y123200D01*
G01Y125700D02*
X202458Y125992D01*
X202333Y126325D01*
X202125Y126533D01*
X201833Y126617D01*
X201542Y126533D01*
X201292Y126283D01*
X201167Y125908D01*
Y125492D01*
X201083Y125242D01*
X200875Y125033D01*
X200583Y124950D01*
X200292Y125075D01*
X200083Y125367D01*
X200000Y125700D01*
X200083Y126033D01*
X200292Y126325D01*
X200583Y126450D01*
X200875Y126367D01*
X201083Y126158D01*
X201167Y125908D01*
Y125492D01*
X201292Y125117D01*
X201542Y124867D01*
X201833Y124783D01*
X202125Y124867D01*
X202333Y125075D01*
X202458Y125408D01*
X202500Y125700D01*
G01X202317Y107342D02*
Y109842D01*
X203317D01*
X203650Y109717D01*
X203900Y109425D01*
X203983Y109092D01*
X203900Y108759D01*
X203692Y108509D01*
X203317Y108384D01*
X202317D01*
G01X205317Y107342D02*
Y109842D01*
X206358D01*
X206692Y109717D01*
X206900Y109550D01*
X206983Y109217D01*
X206900Y108884D01*
X206650Y108675D01*
X206358Y108550D01*
X205317D01*
G01X206358D02*
X206983Y107342D01*
G01X208358Y109425D02*
X208608Y109675D01*
X208900Y109800D01*
X209233Y109842D01*
X209650Y109759D01*
X209942Y109550D01*
X210025Y109300D01*
X209983Y109050D01*
X209817Y108842D01*
X208983Y108425D01*
X208608Y108134D01*
X208358Y107717D01*
X208275Y107342D01*
X210025D01*
G01X211358Y108384D02*
X211650Y108675D01*
X211900Y108842D01*
X212233Y108925D01*
X212525Y108842D01*
X212733Y108675D01*
X212900Y108425D01*
X212942Y108134D01*
X212900Y107884D01*
X212733Y107634D01*
X212483Y107425D01*
X212192Y107342D01*
X211858Y107425D01*
X211567Y107675D01*
X211400Y108050D01*
X211358Y108467D01*
X211442Y109009D01*
X211567Y109300D01*
X211775Y109592D01*
X212067Y109800D01*
X212358Y109842D01*
X212650Y109759D01*
X212858Y109550D01*
G01X196067Y72400D02*
Y74900D01*
X197067D01*
X197400Y74775D01*
X197650Y74483D01*
X197733Y74150D01*
X197650Y73817D01*
X197442Y73567D01*
X197067Y73442D01*
X196067D01*
G01X199067Y72400D02*
Y74900D01*
X200108D01*
X200442Y74775D01*
X200650Y74608D01*
X200733Y74275D01*
X200650Y73942D01*
X200400Y73733D01*
X200108Y73608D01*
X199067D01*
G01X200108D02*
X200733Y72400D01*
G01X202108Y74483D02*
X202358Y74733D01*
X202650Y74858D01*
X202983Y74900D01*
X203400Y74817D01*
X203692Y74608D01*
X203775Y74358D01*
X203733Y74108D01*
X203567Y73900D01*
X202733Y73483D01*
X202358Y73192D01*
X202108Y72775D01*
X202025Y72400D01*
X203775D01*
G01X205108Y74483D02*
X205358Y74733D01*
X205650Y74858D01*
X205983Y74900D01*
X206400Y74817D01*
X206692Y74608D01*
X206775Y74358D01*
X206733Y74108D01*
X206567Y73900D01*
X205733Y73483D01*
X205358Y73192D01*
X205108Y72775D01*
X205025Y72400D01*
X206775D01*
G01X205675Y114691D02*
Y117191D01*
X206675D01*
X207008Y117066D01*
X207258Y116774D01*
X207341Y116441D01*
X207258Y116108D01*
X207050Y115858D01*
X206675Y115733D01*
X205675D01*
G01X208675Y114691D02*
Y117191D01*
X209716D01*
X210050Y117066D01*
X210258Y116899D01*
X210341Y116566D01*
X210258Y116233D01*
X210008Y116024D01*
X209716Y115899D01*
X208675D01*
G01X209716D02*
X210341Y114691D01*
G01X211716Y116774D02*
X211966Y117024D01*
X212258Y117149D01*
X212591Y117191D01*
X213008Y117108D01*
X213300Y116899D01*
X213383Y116649D01*
X213341Y116399D01*
X213175Y116191D01*
X212341Y115774D01*
X211966Y115483D01*
X211716Y115066D01*
X211633Y114691D01*
X213383D01*
G01X215508Y117191D02*
X215175Y117108D01*
X214925Y116899D01*
X214758Y116649D01*
X214633Y116316D01*
X214591Y115941D01*
X214633Y115566D01*
X214758Y115233D01*
X214925Y114983D01*
X215175Y114774D01*
X215508Y114691D01*
X215841Y114774D01*
X216091Y114983D01*
X216258Y115233D01*
X216383Y115566D01*
X216425Y115941D01*
X216383Y116316D01*
X216258Y116649D01*
X216091Y116899D01*
X215841Y117108D01*
X215508Y117191D01*
G01X205756Y111200D02*
Y113700D01*
X206756D01*
X207089Y113575D01*
X207339Y113283D01*
X207422Y112950D01*
X207339Y112617D01*
X207131Y112367D01*
X206756Y112242D01*
X205756D01*
G01X208756Y111200D02*
Y113700D01*
X209797D01*
X210131Y113575D01*
X210339Y113408D01*
X210422Y113075D01*
X210339Y112742D01*
X210089Y112533D01*
X209797Y112408D01*
X208756D01*
G01X209797D02*
X210422Y111200D01*
G01X212589D02*
Y113700D01*
X212089Y113200D01*
G01Y111200D02*
X213089D01*
G01X214881Y111492D02*
X215172Y111283D01*
X215506Y111200D01*
X215839Y111283D01*
X216131Y111533D01*
X216339Y111908D01*
X216422Y112283D01*
Y112742D01*
X216339Y113117D01*
X216131Y113450D01*
X215881Y113617D01*
X215589Y113700D01*
X215256Y113617D01*
X215006Y113450D01*
X214839Y113200D01*
X214756Y112867D01*
X214839Y112575D01*
X215047Y112283D01*
X215297Y112117D01*
X215589Y112075D01*
X215922Y112158D01*
X216172Y112367D01*
X216422Y112742D01*
G01X160750Y131050D02*
Y131883D01*
X161500D01*
X161750Y131633D01*
X161917Y131342D01*
X162000Y130925D01*
X161917Y130508D01*
X161750Y130217D01*
X161500Y129967D01*
X161208Y129800D01*
X160875Y129717D01*
X160583D01*
X160333Y129800D01*
X160042Y129967D01*
X159792Y130217D01*
X159625Y130467D01*
X159500Y130800D01*
Y131092D01*
X159583Y131425D01*
X159750Y131675D01*
G01X162000Y133800D02*
X159500D01*
X160000Y133300D01*
G01X162000D02*
Y134300D01*
G01X154100Y126100D02*
X156600D01*
G01X154100Y125142D02*
Y127058D01*
G01X156600Y128267D02*
X154100D01*
Y129267D01*
X154225Y129600D01*
X154517Y129850D01*
X154850Y129933D01*
X155183Y129850D01*
X155433Y129642D01*
X155558Y129267D01*
Y128267D01*
G01X156225Y131183D02*
X156433Y131433D01*
X156558Y131725D01*
X156600Y132100D01*
X156517Y132475D01*
X156350Y132767D01*
X156058Y132975D01*
X155725Y133017D01*
X155392Y132933D01*
X155183Y132725D01*
X155017Y132433D01*
X154975Y132142D01*
X155017Y131850D01*
X155183Y131475D01*
X154100Y131600D01*
Y132725D01*
G01Y135100D02*
X154183Y134767D01*
X154392Y134517D01*
X154642Y134350D01*
X154975Y134225D01*
X155350Y134183D01*
X155725Y134225D01*
X156058Y134350D01*
X156308Y134517D01*
X156517Y134767D01*
X156600Y135100D01*
X156517Y135433D01*
X156308Y135683D01*
X156058Y135850D01*
X155725Y135975D01*
X155350Y136017D01*
X154975Y135975D01*
X154642Y135850D01*
X154392Y135683D01*
X154183Y135433D01*
X154100Y135100D01*
G01X183300Y192967D02*
X180800D01*
Y193967D01*
X180925Y194300D01*
X181217Y194550D01*
X181550Y194633D01*
X181883Y194550D01*
X182133Y194342D01*
X182258Y193967D01*
Y192967D01*
G01X180800Y195883D02*
X182592D01*
X182967Y196050D01*
X183217Y196383D01*
X183300Y196800D01*
X183217Y197217D01*
X182967Y197550D01*
X182592Y197717D01*
X180800D01*
G01X183300Y200300D02*
X180800D01*
X182592Y198758D01*
Y200842D01*
G01X177800Y192467D02*
X175300D01*
Y193467D01*
X175425Y193800D01*
X175717Y194050D01*
X176050Y194133D01*
X176383Y194050D01*
X176633Y193842D01*
X176758Y193467D01*
Y192467D01*
G01X175508Y197217D02*
X175383Y196967D01*
X175300Y196675D01*
Y196342D01*
X175425Y195967D01*
X175633Y195675D01*
X175883Y195467D01*
X176300Y195300D01*
X176675Y195258D01*
X177050Y195342D01*
X177300Y195467D01*
X177550Y195717D01*
X177717Y196008D01*
X177800Y196300D01*
Y196592D01*
X177717Y196883D01*
X177592Y197133D01*
X177425Y197342D01*
G01X177300Y198383D02*
X177592Y198633D01*
X177758Y198967D01*
X177800Y199342D01*
X177758Y199675D01*
X177550Y200008D01*
X177300Y200217D01*
X177050Y200258D01*
X176758Y200175D01*
X176550Y199883D01*
X176467Y199592D01*
Y199217D01*
G01Y199592D02*
X176342Y199842D01*
X176133Y200050D01*
X175883Y200133D01*
X175633Y200050D01*
X175425Y199842D01*
X175300Y199467D01*
X175342Y199092D01*
X175508Y198717D01*
G01X175717Y201508D02*
X175467Y201758D01*
X175342Y202050D01*
X175300Y202383D01*
X175383Y202800D01*
X175592Y203092D01*
X175842Y203175D01*
X176092Y203133D01*
X176300Y202967D01*
X176717Y202133D01*
X177008Y201758D01*
X177425Y201508D01*
X177800Y201425D01*
Y203175D01*
G01X170667Y204900D02*
Y207400D01*
X171667D01*
X172000Y207275D01*
X172250Y206983D01*
X172333Y206650D01*
X172250Y206317D01*
X172042Y206067D01*
X171667Y205942D01*
X170667D01*
G01X173667Y204900D02*
Y207400D01*
X174708D01*
X175042Y207275D01*
X175250Y207108D01*
X175333Y206775D01*
X175250Y206442D01*
X175000Y206233D01*
X174708Y206108D01*
X173667D01*
G01X174708D02*
X175333Y204900D01*
G01X176583Y205400D02*
X176833Y205108D01*
X177167Y204942D01*
X177542Y204900D01*
X177875Y204942D01*
X178208Y205150D01*
X178417Y205400D01*
X178458Y205650D01*
X178375Y205942D01*
X178083Y206150D01*
X177792Y206233D01*
X177417D01*
G01X177792D02*
X178042Y206358D01*
X178250Y206567D01*
X178333Y206817D01*
X178250Y207067D01*
X178042Y207275D01*
X177667Y207400D01*
X177292Y207358D01*
X176917Y207192D01*
G01X180417Y204900D02*
X180500Y205442D01*
X180625Y205900D01*
X180792Y206317D01*
X181000Y206775D01*
X181333Y207400D01*
X179667D01*
G01X191700Y181267D02*
X189200D01*
Y182267D01*
X189325Y182600D01*
X189617Y182850D01*
X189950Y182933D01*
X190283Y182850D01*
X190533Y182642D01*
X190658Y182267D01*
Y181267D01*
G01X191700Y184267D02*
X189200D01*
Y185308D01*
X189325Y185642D01*
X189492Y185850D01*
X189825Y185933D01*
X190158Y185850D01*
X190367Y185600D01*
X190492Y185308D01*
Y184267D01*
G01Y185308D02*
X191700Y185933D01*
G01X191200Y187183D02*
X191492Y187433D01*
X191658Y187767D01*
X191700Y188142D01*
X191658Y188475D01*
X191450Y188808D01*
X191200Y189017D01*
X190950Y189058D01*
X190658Y188975D01*
X190450Y188683D01*
X190367Y188392D01*
Y188017D01*
G01Y188392D02*
X190242Y188642D01*
X190033Y188850D01*
X189783Y188933D01*
X189533Y188850D01*
X189325Y188642D01*
X189200Y188267D01*
X189242Y187892D01*
X189408Y187517D01*
G01X190658Y190308D02*
X190367Y190600D01*
X190200Y190850D01*
X190117Y191183D01*
X190200Y191475D01*
X190367Y191683D01*
X190617Y191850D01*
X190908Y191892D01*
X191158Y191850D01*
X191408Y191683D01*
X191617Y191433D01*
X191700Y191142D01*
X191617Y190808D01*
X191367Y190517D01*
X190992Y190350D01*
X190575Y190308D01*
X190033Y190392D01*
X189742Y190517D01*
X189450Y190725D01*
X189242Y191017D01*
X189200Y191308D01*
X189283Y191600D01*
X189492Y191808D01*
G01X176467Y187500D02*
Y190000D01*
X177467D01*
X177800Y189875D01*
X178050Y189583D01*
X178133Y189250D01*
X178050Y188917D01*
X177842Y188667D01*
X177467Y188542D01*
X176467D01*
G01X179467Y187500D02*
Y190000D01*
X180508D01*
X180842Y189875D01*
X181050Y189708D01*
X181133Y189375D01*
X181050Y189042D01*
X180800Y188833D01*
X180508Y188708D01*
X179467D01*
G01X180508D02*
X181133Y187500D01*
G01X182383Y188000D02*
X182633Y187708D01*
X182967Y187542D01*
X183342Y187500D01*
X183675Y187542D01*
X184008Y187750D01*
X184217Y188000D01*
X184258Y188250D01*
X184175Y188542D01*
X183883Y188750D01*
X183592Y188833D01*
X183217D01*
G01X183592D02*
X183842Y188958D01*
X184050Y189167D01*
X184133Y189417D01*
X184050Y189667D01*
X183842Y189875D01*
X183467Y190000D01*
X183092Y189958D01*
X182717Y189792D01*
G01X185508Y189583D02*
X185758Y189833D01*
X186050Y189958D01*
X186383Y190000D01*
X186800Y189917D01*
X187092Y189708D01*
X187175Y189458D01*
X187133Y189208D01*
X186967Y189000D01*
X186133Y188583D01*
X185758Y188292D01*
X185508Y187875D01*
X185425Y187500D01*
X187175D01*
G01X202600Y183467D02*
X200100D01*
Y184467D01*
X200225Y184800D01*
X200517Y185050D01*
X200850Y185133D01*
X201183Y185050D01*
X201433Y184842D01*
X201558Y184467D01*
Y183467D01*
G01X200100Y186467D02*
X202600D01*
Y188133D01*
G01X202100Y189383D02*
X202392Y189633D01*
X202558Y189967D01*
X202600Y190342D01*
X202558Y190675D01*
X202350Y191008D01*
X202100Y191217D01*
X201850Y191258D01*
X201558Y191175D01*
X201350Y190883D01*
X201267Y190592D01*
Y190217D01*
G01Y190592D02*
X201142Y190842D01*
X200933Y191050D01*
X200683Y191133D01*
X200433Y191050D01*
X200225Y190842D01*
X200100Y190467D01*
X200142Y190092D01*
X200308Y189717D01*
G01X212500Y183067D02*
X210000D01*
Y184067D01*
X210125Y184400D01*
X210417Y184650D01*
X210750Y184733D01*
X211083Y184650D01*
X211333Y184442D01*
X211458Y184067D01*
Y183067D01*
G01X210208Y187817D02*
X210083Y187567D01*
X210000Y187275D01*
Y186942D01*
X210125Y186567D01*
X210333Y186275D01*
X210583Y186067D01*
X211000Y185900D01*
X211375Y185858D01*
X211750Y185942D01*
X212000Y186067D01*
X212250Y186317D01*
X212417Y186608D01*
X212500Y186900D01*
Y187192D01*
X212417Y187483D01*
X212292Y187733D01*
X212125Y187942D01*
G01X212500Y190400D02*
X210000D01*
X211792Y188858D01*
Y190942D01*
G01X212208Y192192D02*
X212417Y192483D01*
X212500Y192817D01*
X212417Y193150D01*
X212167Y193442D01*
X211792Y193650D01*
X211417Y193733D01*
X210958D01*
X210583Y193650D01*
X210250Y193442D01*
X210083Y193192D01*
X210000Y192900D01*
X210083Y192567D01*
X210250Y192317D01*
X210500Y192150D01*
X210833Y192067D01*
X211125Y192150D01*
X211417Y192358D01*
X211583Y192608D01*
X211625Y192900D01*
X211542Y193233D01*
X211333Y193483D01*
X210958Y193733D01*
G01X193000Y156667D02*
X190500D01*
Y157667D01*
X190625Y158000D01*
X190917Y158250D01*
X191250Y158333D01*
X191583Y158250D01*
X191833Y158042D01*
X191958Y157667D01*
Y156667D01*
G01X190708Y161417D02*
X190583Y161167D01*
X190500Y160875D01*
Y160542D01*
X190625Y160167D01*
X190833Y159875D01*
X191083Y159667D01*
X191500Y159500D01*
X191875Y159458D01*
X192250Y159542D01*
X192500Y159667D01*
X192750Y159917D01*
X192917Y160208D01*
X193000Y160500D01*
Y160792D01*
X192917Y161083D01*
X192792Y161333D01*
X192625Y161542D01*
G01X193000Y164000D02*
X190500D01*
X192292Y162458D01*
Y164542D01*
G01X193000Y166500D02*
X192958Y166792D01*
X192833Y167125D01*
X192625Y167333D01*
X192333Y167417D01*
X192042Y167333D01*
X191792Y167083D01*
X191667Y166708D01*
Y166292D01*
X191583Y166042D01*
X191375Y165833D01*
X191083Y165750D01*
X190792Y165875D01*
X190583Y166167D01*
X190500Y166500D01*
X190583Y166833D01*
X190792Y167125D01*
X191083Y167250D01*
X191375Y167167D01*
X191583Y166958D01*
X191667Y166708D01*
Y166292D01*
X191792Y165917D01*
X192042Y165667D01*
X192333Y165583D01*
X192625Y165667D01*
X192833Y165875D01*
X192958Y166208D01*
X193000Y166500D01*
G01X195000Y181267D02*
X192500D01*
Y182267D01*
X192625Y182600D01*
X192917Y182850D01*
X193250Y182933D01*
X193583Y182850D01*
X193833Y182642D01*
X193958Y182267D01*
Y181267D01*
G01X192708Y186017D02*
X192583Y185767D01*
X192500Y185475D01*
Y185142D01*
X192625Y184767D01*
X192833Y184475D01*
X193083Y184267D01*
X193500Y184100D01*
X193875Y184058D01*
X194250Y184142D01*
X194500Y184267D01*
X194750Y184517D01*
X194917Y184808D01*
X195000Y185100D01*
Y185392D01*
X194917Y185683D01*
X194792Y185933D01*
X194625Y186142D01*
G01X192917Y187308D02*
X192667Y187558D01*
X192542Y187850D01*
X192500Y188183D01*
X192583Y188600D01*
X192792Y188892D01*
X193042Y188975D01*
X193292Y188933D01*
X193500Y188767D01*
X193917Y187933D01*
X194208Y187558D01*
X194625Y187308D01*
X195000Y187225D01*
Y188975D01*
G01Y191100D02*
X194958Y191392D01*
X194833Y191725D01*
X194625Y191933D01*
X194333Y192017D01*
X194042Y191933D01*
X193792Y191683D01*
X193667Y191308D01*
Y190892D01*
X193583Y190642D01*
X193375Y190433D01*
X193083Y190350D01*
X192792Y190475D01*
X192583Y190767D01*
X192500Y191100D01*
X192583Y191433D01*
X192792Y191725D01*
X193083Y191850D01*
X193375Y191767D01*
X193583Y191558D01*
X193667Y191308D01*
Y190892D01*
X193792Y190517D01*
X194042Y190267D01*
X194333Y190183D01*
X194625Y190267D01*
X194833Y190475D01*
X194958Y190808D01*
X195000Y191100D01*
G01X198900Y181167D02*
X196400D01*
Y182167D01*
X196525Y182500D01*
X196817Y182750D01*
X197150Y182833D01*
X197483Y182750D01*
X197733Y182542D01*
X197858Y182167D01*
Y181167D01*
G01X196608Y185917D02*
X196483Y185667D01*
X196400Y185375D01*
Y185042D01*
X196525Y184667D01*
X196733Y184375D01*
X196983Y184167D01*
X197400Y184000D01*
X197775Y183958D01*
X198150Y184042D01*
X198400Y184167D01*
X198650Y184417D01*
X198817Y184708D01*
X198900Y185000D01*
Y185292D01*
X198817Y185583D01*
X198692Y185833D01*
X198525Y186042D01*
G01X196817Y187208D02*
X196567Y187458D01*
X196442Y187750D01*
X196400Y188083D01*
X196483Y188500D01*
X196692Y188792D01*
X196942Y188875D01*
X197192Y188833D01*
X197400Y188667D01*
X197817Y187833D01*
X198108Y187458D01*
X198525Y187208D01*
X198900Y187125D01*
Y188875D01*
G01X198608Y190292D02*
X198817Y190583D01*
X198900Y190917D01*
X198817Y191250D01*
X198567Y191542D01*
X198192Y191750D01*
X197817Y191833D01*
X197358D01*
X196983Y191750D01*
X196650Y191542D01*
X196483Y191292D01*
X196400Y191000D01*
X196483Y190667D01*
X196650Y190417D01*
X196900Y190250D01*
X197233Y190167D01*
X197525Y190250D01*
X197817Y190458D01*
X197983Y190708D01*
X198025Y191000D01*
X197942Y191333D01*
X197733Y191583D01*
X197358Y191833D01*
G01X208500Y183167D02*
X206000D01*
Y184167D01*
X206125Y184500D01*
X206417Y184750D01*
X206750Y184833D01*
X207083Y184750D01*
X207333Y184542D01*
X207458Y184167D01*
Y183167D01*
G01X208500Y186167D02*
X206000D01*
Y187208D01*
X206125Y187542D01*
X206292Y187750D01*
X206625Y187833D01*
X206958Y187750D01*
X207167Y187500D01*
X207292Y187208D01*
Y186167D01*
G01Y187208D02*
X208500Y187833D01*
G01X207458Y189208D02*
X207167Y189500D01*
X207000Y189750D01*
X206917Y190083D01*
X207000Y190375D01*
X207167Y190583D01*
X207417Y190750D01*
X207708Y190792D01*
X207958Y190750D01*
X208208Y190583D01*
X208417Y190333D01*
X208500Y190042D01*
X208417Y189708D01*
X208167Y189417D01*
X207792Y189250D01*
X207375Y189208D01*
X206833Y189292D01*
X206542Y189417D01*
X206250Y189625D01*
X206042Y189917D01*
X206000Y190208D01*
X206083Y190500D01*
X206292Y190708D01*
G01X206000Y193000D02*
X206083Y192667D01*
X206292Y192417D01*
X206542Y192250D01*
X206875Y192125D01*
X207250Y192083D01*
X207625Y192125D01*
X207958Y192250D01*
X208208Y192417D01*
X208417Y192667D01*
X208500Y193000D01*
X208417Y193333D01*
X208208Y193583D01*
X207958Y193750D01*
X207625Y193875D01*
X207250Y193917D01*
X206875Y193875D01*
X206542Y193750D01*
X206292Y193583D01*
X206083Y193333D01*
X206000Y193000D01*
G01X200037Y239178D02*
X199787Y239303D01*
X199495Y239386D01*
X199162D01*
X198787Y239261D01*
X198495Y239053D01*
X198287Y238803D01*
X198120Y238386D01*
X198078Y238011D01*
X198162Y237636D01*
X198287Y237386D01*
X198537Y237136D01*
X198828Y236969D01*
X199120Y236886D01*
X199412D01*
X199703Y236969D01*
X199953Y237094D01*
X200162Y237261D01*
G01X202120Y236886D02*
Y239386D01*
X201620Y238886D01*
G01Y236886D02*
X202620D01*
G01X204328Y237928D02*
X204620Y238219D01*
X204870Y238386D01*
X205203Y238469D01*
X205495Y238386D01*
X205703Y238219D01*
X205870Y237969D01*
X205912Y237678D01*
X205870Y237428D01*
X205703Y237178D01*
X205453Y236969D01*
X205162Y236886D01*
X204828Y236969D01*
X204537Y237219D01*
X204370Y237594D01*
X204328Y238011D01*
X204412Y238553D01*
X204537Y238844D01*
X204745Y239136D01*
X205037Y239344D01*
X205328Y239386D01*
X205620Y239303D01*
X205828Y239094D01*
G01X207203Y237386D02*
X207453Y237094D01*
X207787Y236928D01*
X208162Y236886D01*
X208495Y236928D01*
X208828Y237136D01*
X209037Y237386D01*
X209078Y237636D01*
X208995Y237928D01*
X208703Y238136D01*
X208412Y238219D01*
X208037D01*
G01X208412D02*
X208662Y238344D01*
X208870Y238553D01*
X208953Y238803D01*
X208870Y239053D01*
X208662Y239261D01*
X208287Y239386D01*
X207912Y239344D01*
X207537Y239178D01*
G01X177000Y208867D02*
X174500D01*
Y209867D01*
X174625Y210200D01*
X174917Y210450D01*
X175250Y210533D01*
X175583Y210450D01*
X175833Y210242D01*
X175958Y209867D01*
Y208867D01*
G01X174708Y213617D02*
X174583Y213367D01*
X174500Y213075D01*
Y212742D01*
X174625Y212367D01*
X174833Y212075D01*
X175083Y211867D01*
X175500Y211700D01*
X175875Y211658D01*
X176250Y211742D01*
X176500Y211867D01*
X176750Y212117D01*
X176917Y212408D01*
X177000Y212700D01*
Y212992D01*
X176917Y213283D01*
X176792Y213533D01*
X176625Y213742D01*
G01X176500Y214783D02*
X176792Y215033D01*
X176958Y215367D01*
X177000Y215742D01*
X176958Y216075D01*
X176750Y216408D01*
X176500Y216617D01*
X176250Y216658D01*
X175958Y216575D01*
X175750Y216283D01*
X175667Y215992D01*
Y215617D01*
G01Y215992D02*
X175542Y216242D01*
X175333Y216450D01*
X175083Y216533D01*
X174833Y216450D01*
X174625Y216242D01*
X174500Y215867D01*
X174542Y215492D01*
X174708Y215117D01*
G01X176708Y217992D02*
X176917Y218283D01*
X177000Y218617D01*
X176917Y218950D01*
X176667Y219242D01*
X176292Y219450D01*
X175917Y219533D01*
X175458D01*
X175083Y219450D01*
X174750Y219242D01*
X174583Y218992D01*
X174500Y218700D01*
X174583Y218367D01*
X174750Y218117D01*
X175000Y217950D01*
X175333Y217867D01*
X175625Y217950D01*
X175917Y218158D01*
X176083Y218408D01*
X176125Y218700D01*
X176042Y219033D01*
X175833Y219283D01*
X175458Y219533D01*
G01X214208Y229517D02*
X214083Y229267D01*
X214000Y228975D01*
Y228642D01*
X214125Y228267D01*
X214333Y227975D01*
X214583Y227767D01*
X215000Y227600D01*
X215375Y227558D01*
X215750Y227642D01*
X216000Y227767D01*
X216250Y228017D01*
X216417Y228308D01*
X216500Y228600D01*
Y228892D01*
X216417Y229183D01*
X216292Y229433D01*
X216125Y229642D01*
G01X214417Y230808D02*
X214167Y231058D01*
X214042Y231350D01*
X214000Y231683D01*
X214083Y232100D01*
X214292Y232392D01*
X214542Y232475D01*
X214792Y232433D01*
X215000Y232267D01*
X215417Y231433D01*
X215708Y231058D01*
X216125Y230808D01*
X216500Y230725D01*
Y232475D01*
G01X216000Y233683D02*
X216292Y233933D01*
X216458Y234267D01*
X216500Y234642D01*
X216458Y234975D01*
X216250Y235308D01*
X216000Y235517D01*
X215750Y235558D01*
X215458Y235475D01*
X215250Y235183D01*
X215167Y234892D01*
Y234517D01*
G01Y234892D02*
X215042Y235142D01*
X214833Y235350D01*
X214583Y235433D01*
X214333Y235350D01*
X214125Y235142D01*
X214000Y234767D01*
X214042Y234392D01*
X214208Y234017D01*
G01X216000Y236683D02*
X216292Y236933D01*
X216458Y237267D01*
X216500Y237642D01*
X216458Y237975D01*
X216250Y238308D01*
X216000Y238517D01*
X215750Y238558D01*
X215458Y238475D01*
X215250Y238183D01*
X215167Y237892D01*
Y237517D01*
G01Y237892D02*
X215042Y238142D01*
X214833Y238350D01*
X214583Y238433D01*
X214333Y238350D01*
X214125Y238142D01*
X214000Y237767D01*
X214042Y237392D01*
X214208Y237017D01*
G01X200037Y243178D02*
X199787Y243303D01*
X199495Y243386D01*
X199162D01*
X198787Y243261D01*
X198495Y243053D01*
X198287Y242803D01*
X198120Y242386D01*
X198078Y242011D01*
X198162Y241636D01*
X198287Y241386D01*
X198537Y241136D01*
X198828Y240969D01*
X199120Y240886D01*
X199412D01*
X199703Y240969D01*
X199953Y241094D01*
X200162Y241261D01*
G01X202120Y240886D02*
Y243386D01*
X201620Y242886D01*
G01Y240886D02*
X202620D01*
G01X204328Y241928D02*
X204620Y242219D01*
X204870Y242386D01*
X205203Y242469D01*
X205495Y242386D01*
X205703Y242219D01*
X205870Y241969D01*
X205912Y241678D01*
X205870Y241428D01*
X205703Y241178D01*
X205453Y240969D01*
X205162Y240886D01*
X204828Y240969D01*
X204537Y241219D01*
X204370Y241594D01*
X204328Y242011D01*
X204412Y242553D01*
X204537Y242844D01*
X204745Y243136D01*
X205037Y243344D01*
X205328Y243386D01*
X205620Y243303D01*
X205828Y243094D01*
G01X208120Y240886D02*
Y243386D01*
X207620Y242886D01*
G01Y240886D02*
X208620D01*
G01X200037Y247178D02*
X199787Y247303D01*
X199495Y247386D01*
X199162D01*
X198787Y247261D01*
X198495Y247053D01*
X198287Y246803D01*
X198120Y246386D01*
X198078Y246011D01*
X198162Y245636D01*
X198287Y245386D01*
X198537Y245136D01*
X198828Y244969D01*
X199120Y244886D01*
X199412D01*
X199703Y244969D01*
X199953Y245094D01*
X200162Y245261D01*
G01X202120Y244886D02*
Y247386D01*
X201620Y246886D01*
G01Y244886D02*
X202620D01*
G01X204328Y245928D02*
X204620Y246219D01*
X204870Y246386D01*
X205203Y246469D01*
X205495Y246386D01*
X205703Y246219D01*
X205870Y245969D01*
X205912Y245678D01*
X205870Y245428D01*
X205703Y245178D01*
X205453Y244969D01*
X205162Y244886D01*
X204828Y244969D01*
X204537Y245219D01*
X204370Y245594D01*
X204328Y246011D01*
X204412Y246553D01*
X204537Y246844D01*
X204745Y247136D01*
X205037Y247344D01*
X205328Y247386D01*
X205620Y247303D01*
X205828Y247094D01*
G01X208120Y247386D02*
X207787Y247303D01*
X207537Y247094D01*
X207370Y246844D01*
X207245Y246511D01*
X207203Y246136D01*
X207245Y245761D01*
X207370Y245428D01*
X207537Y245178D01*
X207787Y244969D01*
X208120Y244886D01*
X208453Y244969D01*
X208703Y245178D01*
X208870Y245428D01*
X208995Y245761D01*
X209037Y246136D01*
X208995Y246511D01*
X208870Y246844D01*
X208703Y247094D01*
X208453Y247303D01*
X208120Y247386D01*
G01X200017Y235492D02*
X199767Y235617D01*
X199475Y235700D01*
X199142D01*
X198767Y235575D01*
X198475Y235367D01*
X198267Y235117D01*
X198100Y234700D01*
X198058Y234325D01*
X198142Y233950D01*
X198267Y233700D01*
X198517Y233450D01*
X198808Y233283D01*
X199100Y233200D01*
X199392D01*
X199683Y233283D01*
X199933Y233408D01*
X200142Y233575D01*
G01X202100Y233200D02*
Y235700D01*
X201600Y235200D01*
G01Y233200D02*
X202600D01*
G01X204308Y234242D02*
X204600Y234533D01*
X204850Y234700D01*
X205183Y234783D01*
X205475Y234700D01*
X205683Y234533D01*
X205850Y234283D01*
X205892Y233992D01*
X205850Y233742D01*
X205683Y233492D01*
X205433Y233283D01*
X205142Y233200D01*
X204808Y233283D01*
X204517Y233533D01*
X204350Y233908D01*
X204308Y234325D01*
X204392Y234867D01*
X204517Y235158D01*
X204725Y235450D01*
X205017Y235658D01*
X205308Y235700D01*
X205600Y235617D01*
X205808Y235408D01*
G01X207308Y235283D02*
X207558Y235533D01*
X207850Y235658D01*
X208183Y235700D01*
X208600Y235617D01*
X208892Y235408D01*
X208975Y235158D01*
X208933Y234908D01*
X208767Y234700D01*
X207933Y234283D01*
X207558Y233992D01*
X207308Y233575D01*
X207225Y233200D01*
X208975D01*
G01X218367Y232100D02*
Y234600D01*
X219408D01*
X219742Y234475D01*
X219950Y234308D01*
X220033Y233975D01*
X219950Y233642D01*
X219700Y233433D01*
X219408Y233308D01*
X218367D01*
G01X219408D02*
X220033Y232100D01*
G01X222200D02*
Y234600D01*
X221700Y234100D01*
G01Y232100D02*
X222700D01*
G01X225117D02*
X225200Y232642D01*
X225325Y233100D01*
X225492Y233517D01*
X225700Y233975D01*
X226033Y234600D01*
X224367D01*
G01X228200Y232100D02*
Y234600D01*
X227700Y234100D01*
G01Y232100D02*
X228700D01*
G01X218467Y227500D02*
Y230000D01*
X219508D01*
X219842Y229875D01*
X220050Y229708D01*
X220133Y229375D01*
X220050Y229042D01*
X219800Y228833D01*
X219508Y228708D01*
X218467D01*
G01X219508D02*
X220133Y227500D01*
G01X222300D02*
Y230000D01*
X221800Y229500D01*
G01Y227500D02*
X222800D01*
G01X224508Y228542D02*
X224800Y228833D01*
X225050Y229000D01*
X225383Y229083D01*
X225675Y229000D01*
X225883Y228833D01*
X226050Y228583D01*
X226092Y228292D01*
X226050Y228042D01*
X225883Y227792D01*
X225633Y227583D01*
X225342Y227500D01*
X225008Y227583D01*
X224717Y227833D01*
X224550Y228208D01*
X224508Y228625D01*
X224592Y229167D01*
X224717Y229458D01*
X224925Y229750D01*
X225217Y229958D01*
X225508Y230000D01*
X225800Y229917D01*
X226008Y229708D01*
G01X228300Y227500D02*
X228592Y227542D01*
X228925Y227667D01*
X229133Y227875D01*
X229217Y228167D01*
X229133Y228458D01*
X228883Y228708D01*
X228508Y228833D01*
X228092D01*
X227842Y228917D01*
X227633Y229125D01*
X227550Y229417D01*
X227675Y229708D01*
X227967Y229917D01*
X228300Y230000D01*
X228633Y229917D01*
X228925Y229708D01*
X229050Y229417D01*
X228967Y229125D01*
X228758Y228917D01*
X228508Y228833D01*
X228092D01*
X227717Y228708D01*
X227467Y228458D01*
X227383Y228167D01*
X227467Y227875D01*
X227675Y227667D01*
X228008Y227542D01*
X228300Y227500D01*
G01X165167Y275000D02*
Y277500D01*
X166208D01*
X166542Y277375D01*
X166750Y277208D01*
X166833Y276875D01*
X166750Y276542D01*
X166500Y276333D01*
X166208Y276208D01*
X165167D01*
G01X166208D02*
X166833Y275000D01*
G01X169000D02*
X169292Y275042D01*
X169625Y275167D01*
X169833Y275375D01*
X169917Y275667D01*
X169833Y275958D01*
X169583Y276208D01*
X169208Y276333D01*
X168792D01*
X168542Y276417D01*
X168333Y276625D01*
X168250Y276917D01*
X168375Y277208D01*
X168667Y277417D01*
X169000Y277500D01*
X169333Y277417D01*
X169625Y277208D01*
X169750Y276917D01*
X169667Y276625D01*
X169458Y276417D01*
X169208Y276333D01*
X168792D01*
X168417Y276208D01*
X168167Y275958D01*
X168083Y275667D01*
X168167Y275375D01*
X168375Y275167D01*
X168708Y275042D01*
X169000Y275000D01*
G01X171083Y275375D02*
X171333Y275167D01*
X171625Y275042D01*
X172000Y275000D01*
X172375Y275083D01*
X172667Y275250D01*
X172875Y275542D01*
X172917Y275875D01*
X172833Y276208D01*
X172625Y276417D01*
X172333Y276583D01*
X172042Y276625D01*
X171750Y276583D01*
X171375Y276417D01*
X171500Y277500D01*
X172625D01*
G01X165167Y270500D02*
Y273000D01*
X166208D01*
X166542Y272875D01*
X166750Y272708D01*
X166833Y272375D01*
X166750Y272042D01*
X166500Y271833D01*
X166208Y271708D01*
X165167D01*
G01X166208D02*
X166833Y270500D01*
G01X169000D02*
X169292Y270542D01*
X169625Y270667D01*
X169833Y270875D01*
X169917Y271167D01*
X169833Y271458D01*
X169583Y271708D01*
X169208Y271833D01*
X168792D01*
X168542Y271917D01*
X168333Y272125D01*
X168250Y272417D01*
X168375Y272708D01*
X168667Y272917D01*
X169000Y273000D01*
X169333Y272917D01*
X169625Y272708D01*
X169750Y272417D01*
X169667Y272125D01*
X169458Y271917D01*
X169208Y271833D01*
X168792D01*
X168417Y271708D01*
X168167Y271458D01*
X168083Y271167D01*
X168167Y270875D01*
X168375Y270667D01*
X168708Y270542D01*
X169000Y270500D01*
G01X172500D02*
Y273000D01*
X170958Y271208D01*
X173042D01*
G01X165067Y264700D02*
Y267200D01*
X166108D01*
X166442Y267075D01*
X166650Y266908D01*
X166733Y266575D01*
X166650Y266242D01*
X166400Y266033D01*
X166108Y265908D01*
X165067D01*
G01X166108D02*
X166733Y264700D01*
G01X168900D02*
X169192Y264742D01*
X169525Y264867D01*
X169733Y265075D01*
X169817Y265367D01*
X169733Y265658D01*
X169483Y265908D01*
X169108Y266033D01*
X168692D01*
X168442Y266117D01*
X168233Y266325D01*
X168150Y266617D01*
X168275Y266908D01*
X168567Y267117D01*
X168900Y267200D01*
X169233Y267117D01*
X169525Y266908D01*
X169650Y266617D01*
X169567Y266325D01*
X169358Y266117D01*
X169108Y266033D01*
X168692D01*
X168317Y265908D01*
X168067Y265658D01*
X167983Y265367D01*
X168067Y265075D01*
X168275Y264867D01*
X168608Y264742D01*
X168900Y264700D01*
G01X170983Y265200D02*
X171233Y264908D01*
X171567Y264742D01*
X171942Y264700D01*
X172275Y264742D01*
X172608Y264950D01*
X172817Y265200D01*
X172858Y265450D01*
X172775Y265742D01*
X172483Y265950D01*
X172192Y266033D01*
X171817D01*
G01X172192D02*
X172442Y266158D01*
X172650Y266367D01*
X172733Y266617D01*
X172650Y266867D01*
X172442Y267075D01*
X172067Y267200D01*
X171692Y267158D01*
X171317Y266992D01*
G01X164767Y260400D02*
Y262900D01*
X165808D01*
X166142Y262775D01*
X166350Y262608D01*
X166433Y262275D01*
X166350Y261942D01*
X166100Y261733D01*
X165808Y261608D01*
X164767D01*
G01X165808D02*
X166433Y260400D01*
G01X168600D02*
X168892Y260442D01*
X169225Y260567D01*
X169433Y260775D01*
X169517Y261067D01*
X169433Y261358D01*
X169183Y261608D01*
X168808Y261733D01*
X168392D01*
X168142Y261817D01*
X167933Y262025D01*
X167850Y262317D01*
X167975Y262608D01*
X168267Y262817D01*
X168600Y262900D01*
X168933Y262817D01*
X169225Y262608D01*
X169350Y262317D01*
X169267Y262025D01*
X169058Y261817D01*
X168808Y261733D01*
X168392D01*
X168017Y261608D01*
X167767Y261358D01*
X167683Y261067D01*
X167767Y260775D01*
X167975Y260567D01*
X168308Y260442D01*
X168600Y260400D01*
G01X170808Y262483D02*
X171058Y262733D01*
X171350Y262858D01*
X171683Y262900D01*
X172100Y262817D01*
X172392Y262608D01*
X172475Y262358D01*
X172433Y262108D01*
X172267Y261900D01*
X171433Y261483D01*
X171058Y261192D01*
X170808Y260775D01*
X170725Y260400D01*
X172475D01*
G01X164567Y254500D02*
Y257000D01*
X165608D01*
X165942Y256875D01*
X166150Y256708D01*
X166233Y256375D01*
X166150Y256042D01*
X165900Y255833D01*
X165608Y255708D01*
X164567D01*
G01X165608D02*
X166233Y254500D01*
G01X168400D02*
X168692Y254542D01*
X169025Y254667D01*
X169233Y254875D01*
X169317Y255167D01*
X169233Y255458D01*
X168983Y255708D01*
X168608Y255833D01*
X168192D01*
X167942Y255917D01*
X167733Y256125D01*
X167650Y256417D01*
X167775Y256708D01*
X168067Y256917D01*
X168400Y257000D01*
X168733Y256917D01*
X169025Y256708D01*
X169150Y256417D01*
X169067Y256125D01*
X168858Y255917D01*
X168608Y255833D01*
X168192D01*
X167817Y255708D01*
X167567Y255458D01*
X167483Y255167D01*
X167567Y254875D01*
X167775Y254667D01*
X168108Y254542D01*
X168400Y254500D01*
G01X171400D02*
Y257000D01*
X170900Y256500D01*
G01Y254500D02*
X171900D01*
G01X164167Y250000D02*
Y252500D01*
X165208D01*
X165542Y252375D01*
X165750Y252208D01*
X165833Y251875D01*
X165750Y251542D01*
X165500Y251333D01*
X165208Y251208D01*
X164167D01*
G01X165208D02*
X165833Y250000D01*
G01X168000D02*
X168292Y250042D01*
X168625Y250167D01*
X168833Y250375D01*
X168917Y250667D01*
X168833Y250958D01*
X168583Y251208D01*
X168208Y251333D01*
X167792D01*
X167542Y251417D01*
X167333Y251625D01*
X167250Y251917D01*
X167375Y252208D01*
X167667Y252417D01*
X168000Y252500D01*
X168333Y252417D01*
X168625Y252208D01*
X168750Y251917D01*
X168667Y251625D01*
X168458Y251417D01*
X168208Y251333D01*
X167792D01*
X167417Y251208D01*
X167167Y250958D01*
X167083Y250667D01*
X167167Y250375D01*
X167375Y250167D01*
X167708Y250042D01*
X168000Y250000D01*
G01X171000Y252500D02*
X170667Y252417D01*
X170417Y252208D01*
X170250Y251958D01*
X170125Y251625D01*
X170083Y251250D01*
X170125Y250875D01*
X170250Y250542D01*
X170417Y250292D01*
X170667Y250083D01*
X171000Y250000D01*
X171333Y250083D01*
X171583Y250292D01*
X171750Y250542D01*
X171875Y250875D01*
X171917Y251250D01*
X171875Y251625D01*
X171750Y251958D01*
X171583Y252208D01*
X171333Y252417D01*
X171000Y252500D01*
G01X163167Y245300D02*
Y247800D01*
X164208D01*
X164542Y247675D01*
X164750Y247508D01*
X164833Y247175D01*
X164750Y246842D01*
X164500Y246633D01*
X164208Y246508D01*
X163167D01*
G01X164208D02*
X164833Y245300D01*
G01X166917D02*
X167000Y245842D01*
X167125Y246300D01*
X167292Y246717D01*
X167500Y247175D01*
X167833Y247800D01*
X166167D01*
G01X169292Y245592D02*
X169583Y245383D01*
X169917Y245300D01*
X170250Y245383D01*
X170542Y245633D01*
X170750Y246008D01*
X170833Y246383D01*
Y246842D01*
X170750Y247217D01*
X170542Y247550D01*
X170292Y247717D01*
X170000Y247800D01*
X169667Y247717D01*
X169417Y247550D01*
X169250Y247300D01*
X169167Y246967D01*
X169250Y246675D01*
X169458Y246383D01*
X169708Y246217D01*
X170000Y246175D01*
X170333Y246258D01*
X170583Y246467D01*
X170833Y246842D01*
G01X162567Y235300D02*
Y237800D01*
X163608D01*
X163942Y237675D01*
X164150Y237508D01*
X164233Y237175D01*
X164150Y236842D01*
X163900Y236633D01*
X163608Y236508D01*
X162567D01*
G01X163608D02*
X164233Y235300D01*
G01X165483Y235675D02*
X165733Y235467D01*
X166025Y235342D01*
X166400Y235300D01*
X166775Y235383D01*
X167067Y235550D01*
X167275Y235842D01*
X167317Y236175D01*
X167233Y236508D01*
X167025Y236717D01*
X166733Y236883D01*
X166442Y236925D01*
X166150Y236883D01*
X165775Y236717D01*
X165900Y237800D01*
X167025D01*
G01X168483Y235800D02*
X168733Y235508D01*
X169067Y235342D01*
X169442Y235300D01*
X169775Y235342D01*
X170108Y235550D01*
X170317Y235800D01*
X170358Y236050D01*
X170275Y236342D01*
X169983Y236550D01*
X169692Y236633D01*
X169317D01*
G01X169692D02*
X169942Y236758D01*
X170150Y236967D01*
X170233Y237217D01*
X170150Y237467D01*
X169942Y237675D01*
X169567Y237800D01*
X169192Y237758D01*
X168817Y237592D01*
G01X159467Y239100D02*
Y241600D01*
X160508D01*
X160842Y241475D01*
X161050Y241308D01*
X161133Y240975D01*
X161050Y240642D01*
X160800Y240433D01*
X160508Y240308D01*
X159467D01*
G01X160508D02*
X161133Y239100D01*
G01X163300D02*
Y241600D01*
X162800Y241100D01*
G01Y239100D02*
X163800D01*
G01X166300Y241600D02*
X165967Y241517D01*
X165717Y241308D01*
X165550Y241058D01*
X165425Y240725D01*
X165383Y240350D01*
X165425Y239975D01*
X165550Y239642D01*
X165717Y239392D01*
X165967Y239183D01*
X166300Y239100D01*
X166633Y239183D01*
X166883Y239392D01*
X167050Y239642D01*
X167175Y239975D01*
X167217Y240350D01*
X167175Y240725D01*
X167050Y241058D01*
X166883Y241308D01*
X166633Y241517D01*
X166300Y241600D01*
G01X168383Y239475D02*
X168633Y239267D01*
X168925Y239142D01*
X169300Y239100D01*
X169675Y239183D01*
X169967Y239350D01*
X170175Y239642D01*
X170217Y239975D01*
X170133Y240308D01*
X169925Y240517D01*
X169633Y240683D01*
X169342Y240725D01*
X169050Y240683D01*
X168675Y240517D01*
X168800Y241600D01*
X169925D01*
G01X203042Y212913D02*
X200542D01*
Y213913D01*
X200667Y214246D01*
X200959Y214496D01*
X201292Y214579D01*
X201625Y214496D01*
X201875Y214288D01*
X202000Y213913D01*
Y212913D01*
G01X203042Y215913D02*
X200542D01*
Y216954D01*
X200667Y217288D01*
X200834Y217496D01*
X201167Y217579D01*
X201500Y217496D01*
X201709Y217246D01*
X201834Y216954D01*
Y215913D01*
G01Y216954D02*
X203042Y217579D01*
G01X202542Y218829D02*
X202834Y219079D01*
X203000Y219413D01*
X203042Y219788D01*
X203000Y220121D01*
X202792Y220454D01*
X202542Y220663D01*
X202292Y220704D01*
X202000Y220621D01*
X201792Y220329D01*
X201709Y220038D01*
Y219663D01*
G01Y220038D02*
X201584Y220288D01*
X201375Y220496D01*
X201125Y220579D01*
X200875Y220496D01*
X200667Y220288D01*
X200542Y219913D01*
X200584Y219538D01*
X200750Y219163D01*
G01X202667Y221829D02*
X202875Y222079D01*
X203000Y222371D01*
X203042Y222746D01*
X202959Y223121D01*
X202792Y223413D01*
X202500Y223621D01*
X202167Y223663D01*
X201834Y223579D01*
X201625Y223371D01*
X201459Y223079D01*
X201417Y222788D01*
X201459Y222496D01*
X201625Y222121D01*
X200542Y222246D01*
Y223371D01*
G01X173100Y208867D02*
X170600D01*
Y209867D01*
X170725Y210200D01*
X171017Y210450D01*
X171350Y210533D01*
X171683Y210450D01*
X171933Y210242D01*
X172058Y209867D01*
Y208867D01*
G01X173100Y211867D02*
X170600D01*
Y212908D01*
X170725Y213242D01*
X170892Y213450D01*
X171225Y213533D01*
X171558Y213450D01*
X171767Y213200D01*
X171892Y212908D01*
Y211867D01*
G01Y212908D02*
X173100Y213533D01*
G01X172600Y214783D02*
X172892Y215033D01*
X173058Y215367D01*
X173100Y215742D01*
X173058Y216075D01*
X172850Y216408D01*
X172600Y216617D01*
X172350Y216658D01*
X172058Y216575D01*
X171850Y216283D01*
X171767Y215992D01*
Y215617D01*
G01Y215992D02*
X171642Y216242D01*
X171433Y216450D01*
X171183Y216533D01*
X170933Y216450D01*
X170725Y216242D01*
X170600Y215867D01*
X170642Y215492D01*
X170808Y215117D01*
G01X173100Y219200D02*
X170600D01*
X172392Y217658D01*
Y219742D01*
G01X206752Y212990D02*
X204252D01*
Y213990D01*
X204377Y214323D01*
X204669Y214573D01*
X205002Y214656D01*
X205335Y214573D01*
X205585Y214365D01*
X205710Y213990D01*
Y212990D01*
G01X206752Y215990D02*
X204252D01*
Y217031D01*
X204377Y217365D01*
X204544Y217573D01*
X204877Y217656D01*
X205210Y217573D01*
X205419Y217323D01*
X205544Y217031D01*
Y215990D01*
G01Y217031D02*
X206752Y217656D01*
G01X206252Y218906D02*
X206544Y219156D01*
X206710Y219490D01*
X206752Y219865D01*
X206710Y220198D01*
X206502Y220531D01*
X206252Y220740D01*
X206002Y220781D01*
X205710Y220698D01*
X205502Y220406D01*
X205419Y220115D01*
Y219740D01*
G01Y220115D02*
X205294Y220365D01*
X205085Y220573D01*
X204835Y220656D01*
X204585Y220573D01*
X204377Y220365D01*
X204252Y219990D01*
X204294Y219615D01*
X204460Y219240D01*
G01X206752Y222823D02*
X206710Y223115D01*
X206585Y223448D01*
X206377Y223656D01*
X206085Y223740D01*
X205794Y223656D01*
X205544Y223406D01*
X205419Y223031D01*
Y222615D01*
X205335Y222365D01*
X205127Y222156D01*
X204835Y222073D01*
X204544Y222198D01*
X204335Y222490D01*
X204252Y222823D01*
X204335Y223156D01*
X204544Y223448D01*
X204835Y223573D01*
X205127Y223490D01*
X205335Y223281D01*
X205419Y223031D01*
Y222615D01*
X205544Y222240D01*
X205794Y221990D01*
X206085Y221906D01*
X206377Y221990D01*
X206585Y222198D01*
X206710Y222531D01*
X206752Y222823D01*
G01X184967Y220900D02*
Y223400D01*
X185967D01*
X186300Y223275D01*
X186550Y222983D01*
X186633Y222650D01*
X186550Y222317D01*
X186342Y222067D01*
X185967Y221942D01*
X184967D01*
G01X187967Y220900D02*
Y223400D01*
X189008D01*
X189342Y223275D01*
X189550Y223108D01*
X189633Y222775D01*
X189550Y222442D01*
X189300Y222233D01*
X189008Y222108D01*
X187967D01*
G01X189008D02*
X189633Y220900D01*
G01X190883Y221400D02*
X191133Y221108D01*
X191467Y220942D01*
X191842Y220900D01*
X192175Y220942D01*
X192508Y221150D01*
X192717Y221400D01*
X192758Y221650D01*
X192675Y221942D01*
X192383Y222150D01*
X192092Y222233D01*
X191717D01*
G01X192092D02*
X192342Y222358D01*
X192550Y222567D01*
X192633Y222817D01*
X192550Y223067D01*
X192342Y223275D01*
X191967Y223400D01*
X191592Y223358D01*
X191217Y223192D01*
G01X194800Y220900D02*
Y223400D01*
X194300Y222900D01*
G01Y220900D02*
X195300D01*
G01X199308Y212751D02*
X196808D01*
Y213751D01*
X196933Y214084D01*
X197225Y214334D01*
X197558Y214417D01*
X197891Y214334D01*
X198141Y214126D01*
X198266Y213751D01*
Y212751D01*
G01X197016Y217501D02*
X196891Y217251D01*
X196808Y216959D01*
Y216626D01*
X196933Y216251D01*
X197141Y215959D01*
X197391Y215751D01*
X197808Y215584D01*
X198183Y215542D01*
X198558Y215626D01*
X198808Y215751D01*
X199058Y216001D01*
X199225Y216292D01*
X199308Y216584D01*
Y216876D01*
X199225Y217167D01*
X199100Y217417D01*
X198933Y217626D01*
G01X198808Y218667D02*
X199100Y218917D01*
X199266Y219251D01*
X199308Y219626D01*
X199266Y219959D01*
X199058Y220292D01*
X198808Y220501D01*
X198558Y220542D01*
X198266Y220459D01*
X198058Y220167D01*
X197975Y219876D01*
Y219501D01*
G01Y219876D02*
X197850Y220126D01*
X197641Y220334D01*
X197391Y220417D01*
X197141Y220334D01*
X196933Y220126D01*
X196808Y219751D01*
X196850Y219376D01*
X197016Y219001D01*
G01X199308Y222584D02*
X199266Y222876D01*
X199141Y223209D01*
X198933Y223417D01*
X198641Y223501D01*
X198350Y223417D01*
X198100Y223167D01*
X197975Y222792D01*
Y222376D01*
X197891Y222126D01*
X197683Y221917D01*
X197391Y221834D01*
X197100Y221959D01*
X196891Y222251D01*
X196808Y222584D01*
X196891Y222917D01*
X197100Y223209D01*
X197391Y223334D01*
X197683Y223251D01*
X197891Y223042D01*
X197975Y222792D01*
Y222376D01*
X198100Y222001D01*
X198350Y221751D01*
X198641Y221667D01*
X198933Y221751D01*
X199141Y221959D01*
X199266Y222292D01*
X199308Y222584D01*
G01X183267Y216800D02*
Y219300D01*
X184267D01*
X184600Y219175D01*
X184850Y218883D01*
X184933Y218550D01*
X184850Y218217D01*
X184642Y217967D01*
X184267Y217842D01*
X183267D01*
G01X188017Y219092D02*
X187767Y219217D01*
X187475Y219300D01*
X187142D01*
X186767Y219175D01*
X186475Y218967D01*
X186267Y218717D01*
X186100Y218300D01*
X186058Y217925D01*
X186142Y217550D01*
X186267Y217300D01*
X186517Y217050D01*
X186808Y216883D01*
X187100Y216800D01*
X187392D01*
X187683Y216883D01*
X187933Y217008D01*
X188142Y217175D01*
G01X189183Y217300D02*
X189433Y217008D01*
X189767Y216842D01*
X190142Y216800D01*
X190475Y216842D01*
X190808Y217050D01*
X191017Y217300D01*
X191058Y217550D01*
X190975Y217842D01*
X190683Y218050D01*
X190392Y218133D01*
X190017D01*
G01X190392D02*
X190642Y218258D01*
X190850Y218467D01*
X190933Y218717D01*
X190850Y218967D01*
X190642Y219175D01*
X190267Y219300D01*
X189892Y219258D01*
X189517Y219092D01*
G01X193100Y216800D02*
Y219300D01*
X192600Y218800D01*
G01Y216800D02*
X193600D01*
G01X210700Y205867D02*
X208200D01*
Y206867D01*
X208325Y207200D01*
X208617Y207450D01*
X208950Y207533D01*
X209283Y207450D01*
X209533Y207242D01*
X209658Y206867D01*
Y205867D01*
G01X208408Y210617D02*
X208283Y210367D01*
X208200Y210075D01*
Y209742D01*
X208325Y209367D01*
X208533Y209075D01*
X208783Y208867D01*
X209200Y208700D01*
X209575Y208658D01*
X209950Y208742D01*
X210200Y208867D01*
X210450Y209117D01*
X210617Y209408D01*
X210700Y209700D01*
Y209992D01*
X210617Y210283D01*
X210492Y210533D01*
X210325Y210742D01*
G01X210200Y211783D02*
X210492Y212033D01*
X210658Y212367D01*
X210700Y212742D01*
X210658Y213075D01*
X210450Y213408D01*
X210200Y213617D01*
X209950Y213658D01*
X209658Y213575D01*
X209450Y213283D01*
X209367Y212992D01*
Y212617D01*
G01Y212992D02*
X209242Y213242D01*
X209033Y213450D01*
X208783Y213533D01*
X208533Y213450D01*
X208325Y213242D01*
X208200Y212867D01*
X208242Y212492D01*
X208408Y212117D01*
G01X208200Y215700D02*
X208283Y215367D01*
X208492Y215117D01*
X208742Y214950D01*
X209075Y214825D01*
X209450Y214783D01*
X209825Y214825D01*
X210158Y214950D01*
X210408Y215117D01*
X210617Y215367D01*
X210700Y215700D01*
X210617Y216033D01*
X210408Y216283D01*
X210158Y216450D01*
X209825Y216575D01*
X209450Y216617D01*
X209075Y216575D01*
X208742Y216450D01*
X208492Y216283D01*
X208283Y216033D01*
X208200Y215700D01*
G01X171267Y221000D02*
Y223500D01*
X172267D01*
X172600Y223375D01*
X172850Y223083D01*
X172933Y222750D01*
X172850Y222417D01*
X172642Y222167D01*
X172267Y222042D01*
X171267D01*
G01X176017Y223292D02*
X175767Y223417D01*
X175475Y223500D01*
X175142D01*
X174767Y223375D01*
X174475Y223167D01*
X174267Y222917D01*
X174100Y222500D01*
X174058Y222125D01*
X174142Y221750D01*
X174267Y221500D01*
X174517Y221250D01*
X174808Y221083D01*
X175100Y221000D01*
X175392D01*
X175683Y221083D01*
X175933Y221208D01*
X176142Y221375D01*
G01X177183Y221500D02*
X177433Y221208D01*
X177767Y221042D01*
X178142Y221000D01*
X178475Y221042D01*
X178808Y221250D01*
X179017Y221500D01*
X179058Y221750D01*
X178975Y222042D01*
X178683Y222250D01*
X178392Y222333D01*
X178017D01*
G01X178392D02*
X178642Y222458D01*
X178850Y222667D01*
X178933Y222917D01*
X178850Y223167D01*
X178642Y223375D01*
X178267Y223500D01*
X177892Y223458D01*
X177517Y223292D01*
G01X180183Y221500D02*
X180433Y221208D01*
X180767Y221042D01*
X181142Y221000D01*
X181475Y221042D01*
X181808Y221250D01*
X182017Y221500D01*
X182058Y221750D01*
X181975Y222042D01*
X181683Y222250D01*
X181392Y222333D01*
X181017D01*
G01X181392D02*
X181642Y222458D01*
X181850Y222667D01*
X181933Y222917D01*
X181850Y223167D01*
X181642Y223375D01*
X181267Y223500D01*
X180892Y223458D01*
X180517Y223292D01*
G01X203600Y251300D02*
Y248800D01*
G01X202642Y251300D02*
X204558D01*
G01X205767Y248800D02*
Y251300D01*
X206767D01*
X207100Y251175D01*
X207350Y250883D01*
X207433Y250550D01*
X207350Y250217D01*
X207142Y249967D01*
X206767Y249842D01*
X205767D01*
G01X209600Y248800D02*
Y251300D01*
X209100Y250800D01*
G01Y248800D02*
X210100D01*
G01X211808Y250883D02*
X212058Y251133D01*
X212350Y251258D01*
X212683Y251300D01*
X213100Y251217D01*
X213392Y251008D01*
X213475Y250758D01*
X213433Y250508D01*
X213267Y250300D01*
X212433Y249883D01*
X212058Y249592D01*
X211808Y249175D01*
X211725Y248800D01*
X213475D01*
G01X214808Y249842D02*
X215100Y250133D01*
X215350Y250300D01*
X215683Y250383D01*
X215975Y250300D01*
X216183Y250133D01*
X216350Y249883D01*
X216392Y249592D01*
X216350Y249342D01*
X216183Y249092D01*
X215933Y248883D01*
X215642Y248800D01*
X215308Y248883D01*
X215017Y249133D01*
X214850Y249508D01*
X214808Y249925D01*
X214892Y250467D01*
X215017Y250758D01*
X215225Y251050D01*
X215517Y251258D01*
X215808Y251300D01*
X216100Y251217D01*
X216308Y251008D01*
G01X199000Y256300D02*
Y253800D01*
G01X198042Y256300D02*
X199958D01*
G01X201167Y253800D02*
Y256300D01*
X202167D01*
X202500Y256175D01*
X202750Y255883D01*
X202833Y255550D01*
X202750Y255217D01*
X202542Y254967D01*
X202167Y254842D01*
X201167D01*
G01X205000Y253800D02*
Y256300D01*
X204500Y255800D01*
G01Y253800D02*
X205500D01*
G01X207208Y255883D02*
X207458Y256133D01*
X207750Y256258D01*
X208083Y256300D01*
X208500Y256217D01*
X208792Y256008D01*
X208875Y255758D01*
X208833Y255508D01*
X208667Y255300D01*
X207833Y254883D01*
X207458Y254592D01*
X207208Y254175D01*
X207125Y253800D01*
X208875D01*
G01X210917D02*
X211000Y254342D01*
X211125Y254800D01*
X211292Y255217D01*
X211500Y255675D01*
X211833Y256300D01*
X210167D01*
G01X198700Y263100D02*
Y260600D01*
G01X197742Y263100D02*
X199658D01*
G01X200867Y260600D02*
Y263100D01*
X201867D01*
X202200Y262975D01*
X202450Y262683D01*
X202533Y262350D01*
X202450Y262017D01*
X202242Y261767D01*
X201867Y261642D01*
X200867D01*
G01X204700Y260600D02*
Y263100D01*
X204200Y262600D01*
G01Y260600D02*
X205200D01*
G01X206908Y262683D02*
X207158Y262933D01*
X207450Y263058D01*
X207783Y263100D01*
X208200Y263017D01*
X208492Y262808D01*
X208575Y262558D01*
X208533Y262308D01*
X208367Y262100D01*
X207533Y261683D01*
X207158Y261392D01*
X206908Y260975D01*
X206825Y260600D01*
X208575D01*
G01X210700D02*
X210992Y260642D01*
X211325Y260767D01*
X211533Y260975D01*
X211617Y261267D01*
X211533Y261558D01*
X211283Y261808D01*
X210908Y261933D01*
X210492D01*
X210242Y262017D01*
X210033Y262225D01*
X209950Y262517D01*
X210075Y262808D01*
X210367Y263017D01*
X210700Y263100D01*
X211033Y263017D01*
X211325Y262808D01*
X211450Y262517D01*
X211367Y262225D01*
X211158Y262017D01*
X210908Y261933D01*
X210492D01*
X210117Y261808D01*
X209867Y261558D01*
X209783Y261267D01*
X209867Y260975D01*
X210075Y260767D01*
X210408Y260642D01*
X210700Y260600D01*
G01X201400Y268800D02*
Y266300D01*
G01X200442Y268800D02*
X202358D01*
G01X203567Y266300D02*
Y268800D01*
X204567D01*
X204900Y268675D01*
X205150Y268383D01*
X205233Y268050D01*
X205150Y267717D01*
X204942Y267467D01*
X204567Y267342D01*
X203567D01*
G01X207400Y266300D02*
Y268800D01*
X206900Y268300D01*
G01Y266300D02*
X207900D01*
G01X209608Y268383D02*
X209858Y268633D01*
X210150Y268758D01*
X210483Y268800D01*
X210900Y268717D01*
X211192Y268508D01*
X211275Y268258D01*
X211233Y268008D01*
X211067Y267800D01*
X210233Y267383D01*
X209858Y267092D01*
X209608Y266675D01*
X209525Y266300D01*
X211275D01*
G01X212692Y266592D02*
X212983Y266383D01*
X213317Y266300D01*
X213650Y266383D01*
X213942Y266633D01*
X214150Y267008D01*
X214233Y267383D01*
Y267842D01*
X214150Y268217D01*
X213942Y268550D01*
X213692Y268717D01*
X213400Y268800D01*
X213067Y268717D01*
X212817Y268550D01*
X212650Y268300D01*
X212567Y267967D01*
X212650Y267675D01*
X212858Y267383D01*
X213108Y267217D01*
X213400Y267175D01*
X213733Y267258D01*
X213983Y267467D01*
X214233Y267842D01*
G01X201300Y275100D02*
Y272600D01*
G01X200342Y275100D02*
X202258D01*
G01X203467Y272600D02*
Y275100D01*
X204467D01*
X204800Y274975D01*
X205050Y274683D01*
X205133Y274350D01*
X205050Y274017D01*
X204842Y273767D01*
X204467Y273642D01*
X203467D01*
G01X207300Y272600D02*
Y275100D01*
X206800Y274600D01*
G01Y272600D02*
X207800D01*
G01X209383Y273100D02*
X209633Y272808D01*
X209967Y272642D01*
X210342Y272600D01*
X210675Y272642D01*
X211008Y272850D01*
X211217Y273100D01*
X211258Y273350D01*
X211175Y273642D01*
X210883Y273850D01*
X210592Y273933D01*
X210217D01*
G01X210592D02*
X210842Y274058D01*
X211050Y274267D01*
X211133Y274517D01*
X211050Y274767D01*
X210842Y274975D01*
X210467Y275100D01*
X210092Y275058D01*
X209717Y274892D01*
G01X213300Y275100D02*
X212967Y275017D01*
X212717Y274808D01*
X212550Y274558D01*
X212425Y274225D01*
X212383Y273850D01*
X212425Y273475D01*
X212550Y273142D01*
X212717Y272892D01*
X212967Y272683D01*
X213300Y272600D01*
X213633Y272683D01*
X213883Y272892D01*
X214050Y273142D01*
X214175Y273475D01*
X214217Y273850D01*
X214175Y274225D01*
X214050Y274558D01*
X213883Y274808D01*
X213633Y275017D01*
X213300Y275100D01*
G01X213008Y340417D02*
X212883Y340167D01*
X212800Y339875D01*
Y339542D01*
X212925Y339167D01*
X213133Y338875D01*
X213383Y338667D01*
X213800Y338500D01*
X214175Y338458D01*
X214550Y338542D01*
X214800Y338667D01*
X215050Y338917D01*
X215217Y339208D01*
X215300Y339500D01*
Y339792D01*
X215217Y340083D01*
X215092Y340333D01*
X214925Y340542D01*
G01X213217Y341708D02*
X212967Y341958D01*
X212842Y342250D01*
X212800Y342583D01*
X212883Y343000D01*
X213092Y343292D01*
X213342Y343375D01*
X213592Y343333D01*
X213800Y343167D01*
X214217Y342333D01*
X214508Y341958D01*
X214925Y341708D01*
X215300Y341625D01*
Y343375D01*
G01Y345500D02*
X212800D01*
X213300Y345000D01*
G01X215300D02*
Y346000D01*
G01X209208Y340317D02*
X209083Y340067D01*
X209000Y339775D01*
Y339442D01*
X209125Y339067D01*
X209333Y338775D01*
X209583Y338567D01*
X210000Y338400D01*
X210375Y338358D01*
X210750Y338442D01*
X211000Y338567D01*
X211250Y338817D01*
X211417Y339108D01*
X211500Y339400D01*
Y339692D01*
X211417Y339983D01*
X211292Y340233D01*
X211125Y340442D01*
G01X209417Y341608D02*
X209167Y341858D01*
X209042Y342150D01*
X209000Y342483D01*
X209083Y342900D01*
X209292Y343192D01*
X209542Y343275D01*
X209792Y343233D01*
X210000Y343067D01*
X210417Y342233D01*
X210708Y341858D01*
X211125Y341608D01*
X211500Y341525D01*
Y343275D01*
G01X209000Y345400D02*
X209083Y345067D01*
X209292Y344817D01*
X209542Y344650D01*
X209875Y344525D01*
X210250Y344483D01*
X210625Y344525D01*
X210958Y344650D01*
X211208Y344817D01*
X211417Y345067D01*
X211500Y345400D01*
X211417Y345733D01*
X211208Y345983D01*
X210958Y346150D01*
X210625Y346275D01*
X210250Y346317D01*
X209875Y346275D01*
X209542Y346150D01*
X209292Y345983D01*
X209083Y345733D01*
X209000Y345400D01*
G01X201808Y335617D02*
X201683Y335367D01*
X201600Y335075D01*
Y334742D01*
X201725Y334367D01*
X201933Y334075D01*
X202183Y333867D01*
X202600Y333700D01*
X202975Y333658D01*
X203350Y333742D01*
X203600Y333867D01*
X203850Y334117D01*
X204017Y334408D01*
X204100Y334700D01*
Y334992D01*
X204017Y335283D01*
X203892Y335533D01*
X203725Y335742D01*
G01X204100Y337700D02*
X201600D01*
X202100Y337200D01*
G01X204100D02*
Y338200D01*
G01X203808Y339992D02*
X204017Y340283D01*
X204100Y340617D01*
X204017Y340950D01*
X203767Y341242D01*
X203392Y341450D01*
X203017Y341533D01*
X202558D01*
X202183Y341450D01*
X201850Y341242D01*
X201683Y340992D01*
X201600Y340700D01*
X201683Y340367D01*
X201850Y340117D01*
X202100Y339950D01*
X202433Y339867D01*
X202725Y339950D01*
X203017Y340158D01*
X203183Y340408D01*
X203225Y340700D01*
X203142Y341033D01*
X202933Y341283D01*
X202558Y341533D01*
G01X198208Y335717D02*
X198083Y335467D01*
X198000Y335175D01*
Y334842D01*
X198125Y334467D01*
X198333Y334175D01*
X198583Y333967D01*
X199000Y333800D01*
X199375Y333758D01*
X199750Y333842D01*
X200000Y333967D01*
X200250Y334217D01*
X200417Y334508D01*
X200500Y334800D01*
Y335092D01*
X200417Y335383D01*
X200292Y335633D01*
X200125Y335842D01*
G01X200500Y337800D02*
X198000D01*
X198500Y337300D01*
G01X200500D02*
Y338300D01*
G01Y340800D02*
X200458Y341092D01*
X200333Y341425D01*
X200125Y341633D01*
X199833Y341717D01*
X199542Y341633D01*
X199292Y341383D01*
X199167Y341008D01*
Y340592D01*
X199083Y340342D01*
X198875Y340133D01*
X198583Y340050D01*
X198292Y340175D01*
X198083Y340467D01*
X198000Y340800D01*
X198083Y341133D01*
X198292Y341425D01*
X198583Y341550D01*
X198875Y341467D01*
X199083Y341258D01*
X199167Y341008D01*
Y340592D01*
X199292Y340217D01*
X199542Y339967D01*
X199833Y339883D01*
X200125Y339967D01*
X200333Y340175D01*
X200458Y340508D01*
X200500Y340800D01*
G01X191208Y331917D02*
X191083Y331667D01*
X191000Y331375D01*
Y331042D01*
X191125Y330667D01*
X191333Y330375D01*
X191583Y330167D01*
X192000Y330000D01*
X192375Y329958D01*
X192750Y330042D01*
X193000Y330167D01*
X193250Y330417D01*
X193417Y330708D01*
X193500Y331000D01*
Y331292D01*
X193417Y331583D01*
X193292Y331833D01*
X193125Y332042D01*
G01X193500Y334000D02*
X191000D01*
X191500Y333500D01*
G01X193500D02*
Y334500D01*
G01Y336917D02*
X192958Y337000D01*
X192500Y337125D01*
X192083Y337292D01*
X191625Y337500D01*
X191000Y337833D01*
Y336167D01*
G01X187408Y332017D02*
X187283Y331767D01*
X187200Y331475D01*
Y331142D01*
X187325Y330767D01*
X187533Y330475D01*
X187783Y330267D01*
X188200Y330100D01*
X188575Y330058D01*
X188950Y330142D01*
X189200Y330267D01*
X189450Y330517D01*
X189617Y330808D01*
X189700Y331100D01*
Y331392D01*
X189617Y331683D01*
X189492Y331933D01*
X189325Y332142D01*
G01X189700Y334100D02*
X187200D01*
X187700Y333600D01*
G01X189700D02*
Y334600D01*
G01X188658Y336308D02*
X188367Y336600D01*
X188200Y336850D01*
X188117Y337183D01*
X188200Y337475D01*
X188367Y337683D01*
X188617Y337850D01*
X188908Y337892D01*
X189158Y337850D01*
X189408Y337683D01*
X189617Y337433D01*
X189700Y337142D01*
X189617Y336808D01*
X189367Y336517D01*
X188992Y336350D01*
X188575Y336308D01*
X188033Y336392D01*
X187742Y336517D01*
X187450Y336725D01*
X187242Y337017D01*
X187200Y337308D01*
X187283Y337600D01*
X187492Y337808D01*
G01X179808Y327717D02*
X179683Y327467D01*
X179600Y327175D01*
Y326842D01*
X179725Y326467D01*
X179933Y326175D01*
X180183Y325967D01*
X180600Y325800D01*
X180975Y325758D01*
X181350Y325842D01*
X181600Y325967D01*
X181850Y326217D01*
X182017Y326508D01*
X182100Y326800D01*
Y327092D01*
X182017Y327383D01*
X181892Y327633D01*
X181725Y327842D01*
G01X182100Y329800D02*
X179600D01*
X180100Y329300D01*
G01X182100D02*
Y330300D01*
G01X181725Y331883D02*
X181933Y332133D01*
X182058Y332425D01*
X182100Y332800D01*
X182017Y333175D01*
X181850Y333467D01*
X181558Y333675D01*
X181225Y333717D01*
X180892Y333633D01*
X180683Y333425D01*
X180517Y333133D01*
X180475Y332842D01*
X180517Y332550D01*
X180683Y332175D01*
X179600Y332300D01*
Y333425D01*
G01X176108Y327817D02*
X175983Y327567D01*
X175900Y327275D01*
Y326942D01*
X176025Y326567D01*
X176233Y326275D01*
X176483Y326067D01*
X176900Y325900D01*
X177275Y325858D01*
X177650Y325942D01*
X177900Y326067D01*
X178150Y326317D01*
X178317Y326608D01*
X178400Y326900D01*
Y327192D01*
X178317Y327483D01*
X178192Y327733D01*
X178025Y327942D01*
G01X178400Y329900D02*
X175900D01*
X176400Y329400D01*
G01X178400D02*
Y330400D01*
G01Y333400D02*
X175900D01*
X177692Y331858D01*
Y333942D01*
G01X168508Y323417D02*
X168383Y323167D01*
X168300Y322875D01*
Y322542D01*
X168425Y322167D01*
X168633Y321875D01*
X168883Y321667D01*
X169300Y321500D01*
X169675Y321458D01*
X170050Y321542D01*
X170300Y321667D01*
X170550Y321917D01*
X170717Y322208D01*
X170800Y322500D01*
Y322792D01*
X170717Y323083D01*
X170592Y323333D01*
X170425Y323542D01*
G01X170800Y325500D02*
X168300D01*
X168800Y325000D01*
G01X170800D02*
Y326000D01*
G01X170300Y327583D02*
X170592Y327833D01*
X170758Y328167D01*
X170800Y328542D01*
X170758Y328875D01*
X170550Y329208D01*
X170300Y329417D01*
X170050Y329458D01*
X169758Y329375D01*
X169550Y329083D01*
X169467Y328792D01*
Y328417D01*
G01Y328792D02*
X169342Y329042D01*
X169133Y329250D01*
X168883Y329333D01*
X168633Y329250D01*
X168425Y329042D01*
X168300Y328667D01*
X168342Y328292D01*
X168508Y327917D01*
G01X164808Y323417D02*
X164683Y323167D01*
X164600Y322875D01*
Y322542D01*
X164725Y322167D01*
X164933Y321875D01*
X165183Y321667D01*
X165600Y321500D01*
X165975Y321458D01*
X166350Y321542D01*
X166600Y321667D01*
X166850Y321917D01*
X167017Y322208D01*
X167100Y322500D01*
Y322792D01*
X167017Y323083D01*
X166892Y323333D01*
X166725Y323542D01*
G01X167100Y325500D02*
X164600D01*
X165100Y325000D01*
G01X167100D02*
Y326000D01*
G01X165017Y327708D02*
X164767Y327958D01*
X164642Y328250D01*
X164600Y328583D01*
X164683Y329000D01*
X164892Y329292D01*
X165142Y329375D01*
X165392Y329333D01*
X165600Y329167D01*
X166017Y328333D01*
X166308Y327958D01*
X166725Y327708D01*
X167100Y327625D01*
Y329375D01*
G01X157908Y319817D02*
X157783Y319567D01*
X157700Y319275D01*
Y318942D01*
X157825Y318567D01*
X158033Y318275D01*
X158283Y318067D01*
X158700Y317900D01*
X159075Y317858D01*
X159450Y317942D01*
X159700Y318067D01*
X159950Y318317D01*
X160117Y318608D01*
X160200Y318900D01*
Y319192D01*
X160117Y319483D01*
X159992Y319733D01*
X159825Y319942D01*
G01X160200Y321900D02*
X157700D01*
X158200Y321400D01*
G01X160200D02*
Y322400D01*
G01Y324900D02*
X157700D01*
X158200Y324400D01*
G01X160200D02*
Y325400D01*
G01X154308Y319717D02*
X154183Y319467D01*
X154100Y319175D01*
Y318842D01*
X154225Y318467D01*
X154433Y318175D01*
X154683Y317967D01*
X155100Y317800D01*
X155475Y317758D01*
X155850Y317842D01*
X156100Y317967D01*
X156350Y318217D01*
X156517Y318508D01*
X156600Y318800D01*
Y319092D01*
X156517Y319383D01*
X156392Y319633D01*
X156225Y319842D01*
G01X156600Y321800D02*
X154100D01*
X154600Y321300D01*
G01X156600D02*
Y322300D01*
G01X154100Y324800D02*
X154183Y324467D01*
X154392Y324217D01*
X154642Y324050D01*
X154975Y323925D01*
X155350Y323883D01*
X155725Y323925D01*
X156058Y324050D01*
X156308Y324217D01*
X156517Y324467D01*
X156600Y324800D01*
X156517Y325133D01*
X156308Y325383D01*
X156058Y325550D01*
X155725Y325675D01*
X155350Y325717D01*
X154975Y325675D01*
X154642Y325550D01*
X154392Y325383D01*
X154183Y325133D01*
X154100Y324800D01*
G01X164667Y280000D02*
Y282500D01*
X165708D01*
X166042Y282375D01*
X166250Y282208D01*
X166333Y281875D01*
X166250Y281542D01*
X166000Y281333D01*
X165708Y281208D01*
X164667D01*
G01X165708D02*
X166333Y280000D01*
G01X168500D02*
X168792Y280042D01*
X169125Y280167D01*
X169333Y280375D01*
X169417Y280667D01*
X169333Y280958D01*
X169083Y281208D01*
X168708Y281333D01*
X168292D01*
X168042Y281417D01*
X167833Y281625D01*
X167750Y281917D01*
X167875Y282208D01*
X168167Y282417D01*
X168500Y282500D01*
X168833Y282417D01*
X169125Y282208D01*
X169250Y281917D01*
X169167Y281625D01*
X168958Y281417D01*
X168708Y281333D01*
X168292D01*
X167917Y281208D01*
X167667Y280958D01*
X167583Y280667D01*
X167667Y280375D01*
X167875Y280167D01*
X168208Y280042D01*
X168500Y280000D01*
G01X170708Y281042D02*
X171000Y281333D01*
X171250Y281500D01*
X171583Y281583D01*
X171875Y281500D01*
X172083Y281333D01*
X172250Y281083D01*
X172292Y280792D01*
X172250Y280542D01*
X172083Y280292D01*
X171833Y280083D01*
X171542Y280000D01*
X171208Y280083D01*
X170917Y280333D01*
X170750Y280708D01*
X170708Y281125D01*
X170792Y281667D01*
X170917Y281958D01*
X171125Y282250D01*
X171417Y282458D01*
X171708Y282500D01*
X172000Y282417D01*
X172208Y282208D01*
G01X174767Y297300D02*
Y299800D01*
X175808D01*
X176142Y299675D01*
X176350Y299508D01*
X176433Y299175D01*
X176350Y298842D01*
X176100Y298633D01*
X175808Y298508D01*
X174767D01*
G01X175808D02*
X176433Y297300D01*
G01X178517D02*
X178600Y297842D01*
X178725Y298300D01*
X178892Y298717D01*
X179100Y299175D01*
X179433Y299800D01*
X177767D01*
G01X181600Y297300D02*
Y299800D01*
X181100Y299300D01*
G01Y297300D02*
X182100D01*
G01X164667Y284500D02*
Y287000D01*
X165708D01*
X166042Y286875D01*
X166250Y286708D01*
X166333Y286375D01*
X166250Y286042D01*
X166000Y285833D01*
X165708Y285708D01*
X164667D01*
G01X165708D02*
X166333Y284500D01*
G01X167583Y284875D02*
X167833Y284667D01*
X168125Y284542D01*
X168500Y284500D01*
X168875Y284583D01*
X169167Y284750D01*
X169375Y285042D01*
X169417Y285375D01*
X169333Y285708D01*
X169125Y285917D01*
X168833Y286083D01*
X168542Y286125D01*
X168250Y286083D01*
X167875Y285917D01*
X168000Y287000D01*
X169125D01*
G01X170708Y286583D02*
X170958Y286833D01*
X171250Y286958D01*
X171583Y287000D01*
X172000Y286917D01*
X172292Y286708D01*
X172375Y286458D01*
X172333Y286208D01*
X172167Y286000D01*
X171333Y285583D01*
X170958Y285292D01*
X170708Y284875D01*
X170625Y284500D01*
X172375D01*
G01X185367Y288800D02*
Y291300D01*
X186408D01*
X186742Y291175D01*
X186950Y291008D01*
X187033Y290675D01*
X186950Y290342D01*
X186700Y290133D01*
X186408Y290008D01*
X185367D01*
G01X186408D02*
X187033Y288800D01*
G01X189200D02*
Y291300D01*
X188700Y290800D01*
G01Y288800D02*
X189700D01*
G01X192200Y291300D02*
X191867Y291217D01*
X191617Y291008D01*
X191450Y290758D01*
X191325Y290425D01*
X191283Y290050D01*
X191325Y289675D01*
X191450Y289342D01*
X191617Y289092D01*
X191867Y288883D01*
X192200Y288800D01*
X192533Y288883D01*
X192783Y289092D01*
X192950Y289342D01*
X193075Y289675D01*
X193117Y290050D01*
X193075Y290425D01*
X192950Y290758D01*
X192783Y291008D01*
X192533Y291217D01*
X192200Y291300D01*
G01X195700Y288800D02*
Y291300D01*
X194158Y289508D01*
X196242D01*
G01X160900Y326267D02*
X163400D01*
Y327933D01*
G01X163108Y329392D02*
X163317Y329683D01*
X163400Y330017D01*
X163317Y330350D01*
X163067Y330642D01*
X162692Y330850D01*
X162317Y330933D01*
X161858D01*
X161483Y330850D01*
X161150Y330642D01*
X160983Y330392D01*
X160900Y330100D01*
X160983Y329767D01*
X161150Y329517D01*
X161400Y329350D01*
X161733Y329267D01*
X162025Y329350D01*
X162317Y329558D01*
X162483Y329808D01*
X162525Y330100D01*
X162442Y330433D01*
X162233Y330683D01*
X161858Y330933D01*
G01X149567Y341400D02*
Y338900D01*
X151233D01*
G01X153400D02*
X153692Y338942D01*
X154025Y339067D01*
X154233Y339275D01*
X154317Y339567D01*
X154233Y339858D01*
X153983Y340108D01*
X153608Y340233D01*
X153192D01*
X152942Y340317D01*
X152733Y340525D01*
X152650Y340817D01*
X152775Y341108D01*
X153067Y341317D01*
X153400Y341400D01*
X153733Y341317D01*
X154025Y341108D01*
X154150Y340817D01*
X154067Y340525D01*
X153858Y340317D01*
X153608Y340233D01*
X153192D01*
X152817Y340108D01*
X152567Y339858D01*
X152483Y339567D01*
X152567Y339275D01*
X152775Y339067D01*
X153108Y338942D01*
X153400Y338900D01*
G01X150500Y324067D02*
X153000D01*
Y325733D01*
G01Y327817D02*
X152458Y327900D01*
X152000Y328025D01*
X151583Y328192D01*
X151125Y328400D01*
X150500Y328733D01*
Y327067D01*
G01X205100Y339167D02*
X207600D01*
Y340833D01*
G01Y343000D02*
X205100D01*
X205600Y342500D01*
G01X207600D02*
Y343500D01*
G01Y345917D02*
X207058Y346000D01*
X206600Y346125D01*
X206183Y346292D01*
X205725Y346500D01*
X205100Y346833D01*
Y345167D01*
G01X194400Y336967D02*
X196900D01*
Y338633D01*
G01Y340800D02*
X194400D01*
X194900Y340300D01*
G01X196900D02*
Y341300D01*
G01X196525Y342883D02*
X196733Y343133D01*
X196858Y343425D01*
X196900Y343800D01*
X196817Y344175D01*
X196650Y344467D01*
X196358Y344675D01*
X196025Y344717D01*
X195692Y344633D01*
X195483Y344425D01*
X195317Y344133D01*
X195275Y343842D01*
X195317Y343550D01*
X195483Y343175D01*
X194400Y343300D01*
Y344425D01*
G01X183100Y330867D02*
X185600D01*
Y332533D01*
G01Y334700D02*
X183100D01*
X183600Y334200D01*
G01X185600D02*
Y335200D01*
G01X185100Y336783D02*
X185392Y337033D01*
X185558Y337367D01*
X185600Y337742D01*
X185558Y338075D01*
X185350Y338408D01*
X185100Y338617D01*
X184850Y338658D01*
X184558Y338575D01*
X184350Y338283D01*
X184267Y337992D01*
Y337617D01*
G01Y337992D02*
X184142Y338242D01*
X183933Y338450D01*
X183683Y338533D01*
X183433Y338450D01*
X183225Y338242D01*
X183100Y337867D01*
X183142Y337492D01*
X183308Y337117D01*
G01X172000Y329267D02*
X174500D01*
Y330933D01*
G01Y333100D02*
X172000D01*
X172500Y332600D01*
G01X174500D02*
Y333600D01*
G01Y336100D02*
X172000D01*
X172500Y335600D01*
G01X174500D02*
Y336600D01*
G01X159167Y345800D02*
Y343300D01*
X160833D01*
G01X163000D02*
Y345800D01*
X162500Y345300D01*
G01Y343300D02*
X163500D01*
G01X166000Y345800D02*
X165667Y345717D01*
X165417Y345508D01*
X165250Y345258D01*
X165125Y344925D01*
X165083Y344550D01*
X165125Y344175D01*
X165250Y343842D01*
X165417Y343592D01*
X165667Y343383D01*
X166000Y343300D01*
X166333Y343383D01*
X166583Y343592D01*
X166750Y343842D01*
X166875Y344175D01*
X166917Y344550D01*
X166875Y344925D01*
X166750Y345258D01*
X166583Y345508D01*
X166333Y345717D01*
X166000Y345800D01*
G01X195600Y279100D02*
Y276600D01*
G01X194642Y279100D02*
X196558D01*
G01X197767Y276600D02*
Y279100D01*
X198767D01*
X199100Y278975D01*
X199350Y278683D01*
X199433Y278350D01*
X199350Y278017D01*
X199142Y277767D01*
X198767Y277642D01*
X197767D01*
G01X201600Y276600D02*
Y279100D01*
X201100Y278600D01*
G01Y276600D02*
X202100D01*
G01X203683Y277100D02*
X203933Y276808D01*
X204267Y276642D01*
X204642Y276600D01*
X204975Y276642D01*
X205308Y276850D01*
X205517Y277100D01*
X205558Y277350D01*
X205475Y277642D01*
X205183Y277850D01*
X204892Y277933D01*
X204517D01*
G01X204892D02*
X205142Y278058D01*
X205350Y278267D01*
X205433Y278517D01*
X205350Y278767D01*
X205142Y278975D01*
X204767Y279100D01*
X204392Y279058D01*
X204017Y278892D01*
G01X207600Y276600D02*
Y279100D01*
X207100Y278600D01*
G01Y276600D02*
X208100D01*
G01X200687Y282661D02*
Y280161D01*
G01X199729Y282661D02*
X201645D01*
G01X202854Y280161D02*
Y282661D01*
X203854D01*
X204187Y282536D01*
X204437Y282244D01*
X204520Y281911D01*
X204437Y281578D01*
X204229Y281328D01*
X203854Y281203D01*
X202854D01*
G01X206687Y280161D02*
Y282661D01*
X206187Y282161D01*
G01Y280161D02*
X207187D01*
G01X208770Y280661D02*
X209020Y280369D01*
X209354Y280203D01*
X209729Y280161D01*
X210062Y280203D01*
X210395Y280411D01*
X210604Y280661D01*
X210645Y280911D01*
X210562Y281203D01*
X210270Y281411D01*
X209979Y281494D01*
X209604D01*
G01X209979D02*
X210229Y281619D01*
X210437Y281828D01*
X210520Y282078D01*
X210437Y282328D01*
X210229Y282536D01*
X209854Y282661D01*
X209479Y282619D01*
X209104Y282453D01*
G01X211895Y282244D02*
X212145Y282494D01*
X212437Y282619D01*
X212770Y282661D01*
X213187Y282578D01*
X213479Y282369D01*
X213562Y282119D01*
X213520Y281869D01*
X213354Y281661D01*
X212520Y281244D01*
X212145Y280953D01*
X211895Y280536D01*
X211812Y280161D01*
X213562D01*
G01X209787Y397590D02*
X207287D01*
Y398631D01*
X207412Y398965D01*
X207579Y399173D01*
X207912Y399256D01*
X208245Y399173D01*
X208454Y398923D01*
X208579Y398631D01*
Y397590D01*
G01Y398631D02*
X209787Y399256D01*
G01X209287Y400506D02*
X209579Y400756D01*
X209745Y401090D01*
X209787Y401465D01*
X209745Y401798D01*
X209537Y402131D01*
X209287Y402340D01*
X209037Y402381D01*
X208745Y402298D01*
X208537Y402006D01*
X208454Y401715D01*
Y401340D01*
G01Y401715D02*
X208329Y401965D01*
X208120Y402173D01*
X207870Y402256D01*
X207620Y402173D01*
X207412Y401965D01*
X207287Y401590D01*
X207329Y401215D01*
X207495Y400840D01*
G01X209787Y404923D02*
X207287D01*
X209079Y403381D01*
Y405465D01*
G01X199213Y376183D02*
X199088Y375933D01*
X199005Y375641D01*
Y375308D01*
X199130Y374933D01*
X199338Y374641D01*
X199588Y374433D01*
X200005Y374266D01*
X200380Y374224D01*
X200755Y374308D01*
X201005Y374433D01*
X201255Y374683D01*
X201422Y374974D01*
X201505Y375266D01*
Y375558D01*
X201422Y375849D01*
X201297Y376099D01*
X201130Y376308D01*
G01X201505Y378266D02*
X199005D01*
X199505Y377766D01*
G01X201505D02*
Y378766D01*
G01X201130Y380349D02*
X201338Y380599D01*
X201463Y380891D01*
X201505Y381266D01*
X201422Y381641D01*
X201255Y381933D01*
X200963Y382141D01*
X200630Y382183D01*
X200297Y382099D01*
X200088Y381891D01*
X199922Y381599D01*
X199880Y381308D01*
X199922Y381016D01*
X200088Y380641D01*
X199005Y380766D01*
Y381891D01*
G01X201213Y383558D02*
X201422Y383849D01*
X201505Y384183D01*
X201422Y384516D01*
X201172Y384808D01*
X200797Y385016D01*
X200422Y385099D01*
X199963D01*
X199588Y385016D01*
X199255Y384808D01*
X199088Y384558D01*
X199005Y384266D01*
X199088Y383933D01*
X199255Y383683D01*
X199505Y383516D01*
X199838Y383433D01*
X200130Y383516D01*
X200422Y383724D01*
X200588Y383974D01*
X200630Y384266D01*
X200547Y384599D01*
X200338Y384849D01*
X199963Y385099D01*
G01X210217Y415092D02*
X209967Y415217D01*
X209675Y415300D01*
X209342D01*
X208967Y415175D01*
X208675Y414967D01*
X208467Y414717D01*
X208300Y414300D01*
X208258Y413925D01*
X208342Y413550D01*
X208467Y413300D01*
X208717Y413050D01*
X209008Y412883D01*
X209300Y412800D01*
X209592D01*
X209883Y412883D01*
X210133Y413008D01*
X210342Y413175D01*
G01X211508Y413842D02*
X211800Y414133D01*
X212050Y414300D01*
X212383Y414383D01*
X212675Y414300D01*
X212883Y414133D01*
X213050Y413883D01*
X213092Y413592D01*
X213050Y413342D01*
X212883Y413092D01*
X212633Y412883D01*
X212342Y412800D01*
X212008Y412883D01*
X211717Y413133D01*
X211550Y413508D01*
X211508Y413925D01*
X211592Y414467D01*
X211717Y414758D01*
X211925Y415050D01*
X212217Y415258D01*
X212508Y415300D01*
X212800Y415217D01*
X213008Y415008D01*
G01X215300Y412800D02*
Y415300D01*
X214800Y414800D01*
G01Y412800D02*
X215800D01*
G01X203282Y398486D02*
X203157Y398236D01*
X203074Y397944D01*
Y397611D01*
X203199Y397236D01*
X203407Y396944D01*
X203657Y396736D01*
X204074Y396569D01*
X204449Y396527D01*
X204824Y396611D01*
X205074Y396736D01*
X205324Y396986D01*
X205491Y397277D01*
X205574Y397569D01*
Y397861D01*
X205491Y398152D01*
X205366Y398402D01*
X205199Y398611D01*
G01X204532Y399777D02*
X204241Y400069D01*
X204074Y400319D01*
X203991Y400652D01*
X204074Y400944D01*
X204241Y401152D01*
X204491Y401319D01*
X204782Y401361D01*
X205032Y401319D01*
X205282Y401152D01*
X205491Y400902D01*
X205574Y400611D01*
X205491Y400277D01*
X205241Y399986D01*
X204866Y399819D01*
X204449Y399777D01*
X203907Y399861D01*
X203616Y399986D01*
X203324Y400194D01*
X203116Y400486D01*
X203074Y400777D01*
X203157Y401069D01*
X203366Y401277D01*
G01X205574Y404069D02*
X203074D01*
X204866Y402527D01*
Y404611D01*
G01X180008Y401617D02*
X179883Y401367D01*
X179800Y401075D01*
Y400742D01*
X179925Y400367D01*
X180133Y400075D01*
X180383Y399867D01*
X180800Y399700D01*
X181175Y399658D01*
X181550Y399742D01*
X181800Y399867D01*
X182050Y400117D01*
X182217Y400408D01*
X182300Y400700D01*
Y400992D01*
X182217Y401283D01*
X182092Y401533D01*
X181925Y401742D01*
G01X182300Y403700D02*
X179800D01*
X180300Y403200D01*
G01X182300D02*
Y404200D01*
G01Y406700D02*
X179800D01*
X180300Y406200D01*
G01X182300D02*
Y407200D01*
G01X181925Y408783D02*
X182133Y409033D01*
X182258Y409325D01*
X182300Y409700D01*
X182217Y410075D01*
X182050Y410367D01*
X181758Y410575D01*
X181425Y410617D01*
X181092Y410533D01*
X180883Y410325D01*
X180717Y410033D01*
X180675Y409742D01*
X180717Y409450D01*
X180883Y409075D01*
X179800Y409200D01*
Y410325D01*
G01X187600Y397067D02*
X185100D01*
Y398108D01*
X185225Y398442D01*
X185392Y398650D01*
X185725Y398733D01*
X186058Y398650D01*
X186267Y398400D01*
X186392Y398108D01*
Y397067D01*
G01Y398108D02*
X187600Y398733D01*
G01X185517Y400108D02*
X185267Y400358D01*
X185142Y400650D01*
X185100Y400983D01*
X185183Y401400D01*
X185392Y401692D01*
X185642Y401775D01*
X185892Y401733D01*
X186100Y401567D01*
X186517Y400733D01*
X186808Y400358D01*
X187225Y400108D01*
X187600Y400025D01*
Y401775D01*
G01Y404400D02*
X185100D01*
X186892Y402858D01*
Y404942D01*
G01X179100Y412967D02*
X176600D01*
Y414008D01*
X176725Y414342D01*
X176892Y414550D01*
X177225Y414633D01*
X177558Y414550D01*
X177767Y414300D01*
X177892Y414008D01*
Y412967D01*
G01Y414008D02*
X179100Y414633D01*
G01Y416800D02*
X176600D01*
X177100Y416300D01*
G01X179100D02*
Y417300D01*
G01X176600Y419800D02*
X176683Y419467D01*
X176892Y419217D01*
X177142Y419050D01*
X177475Y418925D01*
X177850Y418883D01*
X178225Y418925D01*
X178558Y419050D01*
X178808Y419217D01*
X179017Y419467D01*
X179100Y419800D01*
X179017Y420133D01*
X178808Y420383D01*
X178558Y420550D01*
X178225Y420675D01*
X177850Y420717D01*
X177475Y420675D01*
X177142Y420550D01*
X176892Y420383D01*
X176683Y420133D01*
X176600Y419800D01*
G01X202267Y362200D02*
Y359700D01*
X203933D01*
G01X205183Y360200D02*
X205433Y359908D01*
X205767Y359742D01*
X206142Y359700D01*
X206475Y359742D01*
X206808Y359950D01*
X207017Y360200D01*
X207058Y360450D01*
X206975Y360742D01*
X206683Y360950D01*
X206392Y361033D01*
X206017D01*
G01X206392D02*
X206642Y361158D01*
X206850Y361367D01*
X206933Y361617D01*
X206850Y361867D01*
X206642Y362075D01*
X206267Y362200D01*
X205892Y362158D01*
X205517Y361992D01*
G01X208183Y360200D02*
X208433Y359908D01*
X208767Y359742D01*
X209142Y359700D01*
X209475Y359742D01*
X209808Y359950D01*
X210017Y360200D01*
X210058Y360450D01*
X209975Y360742D01*
X209683Y360950D01*
X209392Y361033D01*
X209017D01*
G01X209392D02*
X209642Y361158D01*
X209850Y361367D01*
X209933Y361617D01*
X209850Y361867D01*
X209642Y362075D01*
X209267Y362200D01*
X208892Y362158D01*
X208517Y361992D01*
G01X217300Y345967D02*
X219800D01*
Y347633D01*
G01X219300Y348883D02*
X219592Y349133D01*
X219758Y349467D01*
X219800Y349842D01*
X219758Y350175D01*
X219550Y350508D01*
X219300Y350717D01*
X219050Y350758D01*
X218758Y350675D01*
X218550Y350383D01*
X218467Y350092D01*
Y349717D01*
G01Y350092D02*
X218342Y350342D01*
X218133Y350550D01*
X217883Y350633D01*
X217633Y350550D01*
X217425Y350342D01*
X217300Y349967D01*
X217342Y349592D01*
X217508Y349217D01*
G01X217717Y352008D02*
X217467Y352258D01*
X217342Y352550D01*
X217300Y352883D01*
X217383Y353300D01*
X217592Y353592D01*
X217842Y353675D01*
X218092Y353633D01*
X218300Y353467D01*
X218717Y352633D01*
X219008Y352258D01*
X219425Y352008D01*
X219800Y351925D01*
Y353675D01*
G01X207267Y366500D02*
Y364000D01*
X208933D01*
G01X210183Y364500D02*
X210433Y364208D01*
X210767Y364042D01*
X211142Y364000D01*
X211475Y364042D01*
X211808Y364250D01*
X212017Y364500D01*
X212058Y364750D01*
X211975Y365042D01*
X211683Y365250D01*
X211392Y365333D01*
X211017D01*
G01X211392D02*
X211642Y365458D01*
X211850Y365667D01*
X211933Y365917D01*
X211850Y366167D01*
X211642Y366375D01*
X211267Y366500D01*
X210892Y366458D01*
X210517Y366292D01*
G01X214100Y364000D02*
Y366500D01*
X213600Y366000D01*
G01Y364000D02*
X214600D01*
G01X192767Y358400D02*
Y355900D01*
X194433D01*
G01X196600D02*
Y358400D01*
X196100Y357900D01*
G01Y355900D02*
X197100D01*
G01X198808Y356942D02*
X199100Y357233D01*
X199350Y357400D01*
X199683Y357483D01*
X199975Y357400D01*
X200183Y357233D01*
X200350Y356983D01*
X200392Y356692D01*
X200350Y356442D01*
X200183Y356192D01*
X199933Y355983D01*
X199642Y355900D01*
X199308Y355983D01*
X199017Y356233D01*
X198850Y356608D01*
X198808Y357025D01*
X198892Y357567D01*
X199017Y357858D01*
X199225Y358150D01*
X199517Y358358D01*
X199808Y358400D01*
X200100Y358317D01*
X200308Y358108D01*
G01X181867Y353900D02*
Y351400D01*
X183533D01*
G01X185700D02*
Y353900D01*
X185200Y353400D01*
G01Y351400D02*
X186200D01*
G01X189200D02*
Y353900D01*
X187658Y352108D01*
X189742D01*
G01X168867Y350000D02*
Y347500D01*
X170533D01*
G01X172700D02*
Y350000D01*
X172200Y349500D01*
G01Y347500D02*
X173200D01*
G01X174908Y349583D02*
X175158Y349833D01*
X175450Y349958D01*
X175783Y350000D01*
X176200Y349917D01*
X176492Y349708D01*
X176575Y349458D01*
X176533Y349208D01*
X176367Y349000D01*
X175533Y348583D01*
X175158Y348292D01*
X174908Y347875D01*
X174825Y347500D01*
X176575D01*
G01X195908Y398117D02*
X195783Y397867D01*
X195700Y397575D01*
Y397242D01*
X195825Y396867D01*
X196033Y396575D01*
X196283Y396367D01*
X196700Y396200D01*
X197075Y396158D01*
X197450Y396242D01*
X197700Y396367D01*
X197950Y396617D01*
X198117Y396908D01*
X198200Y397200D01*
Y397492D01*
X198117Y397783D01*
X197992Y398033D01*
X197825Y398242D01*
G01X197158Y399408D02*
X196867Y399700D01*
X196700Y399950D01*
X196617Y400283D01*
X196700Y400575D01*
X196867Y400783D01*
X197117Y400950D01*
X197408Y400992D01*
X197658Y400950D01*
X197908Y400783D01*
X198117Y400533D01*
X198200Y400242D01*
X198117Y399908D01*
X197867Y399617D01*
X197492Y399450D01*
X197075Y399408D01*
X196533Y399492D01*
X196242Y399617D01*
X195950Y399825D01*
X195742Y400117D01*
X195700Y400408D01*
X195783Y400700D01*
X195992Y400908D01*
G01X197700Y402283D02*
X197992Y402533D01*
X198158Y402867D01*
X198200Y403242D01*
X198158Y403575D01*
X197950Y403908D01*
X197700Y404117D01*
X197450Y404158D01*
X197158Y404075D01*
X196950Y403783D01*
X196867Y403492D01*
Y403117D01*
G01Y403492D02*
X196742Y403742D01*
X196533Y403950D01*
X196283Y404033D01*
X196033Y403950D01*
X195825Y403742D01*
X195700Y403367D01*
X195742Y402992D01*
X195908Y402617D01*
G01X204951Y373583D02*
X204826Y373333D01*
X204743Y373041D01*
Y372708D01*
X204868Y372333D01*
X205076Y372041D01*
X205326Y371833D01*
X205743Y371666D01*
X206118Y371624D01*
X206493Y371708D01*
X206743Y371833D01*
X206993Y372083D01*
X207160Y372374D01*
X207243Y372666D01*
Y372958D01*
X207160Y373249D01*
X207035Y373499D01*
X206868Y373708D01*
G01X207243Y375666D02*
X204743D01*
X205243Y375166D01*
G01X207243D02*
Y376166D01*
G01X206868Y377749D02*
X207076Y377999D01*
X207201Y378291D01*
X207243Y378666D01*
X207160Y379041D01*
X206993Y379333D01*
X206701Y379541D01*
X206368Y379583D01*
X206035Y379499D01*
X205826Y379291D01*
X205660Y378999D01*
X205618Y378708D01*
X205660Y378416D01*
X205826Y378041D01*
X204743Y378166D01*
Y379291D01*
G01X207243Y381666D02*
X207201Y381958D01*
X207076Y382291D01*
X206868Y382499D01*
X206576Y382583D01*
X206285Y382499D01*
X206035Y382249D01*
X205910Y381874D01*
Y381458D01*
X205826Y381208D01*
X205618Y380999D01*
X205326Y380916D01*
X205035Y381041D01*
X204826Y381333D01*
X204743Y381666D01*
X204826Y381999D01*
X205035Y382291D01*
X205326Y382416D01*
X205618Y382333D01*
X205826Y382124D01*
X205910Y381874D01*
Y381458D01*
X206035Y381083D01*
X206285Y380833D01*
X206576Y380749D01*
X206868Y380833D01*
X207076Y381041D01*
X207201Y381374D01*
X207243Y381666D01*
G01X193012Y371589D02*
X192887Y371339D01*
X192804Y371047D01*
Y370714D01*
X192929Y370339D01*
X193137Y370047D01*
X193387Y369839D01*
X193804Y369672D01*
X194179Y369630D01*
X194554Y369714D01*
X194804Y369839D01*
X195054Y370089D01*
X195221Y370380D01*
X195304Y370672D01*
Y370964D01*
X195221Y371255D01*
X195096Y371505D01*
X194929Y371714D01*
G01X195304Y373672D02*
X192804D01*
X193304Y373172D01*
G01X195304D02*
Y374172D01*
G01X194929Y375755D02*
X195137Y376005D01*
X195262Y376297D01*
X195304Y376672D01*
X195221Y377047D01*
X195054Y377339D01*
X194762Y377547D01*
X194429Y377589D01*
X194096Y377505D01*
X193887Y377297D01*
X193721Y377005D01*
X193679Y376714D01*
X193721Y376422D01*
X193887Y376047D01*
X192804Y376172D01*
Y377297D01*
G01X194262Y378880D02*
X193971Y379172D01*
X193804Y379422D01*
X193721Y379755D01*
X193804Y380047D01*
X193971Y380255D01*
X194221Y380422D01*
X194512Y380464D01*
X194762Y380422D01*
X195012Y380255D01*
X195221Y380005D01*
X195304Y379714D01*
X195221Y379380D01*
X194971Y379089D01*
X194596Y378922D01*
X194179Y378880D01*
X193637Y378964D01*
X193346Y379089D01*
X193054Y379297D01*
X192846Y379589D01*
X192804Y379880D01*
X192887Y380172D01*
X193096Y380380D01*
G01X186408Y370817D02*
X186283Y370567D01*
X186200Y370275D01*
Y369942D01*
X186325Y369567D01*
X186533Y369275D01*
X186783Y369067D01*
X187200Y368900D01*
X187575Y368858D01*
X187950Y368942D01*
X188200Y369067D01*
X188450Y369317D01*
X188617Y369608D01*
X188700Y369900D01*
Y370192D01*
X188617Y370483D01*
X188492Y370733D01*
X188325Y370942D01*
G01X188700Y372900D02*
X186200D01*
X186700Y372400D01*
G01X188700D02*
Y373400D01*
G01X188325Y374983D02*
X188533Y375233D01*
X188658Y375525D01*
X188700Y375900D01*
X188617Y376275D01*
X188450Y376567D01*
X188158Y376775D01*
X187825Y376817D01*
X187492Y376733D01*
X187283Y376525D01*
X187117Y376233D01*
X187075Y375942D01*
X187117Y375650D01*
X187283Y375275D01*
X186200Y375400D01*
Y376525D01*
G01X188700Y378817D02*
X188158Y378900D01*
X187700Y379025D01*
X187283Y379192D01*
X186825Y379400D01*
X186200Y379733D01*
Y378067D01*
G01X192008Y398017D02*
X191883Y397767D01*
X191800Y397475D01*
Y397142D01*
X191925Y396767D01*
X192133Y396475D01*
X192383Y396267D01*
X192800Y396100D01*
X193175Y396058D01*
X193550Y396142D01*
X193800Y396267D01*
X194050Y396517D01*
X194217Y396808D01*
X194300Y397100D01*
Y397392D01*
X194217Y397683D01*
X194092Y397933D01*
X193925Y398142D01*
G01X193258Y399308D02*
X192967Y399600D01*
X192800Y399850D01*
X192717Y400183D01*
X192800Y400475D01*
X192967Y400683D01*
X193217Y400850D01*
X193508Y400892D01*
X193758Y400850D01*
X194008Y400683D01*
X194217Y400433D01*
X194300Y400142D01*
X194217Y399808D01*
X193967Y399517D01*
X193592Y399350D01*
X193175Y399308D01*
X192633Y399392D01*
X192342Y399517D01*
X192050Y399725D01*
X191842Y400017D01*
X191800Y400308D01*
X191883Y400600D01*
X192092Y400808D01*
G01X192217Y402308D02*
X191967Y402558D01*
X191842Y402850D01*
X191800Y403183D01*
X191883Y403600D01*
X192092Y403892D01*
X192342Y403975D01*
X192592Y403933D01*
X192800Y403767D01*
X193217Y402933D01*
X193508Y402558D01*
X193925Y402308D01*
X194300Y402225D01*
Y403975D01*
G01X209967Y377800D02*
Y375300D01*
X211633D01*
G01X213008Y376342D02*
X213300Y376633D01*
X213550Y376800D01*
X213883Y376883D01*
X214175Y376800D01*
X214383Y376633D01*
X214550Y376383D01*
X214592Y376092D01*
X214550Y375842D01*
X214383Y375592D01*
X214133Y375383D01*
X213842Y375300D01*
X213508Y375383D01*
X213217Y375633D01*
X213050Y376008D01*
X213008Y376425D01*
X213092Y376967D01*
X213217Y377258D01*
X213425Y377550D01*
X213717Y377758D01*
X214008Y377800D01*
X214300Y377717D01*
X214508Y377508D01*
G01X217300Y375300D02*
Y377800D01*
X215758Y376008D01*
X217842D01*
G01X181300Y465200D02*
Y492000D01*
X178100D01*
Y504600D01*
X189400D01*
Y496000D01*
X195100D01*
Y492800D01*
G01X208367Y430900D02*
Y433400D01*
X209408D01*
X209742Y433275D01*
X209950Y433108D01*
X210033Y432775D01*
X209950Y432442D01*
X209700Y432233D01*
X209408Y432108D01*
X208367D01*
G01X209408D02*
X210033Y430900D01*
G01X211283Y431400D02*
X211533Y431108D01*
X211867Y430942D01*
X212242Y430900D01*
X212575Y430942D01*
X212908Y431150D01*
X213117Y431400D01*
X213158Y431650D01*
X213075Y431942D01*
X212783Y432150D01*
X212492Y432233D01*
X212117D01*
G01X212492D02*
X212742Y432358D01*
X212950Y432567D01*
X213033Y432817D01*
X212950Y433067D01*
X212742Y433275D01*
X212367Y433400D01*
X211992Y433358D01*
X211617Y433192D01*
G01X214283Y431400D02*
X214533Y431108D01*
X214867Y430942D01*
X215242Y430900D01*
X215575Y430942D01*
X215908Y431150D01*
X216117Y431400D01*
X216158Y431650D01*
X216075Y431942D01*
X215783Y432150D01*
X215492Y432233D01*
X215117D01*
G01X215492D02*
X215742Y432358D01*
X215950Y432567D01*
X216033Y432817D01*
X215950Y433067D01*
X215742Y433275D01*
X215367Y433400D01*
X214992Y433358D01*
X214617Y433192D01*
G01X185627Y427071D02*
X185377Y427196D01*
X185085Y427279D01*
X184752D01*
X184377Y427154D01*
X184085Y426946D01*
X183877Y426696D01*
X183710Y426279D01*
X183668Y425904D01*
X183752Y425529D01*
X183877Y425279D01*
X184127Y425029D01*
X184418Y424862D01*
X184710Y424779D01*
X185002D01*
X185293Y424862D01*
X185543Y424987D01*
X185752Y425154D01*
G01X186793D02*
X187043Y424946D01*
X187335Y424821D01*
X187710Y424779D01*
X188085Y424862D01*
X188377Y425029D01*
X188585Y425321D01*
X188627Y425654D01*
X188543Y425987D01*
X188335Y426196D01*
X188043Y426362D01*
X187752Y426404D01*
X187460Y426362D01*
X187085Y426196D01*
X187210Y427279D01*
X188335D01*
G01X190710Y424779D02*
X191002Y424821D01*
X191335Y424946D01*
X191543Y425154D01*
X191627Y425446D01*
X191543Y425737D01*
X191293Y425987D01*
X190918Y426112D01*
X190502D01*
X190252Y426196D01*
X190043Y426404D01*
X189960Y426696D01*
X190085Y426987D01*
X190377Y427196D01*
X190710Y427279D01*
X191043Y427196D01*
X191335Y426987D01*
X191460Y426696D01*
X191377Y426404D01*
X191168Y426196D01*
X190918Y426112D01*
X190502D01*
X190127Y425987D01*
X189877Y425737D01*
X189793Y425446D01*
X189877Y425154D01*
X190085Y424946D01*
X190418Y424821D01*
X190710Y424779D01*
G01X218467Y453400D02*
Y455900D01*
X219508D01*
X219842Y455775D01*
X220050Y455608D01*
X220133Y455275D01*
X220050Y454942D01*
X219800Y454733D01*
X219508Y454608D01*
X218467D01*
G01X219508D02*
X220133Y453400D01*
G01X221508Y455483D02*
X221758Y455733D01*
X222050Y455858D01*
X222383Y455900D01*
X222800Y455817D01*
X223092Y455608D01*
X223175Y455358D01*
X223133Y455108D01*
X222967Y454900D01*
X222133Y454483D01*
X221758Y454192D01*
X221508Y453775D01*
X221425Y453400D01*
X223175D01*
G01X224383Y453775D02*
X224633Y453567D01*
X224925Y453442D01*
X225300Y453400D01*
X225675Y453483D01*
X225967Y453650D01*
X226175Y453942D01*
X226217Y454275D01*
X226133Y454608D01*
X225925Y454817D01*
X225633Y454983D01*
X225342Y455025D01*
X225050Y454983D01*
X224675Y454817D01*
X224800Y455900D01*
X225925D01*
G01X195142Y433261D02*
X195017Y433011D01*
X194934Y432719D01*
Y432386D01*
X195059Y432011D01*
X195267Y431719D01*
X195517Y431511D01*
X195934Y431344D01*
X196309Y431302D01*
X196684Y431386D01*
X196934Y431511D01*
X197184Y431761D01*
X197351Y432052D01*
X197434Y432344D01*
Y432636D01*
X197351Y432927D01*
X197226Y433177D01*
X197059Y433386D01*
G01X196392Y434552D02*
X196101Y434844D01*
X195934Y435094D01*
X195851Y435427D01*
X195934Y435719D01*
X196101Y435927D01*
X196351Y436094D01*
X196642Y436136D01*
X196892Y436094D01*
X197142Y435927D01*
X197351Y435677D01*
X197434Y435386D01*
X197351Y435052D01*
X197101Y434761D01*
X196726Y434594D01*
X196309Y434552D01*
X195767Y434636D01*
X195476Y434761D01*
X195184Y434969D01*
X194976Y435261D01*
X194934Y435552D01*
X195017Y435844D01*
X195226Y436052D01*
G01X194934Y438344D02*
X195017Y438011D01*
X195226Y437761D01*
X195476Y437594D01*
X195809Y437469D01*
X196184Y437427D01*
X196559Y437469D01*
X196892Y437594D01*
X197142Y437761D01*
X197351Y438011D01*
X197434Y438344D01*
X197351Y438677D01*
X197142Y438927D01*
X196892Y439094D01*
X196559Y439219D01*
X196184Y439261D01*
X195809Y439219D01*
X195476Y439094D01*
X195226Y438927D01*
X195017Y438677D01*
X194934Y438344D01*
G01X204539Y432874D02*
X204414Y432624D01*
X204331Y432332D01*
Y431999D01*
X204456Y431624D01*
X204664Y431332D01*
X204914Y431124D01*
X205331Y430957D01*
X205706Y430915D01*
X206081Y430999D01*
X206331Y431124D01*
X206581Y431374D01*
X206748Y431665D01*
X206831Y431957D01*
Y432249D01*
X206748Y432540D01*
X206623Y432790D01*
X206456Y432999D01*
G01Y434040D02*
X206664Y434290D01*
X206789Y434582D01*
X206831Y434957D01*
X206748Y435332D01*
X206581Y435624D01*
X206289Y435832D01*
X205956Y435874D01*
X205623Y435790D01*
X205414Y435582D01*
X205248Y435290D01*
X205206Y434999D01*
X205248Y434707D01*
X205414Y434332D01*
X204331Y434457D01*
Y435582D01*
G01X206539Y437249D02*
X206748Y437540D01*
X206831Y437874D01*
X206748Y438207D01*
X206498Y438499D01*
X206123Y438707D01*
X205748Y438790D01*
X205289D01*
X204914Y438707D01*
X204581Y438499D01*
X204414Y438249D01*
X204331Y437957D01*
X204414Y437624D01*
X204581Y437374D01*
X204831Y437207D01*
X205164Y437124D01*
X205456Y437207D01*
X205748Y437415D01*
X205914Y437665D01*
X205956Y437957D01*
X205873Y438290D01*
X205664Y438540D01*
X205289Y438790D01*
G01X208300Y435067D02*
X210800D01*
Y436733D01*
G01Y439733D02*
Y438067D01*
X208300D01*
Y439733D01*
G01X209508Y439067D02*
Y438067D01*
G01X210800Y440983D02*
X208300D01*
Y441817D01*
X208425Y442150D01*
X208592Y442400D01*
X208842Y442608D01*
X209133Y442775D01*
X209550Y442817D01*
X209967Y442775D01*
X210258Y442608D01*
X210508Y442400D01*
X210675Y442150D01*
X210800Y441817D01*
Y440983D01*
G01X210300Y443983D02*
X210592Y444233D01*
X210758Y444567D01*
X210800Y444942D01*
X210758Y445275D01*
X210550Y445608D01*
X210300Y445817D01*
X210050Y445858D01*
X209758Y445775D01*
X209550Y445483D01*
X209467Y445192D01*
Y444817D01*
G01Y445192D02*
X209342Y445442D01*
X209133Y445650D01*
X208883Y445733D01*
X208633Y445650D01*
X208425Y445442D01*
X208300Y445067D01*
X208342Y444692D01*
X208508Y444317D01*
G01X177302Y447964D02*
X179802D01*
G01X177302Y447006D02*
Y448922D01*
G01X179802Y450131D02*
X177302D01*
Y451131D01*
X177427Y451464D01*
X177719Y451714D01*
X178052Y451797D01*
X178385Y451714D01*
X178635Y451506D01*
X178760Y451131D01*
Y450131D01*
G01X179302Y453047D02*
X179594Y453297D01*
X179760Y453631D01*
X179802Y454006D01*
X179760Y454339D01*
X179552Y454672D01*
X179302Y454881D01*
X179052Y454922D01*
X178760Y454839D01*
X178552Y454547D01*
X178469Y454256D01*
Y453881D01*
G01Y454256D02*
X178344Y454506D01*
X178135Y454714D01*
X177885Y454797D01*
X177635Y454714D01*
X177427Y454506D01*
X177302Y454131D01*
X177344Y453756D01*
X177510Y453381D01*
G01X177302Y456964D02*
X177385Y456631D01*
X177594Y456381D01*
X177844Y456214D01*
X178177Y456089D01*
X178552Y456047D01*
X178927Y456089D01*
X179260Y456214D01*
X179510Y456381D01*
X179719Y456631D01*
X179802Y456964D01*
X179719Y457297D01*
X179510Y457547D01*
X179260Y457714D01*
X178927Y457839D01*
X178552Y457881D01*
X178177Y457839D01*
X177844Y457714D01*
X177594Y457547D01*
X177385Y457297D01*
X177302Y456964D01*
G01X181200Y439200D02*
X183700D01*
G01X181200Y438242D02*
Y440158D01*
G01X183700Y441367D02*
X181200D01*
Y442367D01*
X181325Y442700D01*
X181617Y442950D01*
X181950Y443033D01*
X182283Y442950D01*
X182533Y442742D01*
X182658Y442367D01*
Y441367D01*
G01X183200Y444283D02*
X183492Y444533D01*
X183658Y444867D01*
X183700Y445242D01*
X183658Y445575D01*
X183450Y445908D01*
X183200Y446117D01*
X182950Y446158D01*
X182658Y446075D01*
X182450Y445783D01*
X182367Y445492D01*
Y445117D01*
G01Y445492D02*
X182242Y445742D01*
X182033Y445950D01*
X181783Y446033D01*
X181533Y445950D01*
X181325Y445742D01*
X181200Y445367D01*
X181242Y444992D01*
X181408Y444617D01*
G01X183700Y448700D02*
X181200D01*
X182992Y447158D01*
Y449242D01*
G01X180300Y426800D02*
X182800D01*
G01X180300Y425842D02*
Y427758D01*
G01X182800Y428967D02*
X180300D01*
Y429967D01*
X180425Y430300D01*
X180717Y430550D01*
X181050Y430633D01*
X181383Y430550D01*
X181633Y430342D01*
X181758Y429967D01*
Y428967D01*
G01X182300Y431883D02*
X182592Y432133D01*
X182758Y432467D01*
X182800Y432842D01*
X182758Y433175D01*
X182550Y433508D01*
X182300Y433717D01*
X182050Y433758D01*
X181758Y433675D01*
X181550Y433383D01*
X181467Y433092D01*
Y432717D01*
G01Y433092D02*
X181342Y433342D01*
X181133Y433550D01*
X180883Y433633D01*
X180633Y433550D01*
X180425Y433342D01*
X180300Y432967D01*
X180342Y432592D01*
X180508Y432217D01*
G01X181758Y435008D02*
X181467Y435300D01*
X181300Y435550D01*
X181217Y435883D01*
X181300Y436175D01*
X181467Y436383D01*
X181717Y436550D01*
X182008Y436592D01*
X182258Y436550D01*
X182508Y436383D01*
X182717Y436133D01*
X182800Y435842D01*
X182717Y435508D01*
X182467Y435217D01*
X182092Y435050D01*
X181675Y435008D01*
X181133Y435092D01*
X180842Y435217D01*
X180550Y435425D01*
X180342Y435717D01*
X180300Y436008D01*
X180383Y436300D01*
X180592Y436508D01*
G01X189100Y438000D02*
X191600D01*
G01X189100Y437042D02*
Y438958D01*
G01X191600Y440167D02*
X189100D01*
Y441167D01*
X189225Y441500D01*
X189517Y441750D01*
X189850Y441833D01*
X190183Y441750D01*
X190433Y441542D01*
X190558Y441167D01*
Y440167D01*
G01X191100Y443083D02*
X191392Y443333D01*
X191558Y443667D01*
X191600Y444042D01*
X191558Y444375D01*
X191350Y444708D01*
X191100Y444917D01*
X190850Y444958D01*
X190558Y444875D01*
X190350Y444583D01*
X190267Y444292D01*
Y443917D01*
G01Y444292D02*
X190142Y444542D01*
X189933Y444750D01*
X189683Y444833D01*
X189433Y444750D01*
X189225Y444542D01*
X189100Y444167D01*
X189142Y443792D01*
X189308Y443417D01*
G01X191600Y447000D02*
X191558Y447292D01*
X191433Y447625D01*
X191225Y447833D01*
X190933Y447917D01*
X190642Y447833D01*
X190392Y447583D01*
X190267Y447208D01*
Y446792D01*
X190183Y446542D01*
X189975Y446333D01*
X189683Y446250D01*
X189392Y446375D01*
X189183Y446667D01*
X189100Y447000D01*
X189183Y447333D01*
X189392Y447625D01*
X189683Y447750D01*
X189975Y447667D01*
X190183Y447458D01*
X190267Y447208D01*
Y446792D01*
X190392Y446417D01*
X190642Y446167D01*
X190933Y446083D01*
X191225Y446167D01*
X191433Y446375D01*
X191558Y446708D01*
X191600Y447000D01*
G01X202200Y455500D02*
Y453000D01*
G01X201242Y455500D02*
X203158D01*
G01X204367Y453000D02*
Y455500D01*
X205367D01*
X205700Y455375D01*
X205950Y455083D01*
X206033Y454750D01*
X205950Y454417D01*
X205742Y454167D01*
X205367Y454042D01*
X204367D01*
G01X207408D02*
X207700Y454333D01*
X207950Y454500D01*
X208283Y454583D01*
X208575Y454500D01*
X208783Y454333D01*
X208950Y454083D01*
X208992Y453792D01*
X208950Y453542D01*
X208783Y453292D01*
X208533Y453083D01*
X208242Y453000D01*
X207908Y453083D01*
X207617Y453333D01*
X207450Y453708D01*
X207408Y454125D01*
X207492Y454667D01*
X207617Y454958D01*
X207825Y455250D01*
X208117Y455458D01*
X208408Y455500D01*
X208700Y455417D01*
X208908Y455208D01*
G01X211700Y453000D02*
Y455500D01*
X210158Y453708D01*
X212242D01*
G01X199200Y435000D02*
X201700D01*
G01X199200Y434042D02*
Y435958D01*
G01X201700Y437167D02*
X199200D01*
Y438167D01*
X199325Y438500D01*
X199617Y438750D01*
X199950Y438833D01*
X200283Y438750D01*
X200533Y438542D01*
X200658Y438167D01*
Y437167D01*
G01Y440208D02*
X200367Y440500D01*
X200200Y440750D01*
X200117Y441083D01*
X200200Y441375D01*
X200367Y441583D01*
X200617Y441750D01*
X200908Y441792D01*
X201158Y441750D01*
X201408Y441583D01*
X201617Y441333D01*
X201700Y441042D01*
X201617Y440708D01*
X201367Y440417D01*
X200992Y440250D01*
X200575Y440208D01*
X200033Y440292D01*
X199742Y440417D01*
X199450Y440625D01*
X199242Y440917D01*
X199200Y441208D01*
X199283Y441500D01*
X199492Y441708D01*
G01X200658Y443208D02*
X200367Y443500D01*
X200200Y443750D01*
X200117Y444083D01*
X200200Y444375D01*
X200367Y444583D01*
X200617Y444750D01*
X200908Y444792D01*
X201158Y444750D01*
X201408Y444583D01*
X201617Y444333D01*
X201700Y444042D01*
X201617Y443708D01*
X201367Y443417D01*
X200992Y443250D01*
X200575Y443208D01*
X200033Y443292D01*
X199742Y443417D01*
X199450Y443625D01*
X199242Y443917D01*
X199200Y444208D01*
X199283Y444500D01*
X199492Y444708D01*
G01X176716Y434265D02*
X179216D01*
G01X176716Y433307D02*
Y435223D01*
G01X179216Y436432D02*
X176716D01*
Y437432D01*
X176841Y437765D01*
X177133Y438015D01*
X177466Y438098D01*
X177799Y438015D01*
X178049Y437807D01*
X178174Y437432D01*
Y436432D01*
G01Y439473D02*
X177883Y439765D01*
X177716Y440015D01*
X177633Y440348D01*
X177716Y440640D01*
X177883Y440848D01*
X178133Y441015D01*
X178424Y441057D01*
X178674Y441015D01*
X178924Y440848D01*
X179133Y440598D01*
X179216Y440307D01*
X179133Y439973D01*
X178883Y439682D01*
X178508Y439515D01*
X178091Y439473D01*
X177549Y439557D01*
X177258Y439682D01*
X176966Y439890D01*
X176758Y440182D01*
X176716Y440473D01*
X176799Y440765D01*
X177008Y440973D01*
G01X179216Y443182D02*
X178674Y443265D01*
X178216Y443390D01*
X177799Y443557D01*
X177341Y443765D01*
X176716Y444098D01*
Y442432D01*
G01X213071Y534471D02*
X212946Y534221D01*
X212863Y533929D01*
Y533596D01*
X212988Y533221D01*
X213196Y532929D01*
X213446Y532721D01*
X213863Y532554D01*
X214238Y532512D01*
X214613Y532596D01*
X214863Y532721D01*
X215113Y532971D01*
X215280Y533262D01*
X215363Y533554D01*
Y533846D01*
X215280Y534137D01*
X215155Y534387D01*
X214988Y534596D01*
G01X213280Y535762D02*
X213030Y536012D01*
X212905Y536304D01*
X212863Y536637D01*
X212946Y537054D01*
X213155Y537346D01*
X213405Y537429D01*
X213655Y537387D01*
X213863Y537221D01*
X214280Y536387D01*
X214571Y536012D01*
X214988Y535762D01*
X215363Y535679D01*
Y537429D01*
G01Y539554D02*
X215321Y539846D01*
X215196Y540179D01*
X214988Y540387D01*
X214696Y540471D01*
X214405Y540387D01*
X214155Y540137D01*
X214030Y539762D01*
Y539346D01*
X213946Y539096D01*
X213738Y538887D01*
X213446Y538804D01*
X213155Y538929D01*
X212946Y539221D01*
X212863Y539554D01*
X212946Y539887D01*
X213155Y540179D01*
X213446Y540304D01*
X213738Y540221D01*
X213946Y540012D01*
X214030Y539762D01*
Y539346D01*
X214155Y538971D01*
X214405Y538721D01*
X214696Y538637D01*
X214988Y538721D01*
X215196Y538929D01*
X215321Y539262D01*
X215363Y539554D01*
G01X209662Y534309D02*
X209537Y534059D01*
X209454Y533767D01*
Y533434D01*
X209579Y533059D01*
X209787Y532767D01*
X210037Y532559D01*
X210454Y532392D01*
X210829Y532350D01*
X211204Y532434D01*
X211454Y532559D01*
X211704Y532809D01*
X211871Y533100D01*
X211954Y533392D01*
Y533684D01*
X211871Y533975D01*
X211746Y534225D01*
X211579Y534434D01*
G01X209871Y535600D02*
X209621Y535850D01*
X209496Y536142D01*
X209454Y536475D01*
X209537Y536892D01*
X209746Y537184D01*
X209996Y537267D01*
X210246Y537225D01*
X210454Y537059D01*
X210871Y536225D01*
X211162Y535850D01*
X211579Y535600D01*
X211954Y535517D01*
Y537267D01*
G01X211662Y538684D02*
X211871Y538975D01*
X211954Y539309D01*
X211871Y539642D01*
X211621Y539934D01*
X211246Y540142D01*
X210871Y540225D01*
X210412D01*
X210037Y540142D01*
X209704Y539934D01*
X209537Y539684D01*
X209454Y539392D01*
X209537Y539059D01*
X209704Y538809D01*
X209954Y538642D01*
X210287Y538559D01*
X210579Y538642D01*
X210871Y538850D01*
X211037Y539100D01*
X211079Y539392D01*
X210996Y539725D01*
X210787Y539975D01*
X210412Y540225D01*
G01X202379Y530120D02*
X202254Y529870D01*
X202171Y529578D01*
Y529245D01*
X202296Y528870D01*
X202504Y528578D01*
X202754Y528370D01*
X203171Y528203D01*
X203546Y528161D01*
X203921Y528245D01*
X204171Y528370D01*
X204421Y528620D01*
X204588Y528911D01*
X204671Y529203D01*
Y529495D01*
X204588Y529786D01*
X204463Y530036D01*
X204296Y530245D01*
G01X204171Y531286D02*
X204463Y531536D01*
X204629Y531870D01*
X204671Y532245D01*
X204629Y532578D01*
X204421Y532911D01*
X204171Y533120D01*
X203921Y533161D01*
X203629Y533078D01*
X203421Y532786D01*
X203338Y532495D01*
Y532120D01*
G01Y532495D02*
X203213Y532745D01*
X203004Y532953D01*
X202754Y533036D01*
X202504Y532953D01*
X202296Y532745D01*
X202171Y532370D01*
X202213Y531995D01*
X202379Y531620D01*
G01X202171Y535203D02*
X202254Y534870D01*
X202463Y534620D01*
X202713Y534453D01*
X203046Y534328D01*
X203421Y534286D01*
X203796Y534328D01*
X204129Y534453D01*
X204379Y534620D01*
X204588Y534870D01*
X204671Y535203D01*
X204588Y535536D01*
X204379Y535786D01*
X204129Y535953D01*
X203796Y536078D01*
X203421Y536120D01*
X203046Y536078D01*
X202713Y535953D01*
X202463Y535786D01*
X202254Y535536D01*
X202171Y535203D01*
G01X198158Y530445D02*
X198033Y530195D01*
X197950Y529903D01*
Y529570D01*
X198075Y529195D01*
X198283Y528903D01*
X198533Y528695D01*
X198950Y528528D01*
X199325Y528486D01*
X199700Y528570D01*
X199950Y528695D01*
X200200Y528945D01*
X200367Y529236D01*
X200450Y529528D01*
Y529820D01*
X200367Y530111D01*
X200242Y530361D01*
X200075Y530570D01*
G01X199950Y531611D02*
X200242Y531861D01*
X200408Y532195D01*
X200450Y532570D01*
X200408Y532903D01*
X200200Y533236D01*
X199950Y533445D01*
X199700Y533486D01*
X199408Y533403D01*
X199200Y533111D01*
X199117Y532820D01*
Y532445D01*
G01Y532820D02*
X198992Y533070D01*
X198783Y533278D01*
X198533Y533361D01*
X198283Y533278D01*
X198075Y533070D01*
X197950Y532695D01*
X197992Y532320D01*
X198158Y531945D01*
G01X200450Y535528D02*
X197950D01*
X198450Y535028D01*
G01X200450D02*
Y536028D01*
G01X190914Y534314D02*
X190789Y534064D01*
X190706Y533772D01*
Y533439D01*
X190831Y533064D01*
X191039Y532772D01*
X191289Y532564D01*
X191706Y532397D01*
X192081Y532355D01*
X192456Y532439D01*
X192706Y532564D01*
X192956Y532814D01*
X193123Y533105D01*
X193206Y533397D01*
Y533689D01*
X193123Y533980D01*
X192998Y534230D01*
X192831Y534439D01*
G01X192706Y535480D02*
X192998Y535730D01*
X193164Y536064D01*
X193206Y536439D01*
X193164Y536772D01*
X192956Y537105D01*
X192706Y537314D01*
X192456Y537355D01*
X192164Y537272D01*
X191956Y536980D01*
X191873Y536689D01*
Y536314D01*
G01Y536689D02*
X191748Y536939D01*
X191539Y537147D01*
X191289Y537230D01*
X191039Y537147D01*
X190831Y536939D01*
X190706Y536564D01*
X190748Y536189D01*
X190914Y535814D01*
G01X191123Y538605D02*
X190873Y538855D01*
X190748Y539147D01*
X190706Y539480D01*
X190789Y539897D01*
X190998Y540189D01*
X191248Y540272D01*
X191498Y540230D01*
X191706Y540064D01*
X192123Y539230D01*
X192414Y538855D01*
X192831Y538605D01*
X193206Y538522D01*
Y540272D01*
G01X186840Y534379D02*
X186715Y534129D01*
X186632Y533837D01*
Y533504D01*
X186757Y533129D01*
X186965Y532837D01*
X187215Y532629D01*
X187632Y532462D01*
X188007Y532420D01*
X188382Y532504D01*
X188632Y532629D01*
X188882Y532879D01*
X189049Y533170D01*
X189132Y533462D01*
Y533754D01*
X189049Y534045D01*
X188924Y534295D01*
X188757Y534504D01*
G01X188632Y535545D02*
X188924Y535795D01*
X189090Y536129D01*
X189132Y536504D01*
X189090Y536837D01*
X188882Y537170D01*
X188632Y537379D01*
X188382Y537420D01*
X188090Y537337D01*
X187882Y537045D01*
X187799Y536754D01*
Y536379D01*
G01Y536754D02*
X187674Y537004D01*
X187465Y537212D01*
X187215Y537295D01*
X186965Y537212D01*
X186757Y537004D01*
X186632Y536629D01*
X186674Y536254D01*
X186840Y535879D01*
G01X188632Y538545D02*
X188924Y538795D01*
X189090Y539129D01*
X189132Y539504D01*
X189090Y539837D01*
X188882Y540170D01*
X188632Y540379D01*
X188382Y540420D01*
X188090Y540337D01*
X187882Y540045D01*
X187799Y539754D01*
Y539379D01*
G01Y539754D02*
X187674Y540004D01*
X187465Y540212D01*
X187215Y540295D01*
X186965Y540212D01*
X186757Y540004D01*
X186632Y539629D01*
X186674Y539254D01*
X186840Y538879D01*
G01X180098Y530462D02*
X179973Y530212D01*
X179890Y529920D01*
Y529587D01*
X180015Y529212D01*
X180223Y528920D01*
X180473Y528712D01*
X180890Y528545D01*
X181265Y528503D01*
X181640Y528587D01*
X181890Y528712D01*
X182140Y528962D01*
X182307Y529253D01*
X182390Y529545D01*
Y529837D01*
X182307Y530128D01*
X182182Y530378D01*
X182015Y530587D01*
G01X181890Y531628D02*
X182182Y531878D01*
X182348Y532212D01*
X182390Y532587D01*
X182348Y532920D01*
X182140Y533253D01*
X181890Y533462D01*
X181640Y533503D01*
X181348Y533420D01*
X181140Y533128D01*
X181057Y532837D01*
Y532462D01*
G01Y532837D02*
X180932Y533087D01*
X180723Y533295D01*
X180473Y533378D01*
X180223Y533295D01*
X180015Y533087D01*
X179890Y532712D01*
X179932Y532337D01*
X180098Y531962D01*
G01X182390Y536045D02*
X179890D01*
X181682Y534503D01*
Y536587D01*
G01X175957Y530462D02*
X175832Y530212D01*
X175749Y529920D01*
Y529587D01*
X175874Y529212D01*
X176082Y528920D01*
X176332Y528712D01*
X176749Y528545D01*
X177124Y528503D01*
X177499Y528587D01*
X177749Y528712D01*
X177999Y528962D01*
X178166Y529253D01*
X178249Y529545D01*
Y529837D01*
X178166Y530128D01*
X178041Y530378D01*
X177874Y530587D01*
G01X177749Y531628D02*
X178041Y531878D01*
X178207Y532212D01*
X178249Y532587D01*
X178207Y532920D01*
X177999Y533253D01*
X177749Y533462D01*
X177499Y533503D01*
X177207Y533420D01*
X176999Y533128D01*
X176916Y532837D01*
Y532462D01*
G01Y532837D02*
X176791Y533087D01*
X176582Y533295D01*
X176332Y533378D01*
X176082Y533295D01*
X175874Y533087D01*
X175749Y532712D01*
X175791Y532337D01*
X175957Y531962D01*
G01X177874Y534628D02*
X178082Y534878D01*
X178207Y535170D01*
X178249Y535545D01*
X178166Y535920D01*
X177999Y536212D01*
X177707Y536420D01*
X177374Y536462D01*
X177041Y536378D01*
X176832Y536170D01*
X176666Y535878D01*
X176624Y535587D01*
X176666Y535295D01*
X176832Y534920D01*
X175749Y535045D01*
Y536170D01*
G01X169263Y534338D02*
X169138Y534088D01*
X169055Y533796D01*
Y533463D01*
X169180Y533088D01*
X169388Y532796D01*
X169638Y532588D01*
X170055Y532421D01*
X170430Y532379D01*
X170805Y532463D01*
X171055Y532588D01*
X171305Y532838D01*
X171472Y533129D01*
X171555Y533421D01*
Y533713D01*
X171472Y534004D01*
X171347Y534254D01*
X171180Y534463D01*
G01X171055Y535504D02*
X171347Y535754D01*
X171513Y536088D01*
X171555Y536463D01*
X171513Y536796D01*
X171305Y537129D01*
X171055Y537338D01*
X170805Y537379D01*
X170513Y537296D01*
X170305Y537004D01*
X170222Y536713D01*
Y536338D01*
G01Y536713D02*
X170097Y536963D01*
X169888Y537171D01*
X169638Y537254D01*
X169388Y537171D01*
X169180Y536963D01*
X169055Y536588D01*
X169097Y536213D01*
X169263Y535838D01*
G01X170513Y538629D02*
X170222Y538921D01*
X170055Y539171D01*
X169972Y539504D01*
X170055Y539796D01*
X170222Y540004D01*
X170472Y540171D01*
X170763Y540213D01*
X171013Y540171D01*
X171263Y540004D01*
X171472Y539754D01*
X171555Y539463D01*
X171472Y539129D01*
X171222Y538838D01*
X170847Y538671D01*
X170430Y538629D01*
X169888Y538713D01*
X169597Y538838D01*
X169305Y539046D01*
X169097Y539338D01*
X169055Y539629D01*
X169138Y539921D01*
X169347Y540129D01*
G01X164879Y534338D02*
X164754Y534088D01*
X164671Y533796D01*
Y533463D01*
X164796Y533088D01*
X165004Y532796D01*
X165254Y532588D01*
X165671Y532421D01*
X166046Y532379D01*
X166421Y532463D01*
X166671Y532588D01*
X166921Y532838D01*
X167088Y533129D01*
X167171Y533421D01*
Y533713D01*
X167088Y534004D01*
X166963Y534254D01*
X166796Y534463D01*
G01X166671Y535504D02*
X166963Y535754D01*
X167129Y536088D01*
X167171Y536463D01*
X167129Y536796D01*
X166921Y537129D01*
X166671Y537338D01*
X166421Y537379D01*
X166129Y537296D01*
X165921Y537004D01*
X165838Y536713D01*
Y536338D01*
G01Y536713D02*
X165713Y536963D01*
X165504Y537171D01*
X165254Y537254D01*
X165004Y537171D01*
X164796Y536963D01*
X164671Y536588D01*
X164713Y536213D01*
X164879Y535838D01*
G01X167171Y539338D02*
X166629Y539421D01*
X166171Y539546D01*
X165754Y539713D01*
X165296Y539921D01*
X164671Y540254D01*
Y538588D01*
G01X158303Y530083D02*
X158178Y529833D01*
X158095Y529541D01*
Y529208D01*
X158220Y528833D01*
X158428Y528541D01*
X158678Y528333D01*
X159095Y528166D01*
X159470Y528124D01*
X159845Y528208D01*
X160095Y528333D01*
X160345Y528583D01*
X160512Y528874D01*
X160595Y529166D01*
Y529458D01*
X160512Y529749D01*
X160387Y529999D01*
X160220Y530208D01*
G01X160095Y531249D02*
X160387Y531499D01*
X160553Y531833D01*
X160595Y532208D01*
X160553Y532541D01*
X160345Y532874D01*
X160095Y533083D01*
X159845Y533124D01*
X159553Y533041D01*
X159345Y532749D01*
X159262Y532458D01*
Y532083D01*
G01Y532458D02*
X159137Y532708D01*
X158928Y532916D01*
X158678Y532999D01*
X158428Y532916D01*
X158220Y532708D01*
X158095Y532333D01*
X158137Y531958D01*
X158303Y531583D01*
G01X160595Y535166D02*
X160553Y535458D01*
X160428Y535791D01*
X160220Y535999D01*
X159928Y536083D01*
X159637Y535999D01*
X159387Y535749D01*
X159262Y535374D01*
Y534958D01*
X159178Y534708D01*
X158970Y534499D01*
X158678Y534416D01*
X158387Y534541D01*
X158178Y534833D01*
X158095Y535166D01*
X158178Y535499D01*
X158387Y535791D01*
X158678Y535916D01*
X158970Y535833D01*
X159178Y535624D01*
X159262Y535374D01*
Y534958D01*
X159387Y534583D01*
X159637Y534333D01*
X159928Y534249D01*
X160220Y534333D01*
X160428Y534541D01*
X160553Y534874D01*
X160595Y535166D01*
G01X154163Y530245D02*
X154038Y529995D01*
X153955Y529703D01*
Y529370D01*
X154080Y528995D01*
X154288Y528703D01*
X154538Y528495D01*
X154955Y528328D01*
X155330Y528286D01*
X155705Y528370D01*
X155955Y528495D01*
X156205Y528745D01*
X156372Y529036D01*
X156455Y529328D01*
Y529620D01*
X156372Y529911D01*
X156247Y530161D01*
X156080Y530370D01*
G01X155955Y531411D02*
X156247Y531661D01*
X156413Y531995D01*
X156455Y532370D01*
X156413Y532703D01*
X156205Y533036D01*
X155955Y533245D01*
X155705Y533286D01*
X155413Y533203D01*
X155205Y532911D01*
X155122Y532620D01*
Y532245D01*
G01Y532620D02*
X154997Y532870D01*
X154788Y533078D01*
X154538Y533161D01*
X154288Y533078D01*
X154080Y532870D01*
X153955Y532495D01*
X153997Y532120D01*
X154163Y531745D01*
G01X156163Y534620D02*
X156372Y534911D01*
X156455Y535245D01*
X156372Y535578D01*
X156122Y535870D01*
X155747Y536078D01*
X155372Y536161D01*
X154913D01*
X154538Y536078D01*
X154205Y535870D01*
X154038Y535620D01*
X153955Y535328D01*
X154038Y534995D01*
X154205Y534745D01*
X154455Y534578D01*
X154788Y534495D01*
X155080Y534578D01*
X155372Y534786D01*
X155538Y535036D01*
X155580Y535328D01*
X155497Y535661D01*
X155288Y535911D01*
X154913Y536161D01*
G01X181167Y511200D02*
Y508700D01*
X182833D01*
G01X185000D02*
Y511200D01*
X184500Y510700D01*
G01Y508700D02*
X185500D01*
G01X187292Y508992D02*
X187583Y508783D01*
X187917Y508700D01*
X188250Y508783D01*
X188542Y509033D01*
X188750Y509408D01*
X188833Y509783D01*
Y510242D01*
X188750Y510617D01*
X188542Y510950D01*
X188292Y511117D01*
X188000Y511200D01*
X187667Y511117D01*
X187417Y510950D01*
X187250Y510700D01*
X187167Y510367D01*
X187250Y510075D01*
X187458Y509783D01*
X187708Y509617D01*
X188000Y509575D01*
X188333Y509658D01*
X188583Y509867D01*
X188833Y510242D01*
G01X170611Y511093D02*
Y508593D01*
X172277D01*
G01X174444D02*
Y511093D01*
X173944Y510593D01*
G01Y508593D02*
X174944D01*
G01X177444D02*
X177736Y508635D01*
X178069Y508760D01*
X178277Y508968D01*
X178361Y509260D01*
X178277Y509551D01*
X178027Y509801D01*
X177652Y509926D01*
X177236D01*
X176986Y510010D01*
X176777Y510218D01*
X176694Y510510D01*
X176819Y510801D01*
X177111Y511010D01*
X177444Y511093D01*
X177777Y511010D01*
X178069Y510801D01*
X178194Y510510D01*
X178111Y510218D01*
X177902Y510010D01*
X177652Y509926D01*
X177236D01*
X176861Y509801D01*
X176611Y509551D01*
X176527Y509260D01*
X176611Y508968D01*
X176819Y508760D01*
X177152Y508635D01*
X177444Y508593D01*
G01X159067Y511000D02*
Y508500D01*
X160733D01*
G01X161983Y509000D02*
X162233Y508708D01*
X162567Y508542D01*
X162942Y508500D01*
X163275Y508542D01*
X163608Y508750D01*
X163817Y509000D01*
X163858Y509250D01*
X163775Y509542D01*
X163483Y509750D01*
X163192Y509833D01*
X162817D01*
G01X163192D02*
X163442Y509958D01*
X163650Y510167D01*
X163733Y510417D01*
X163650Y510667D01*
X163442Y510875D01*
X163067Y511000D01*
X162692Y510958D01*
X162317Y510792D01*
G01X165108Y509542D02*
X165400Y509833D01*
X165650Y510000D01*
X165983Y510083D01*
X166275Y510000D01*
X166483Y509833D01*
X166650Y509583D01*
X166692Y509292D01*
X166650Y509042D01*
X166483Y508792D01*
X166233Y508583D01*
X165942Y508500D01*
X165608Y508583D01*
X165317Y508833D01*
X165150Y509208D01*
X165108Y509625D01*
X165192Y510167D01*
X165317Y510458D01*
X165525Y510750D01*
X165817Y510958D01*
X166108Y511000D01*
X166400Y510917D01*
X166608Y510708D01*
G01X159667Y514500D02*
Y512000D01*
X161333D01*
G01X162583Y512500D02*
X162833Y512208D01*
X163167Y512042D01*
X163542Y512000D01*
X163875Y512042D01*
X164208Y512250D01*
X164417Y512500D01*
X164458Y512750D01*
X164375Y513042D01*
X164083Y513250D01*
X163792Y513333D01*
X163417D01*
G01X163792D02*
X164042Y513458D01*
X164250Y513667D01*
X164333Y513917D01*
X164250Y514167D01*
X164042Y514375D01*
X163667Y514500D01*
X163292Y514458D01*
X162917Y514292D01*
G01X165583Y512375D02*
X165833Y512167D01*
X166125Y512042D01*
X166500Y512000D01*
X166875Y512083D01*
X167167Y512250D01*
X167375Y512542D01*
X167417Y512875D01*
X167333Y513208D01*
X167125Y513417D01*
X166833Y513583D01*
X166542Y513625D01*
X166250Y513583D01*
X165875Y513417D01*
X166000Y514500D01*
X167125D01*
G01X170067D02*
Y512000D01*
X171733D01*
G01X172983Y512500D02*
X173233Y512208D01*
X173567Y512042D01*
X173942Y512000D01*
X174275Y512042D01*
X174608Y512250D01*
X174817Y512500D01*
X174858Y512750D01*
X174775Y513042D01*
X174483Y513250D01*
X174192Y513333D01*
X173817D01*
G01X174192D02*
X174442Y513458D01*
X174650Y513667D01*
X174733Y513917D01*
X174650Y514167D01*
X174442Y514375D01*
X174067Y514500D01*
X173692Y514458D01*
X173317Y514292D01*
G01X177400Y512000D02*
Y514500D01*
X175858Y512708D01*
X177942D01*
G01X213967Y518100D02*
Y515600D01*
X215633D01*
G01X217008Y517683D02*
X217258Y517933D01*
X217550Y518058D01*
X217883Y518100D01*
X218300Y518017D01*
X218592Y517808D01*
X218675Y517558D01*
X218633Y517308D01*
X218467Y517100D01*
X217633Y516683D01*
X217258Y516392D01*
X217008Y515975D01*
X216925Y515600D01*
X218675D01*
G01X219883Y515975D02*
X220133Y515767D01*
X220425Y515642D01*
X220800Y515600D01*
X221175Y515683D01*
X221467Y515850D01*
X221675Y516142D01*
X221717Y516475D01*
X221633Y516808D01*
X221425Y517017D01*
X221133Y517183D01*
X220842Y517225D01*
X220550Y517183D01*
X220175Y517017D01*
X220300Y518100D01*
X221425D01*
G01X203267Y514400D02*
Y511900D01*
X204933D01*
G01X206308Y513983D02*
X206558Y514233D01*
X206850Y514358D01*
X207183Y514400D01*
X207600Y514317D01*
X207892Y514108D01*
X207975Y513858D01*
X207933Y513608D01*
X207767Y513400D01*
X206933Y512983D01*
X206558Y512692D01*
X206308Y512275D01*
X206225Y511900D01*
X207975D01*
G01X210600D02*
Y514400D01*
X209058Y512608D01*
X211142D01*
G01X203250Y510933D02*
Y508433D01*
X204916D01*
G01X206291Y510516D02*
X206541Y510766D01*
X206833Y510891D01*
X207166Y510933D01*
X207583Y510850D01*
X207875Y510641D01*
X207958Y510391D01*
X207916Y510141D01*
X207750Y509933D01*
X206916Y509516D01*
X206541Y509225D01*
X206291Y508808D01*
X206208Y508433D01*
X207958D01*
G01X209166Y508933D02*
X209416Y508641D01*
X209750Y508475D01*
X210125Y508433D01*
X210458Y508475D01*
X210791Y508683D01*
X211000Y508933D01*
X211041Y509183D01*
X210958Y509475D01*
X210666Y509683D01*
X210375Y509766D01*
X210000D01*
G01X210375D02*
X210625Y509891D01*
X210833Y510100D01*
X210916Y510350D01*
X210833Y510600D01*
X210625Y510808D01*
X210250Y510933D01*
X209875Y510891D01*
X209500Y510725D01*
G01X192067Y510900D02*
Y508400D01*
X193733D01*
G01X195108Y510483D02*
X195358Y510733D01*
X195650Y510858D01*
X195983Y510900D01*
X196400Y510817D01*
X196692Y510608D01*
X196775Y510358D01*
X196733Y510108D01*
X196567Y509900D01*
X195733Y509483D01*
X195358Y509192D01*
X195108Y508775D01*
X195025Y508400D01*
X196775D01*
G01X198108Y510483D02*
X198358Y510733D01*
X198650Y510858D01*
X198983Y510900D01*
X199400Y510817D01*
X199692Y510608D01*
X199775Y510358D01*
X199733Y510108D01*
X199567Y509900D01*
X198733Y509483D01*
X198358Y509192D01*
X198108Y508775D01*
X198025Y508400D01*
X199775D01*
G01X192067Y514700D02*
Y512200D01*
X193733D01*
G01X195108Y514283D02*
X195358Y514533D01*
X195650Y514658D01*
X195983Y514700D01*
X196400Y514617D01*
X196692Y514408D01*
X196775Y514158D01*
X196733Y513908D01*
X196567Y513700D01*
X195733Y513283D01*
X195358Y512992D01*
X195108Y512575D01*
X195025Y512200D01*
X196775D01*
G01X198900D02*
Y514700D01*
X198400Y514200D01*
G01Y512200D02*
X199400D01*
G01X181067Y515100D02*
Y512600D01*
X182733D01*
G01X184108Y514683D02*
X184358Y514933D01*
X184650Y515058D01*
X184983Y515100D01*
X185400Y515017D01*
X185692Y514808D01*
X185775Y514558D01*
X185733Y514308D01*
X185567Y514100D01*
X184733Y513683D01*
X184358Y513392D01*
X184108Y512975D01*
X184025Y512600D01*
X185775D01*
G01X187900Y515100D02*
X187567Y515017D01*
X187317Y514808D01*
X187150Y514558D01*
X187025Y514225D01*
X186983Y513850D01*
X187025Y513475D01*
X187150Y513142D01*
X187317Y512892D01*
X187567Y512683D01*
X187900Y512600D01*
X188233Y512683D01*
X188483Y512892D01*
X188650Y513142D01*
X188775Y513475D01*
X188817Y513850D01*
X188775Y514225D01*
X188650Y514558D01*
X188483Y514808D01*
X188233Y515017D01*
X187900Y515100D01*
G01X172927Y569296D02*
X172802Y569046D01*
X172719Y568754D01*
Y568421D01*
X172844Y568046D01*
X173052Y567754D01*
X173302Y567546D01*
X173719Y567379D01*
X174094Y567337D01*
X174469Y567421D01*
X174719Y567546D01*
X174969Y567796D01*
X175136Y568087D01*
X175219Y568379D01*
Y568671D01*
X175136Y568962D01*
X175011Y569212D01*
X174844Y569421D01*
G01X175219Y570421D02*
X172719D01*
X175219Y572337D01*
X172719D01*
G01X174927Y573671D02*
X175136Y573962D01*
X175219Y574296D01*
X175136Y574629D01*
X174886Y574921D01*
X174511Y575129D01*
X174136Y575212D01*
X173677D01*
X173302Y575129D01*
X172969Y574921D01*
X172802Y574671D01*
X172719Y574379D01*
X172802Y574046D01*
X172969Y573796D01*
X173219Y573629D01*
X173552Y573546D01*
X173844Y573629D01*
X174136Y573837D01*
X174302Y574087D01*
X174344Y574379D01*
X174261Y574712D01*
X174052Y574962D01*
X173677Y575212D01*
G01X212257Y762766D02*
X214049D01*
X214424Y762933D01*
X214674Y763266D01*
X214757Y763683D01*
X214674Y764100D01*
X214424Y764433D01*
X214049Y764600D01*
X212257D01*
G01X214757Y766683D02*
X214715Y766975D01*
X214590Y767308D01*
X214382Y767516D01*
X214090Y767600D01*
X213799Y767516D01*
X213549Y767266D01*
X213424Y766891D01*
Y766475D01*
X213340Y766225D01*
X213132Y766016D01*
X212840Y765933D01*
X212549Y766058D01*
X212340Y766350D01*
X212257Y766683D01*
X212340Y767016D01*
X212549Y767308D01*
X212840Y767433D01*
X213132Y767350D01*
X213340Y767141D01*
X213424Y766891D01*
Y766475D01*
X213549Y766100D01*
X213799Y765850D01*
X214090Y765766D01*
X214382Y765850D01*
X214590Y766058D01*
X214715Y766391D01*
X214757Y766683D01*
G01X214600Y734867D02*
X212100D01*
Y735908D01*
X212225Y736242D01*
X212392Y736450D01*
X212725Y736533D01*
X213058Y736450D01*
X213267Y736200D01*
X213392Y735908D01*
Y734867D01*
G01Y735908D02*
X214600Y736533D01*
G01Y738700D02*
X212100D01*
X212600Y738200D01*
G01X214600D02*
Y739200D01*
G01X214225Y740783D02*
X214433Y741033D01*
X214558Y741325D01*
X214600Y741700D01*
X214517Y742075D01*
X214350Y742367D01*
X214058Y742575D01*
X213725Y742617D01*
X213392Y742533D01*
X213183Y742325D01*
X213017Y742033D01*
X212975Y741742D01*
X213017Y741450D01*
X213183Y741075D01*
X212100Y741200D01*
Y742325D01*
G01X213558Y743908D02*
X213267Y744200D01*
X213100Y744450D01*
X213017Y744783D01*
X213100Y745075D01*
X213267Y745283D01*
X213517Y745450D01*
X213808Y745492D01*
X214058Y745450D01*
X214308Y745283D01*
X214517Y745033D01*
X214600Y744742D01*
X214517Y744408D01*
X214267Y744117D01*
X213892Y743950D01*
X213475Y743908D01*
X212933Y743992D01*
X212642Y744117D01*
X212350Y744325D01*
X212142Y744617D01*
X212100Y744908D01*
X212183Y745200D01*
X212392Y745408D01*
G01X208808Y833117D02*
X208683Y832867D01*
X208600Y832575D01*
Y832242D01*
X208725Y831867D01*
X208933Y831575D01*
X209183Y831367D01*
X209600Y831200D01*
X209975Y831158D01*
X210350Y831242D01*
X210600Y831367D01*
X210850Y831617D01*
X211017Y831908D01*
X211100Y832200D01*
Y832492D01*
X211017Y832783D01*
X210892Y833033D01*
X210725Y833242D01*
G01X211100Y834242D02*
X208600D01*
X211100Y836158D01*
X208600D01*
G01X211100Y838117D02*
X210558Y838200D01*
X210100Y838325D01*
X209683Y838492D01*
X209225Y838700D01*
X208600Y839033D01*
Y837367D01*
G01X208967Y821227D02*
X208842Y820977D01*
X208759Y820685D01*
Y820352D01*
X208884Y819977D01*
X209092Y819685D01*
X209342Y819477D01*
X209759Y819310D01*
X210134Y819268D01*
X210509Y819352D01*
X210759Y819477D01*
X211009Y819727D01*
X211176Y820018D01*
X211259Y820310D01*
Y820602D01*
X211176Y820893D01*
X211051Y821143D01*
X210884Y821352D01*
G01X211259Y822352D02*
X208759D01*
X211259Y824268D01*
X208759D01*
G01X211259Y826310D02*
X208759D01*
X209259Y825810D01*
G01X211259D02*
Y826810D01*
G01X211117Y780092D02*
X210867Y780217D01*
X210575Y780300D01*
X210242D01*
X209867Y780175D01*
X209575Y779967D01*
X209367Y779717D01*
X209200Y779300D01*
X209158Y778925D01*
X209242Y778550D01*
X209367Y778300D01*
X209617Y778050D01*
X209908Y777883D01*
X210200Y777800D01*
X210492D01*
X210783Y777883D01*
X211033Y778008D01*
X211242Y778175D01*
G01X212408Y779883D02*
X212658Y780133D01*
X212950Y780258D01*
X213283Y780300D01*
X213700Y780217D01*
X213992Y780008D01*
X214075Y779758D01*
X214033Y779508D01*
X213867Y779300D01*
X213033Y778883D01*
X212658Y778592D01*
X212408Y778175D01*
X212325Y777800D01*
X214075D01*
G01X215283Y778300D02*
X215533Y778008D01*
X215867Y777842D01*
X216242Y777800D01*
X216575Y777842D01*
X216908Y778050D01*
X217117Y778300D01*
X217158Y778550D01*
X217075Y778842D01*
X216783Y779050D01*
X216492Y779133D01*
X216117D01*
G01X216492D02*
X216742Y779258D01*
X216950Y779467D01*
X217033Y779717D01*
X216950Y779967D01*
X216742Y780175D01*
X216367Y780300D01*
X215992Y780258D01*
X215617Y780092D01*
G01X219200Y780300D02*
X218867Y780217D01*
X218617Y780008D01*
X218450Y779758D01*
X218325Y779425D01*
X218283Y779050D01*
X218325Y778675D01*
X218450Y778342D01*
X218617Y778092D01*
X218867Y777883D01*
X219200Y777800D01*
X219533Y777883D01*
X219783Y778092D01*
X219950Y778342D01*
X220075Y778675D01*
X220117Y779050D01*
X220075Y779425D01*
X219950Y779758D01*
X219783Y780008D01*
X219533Y780217D01*
X219200Y780300D01*
G01X175625Y898500D02*
Y901000D01*
G01X177375D02*
Y898500D01*
G01Y899750D02*
X175625D01*
G01X178583Y899000D02*
X178833Y898708D01*
X179167Y898542D01*
X179542Y898500D01*
X179875Y898542D01*
X180208Y898750D01*
X180417Y899000D01*
X180458Y899250D01*
X180375Y899542D01*
X180083Y899750D01*
X179792Y899833D01*
X179417D01*
G01X179792D02*
X180042Y899958D01*
X180250Y900167D01*
X180333Y900417D01*
X180250Y900667D01*
X180042Y900875D01*
X179667Y901000D01*
X179292Y900958D01*
X178917Y900792D01*
G01X231481Y46005D02*
X228981D01*
Y47005D01*
X229106Y47338D01*
X229398Y47588D01*
X229731Y47671D01*
X230064Y47588D01*
X230314Y47380D01*
X230439Y47005D01*
Y46005D01*
G01X231481Y49005D02*
X228981D01*
Y50046D01*
X229106Y50380D01*
X229273Y50588D01*
X229606Y50671D01*
X229939Y50588D01*
X230148Y50338D01*
X230273Y50046D01*
Y49005D01*
G01Y50046D02*
X231481Y50671D01*
G01Y52838D02*
X228981D01*
X229481Y52338D01*
G01X231481D02*
Y53338D01*
G01Y55755D02*
X230939Y55838D01*
X230481Y55963D01*
X230064Y56130D01*
X229606Y56338D01*
X228981Y56671D01*
Y55005D01*
G01X226691Y45436D02*
X224191D01*
Y46436D01*
X224316Y46769D01*
X224608Y47019D01*
X224941Y47102D01*
X225274Y47019D01*
X225524Y46811D01*
X225649Y46436D01*
Y45436D01*
G01X226691Y48436D02*
X224191D01*
Y49477D01*
X224316Y49811D01*
X224483Y50019D01*
X224816Y50102D01*
X225149Y50019D01*
X225358Y49769D01*
X225483Y49477D01*
Y48436D01*
G01Y49477D02*
X226691Y50102D01*
G01Y52269D02*
X224191D01*
X224691Y51769D01*
G01X226691D02*
Y52769D01*
G01Y55269D02*
X226649Y55561D01*
X226524Y55894D01*
X226316Y56102D01*
X226024Y56186D01*
X225733Y56102D01*
X225483Y55852D01*
X225358Y55477D01*
Y55061D01*
X225274Y54811D01*
X225066Y54602D01*
X224774Y54519D01*
X224483Y54644D01*
X224274Y54936D01*
X224191Y55269D01*
X224274Y55602D01*
X224483Y55894D01*
X224774Y56019D01*
X225066Y55936D01*
X225274Y55727D01*
X225358Y55477D01*
Y55061D01*
X225483Y54686D01*
X225733Y54436D01*
X226024Y54352D01*
X226316Y54436D01*
X226524Y54644D01*
X226649Y54977D01*
X226691Y55269D01*
G01X275889Y34516D02*
X273389D01*
Y35516D01*
X273514Y35849D01*
X273806Y36099D01*
X274139Y36182D01*
X274472Y36099D01*
X274722Y35891D01*
X274847Y35516D01*
Y34516D01*
G01X273389Y37516D02*
X275889D01*
Y39182D01*
G01Y41349D02*
X273389D01*
X273889Y40849D01*
G01X275889D02*
Y41849D01*
G01X238300Y35767D02*
X235800D01*
Y36767D01*
X235925Y37100D01*
X236217Y37350D01*
X236550Y37433D01*
X236883Y37350D01*
X237133Y37142D01*
X237258Y36767D01*
Y35767D01*
G01X236008Y40517D02*
X235883Y40267D01*
X235800Y39975D01*
Y39642D01*
X235925Y39267D01*
X236133Y38975D01*
X236383Y38767D01*
X236800Y38600D01*
X237175Y38558D01*
X237550Y38642D01*
X237800Y38767D01*
X238050Y39017D01*
X238217Y39308D01*
X238300Y39600D01*
Y39892D01*
X238217Y40183D01*
X238092Y40433D01*
X237925Y40642D01*
G01X238300Y42600D02*
X235800D01*
X236300Y42100D01*
G01X238300D02*
Y43100D01*
G01X236217Y44808D02*
X235967Y45058D01*
X235842Y45350D01*
X235800Y45683D01*
X235883Y46100D01*
X236092Y46392D01*
X236342Y46475D01*
X236592Y46433D01*
X236800Y46267D01*
X237217Y45433D01*
X237508Y45058D01*
X237925Y44808D01*
X238300Y44725D01*
Y46475D01*
G01X261600Y36667D02*
X259100D01*
Y37667D01*
X259225Y38000D01*
X259517Y38250D01*
X259850Y38333D01*
X260183Y38250D01*
X260433Y38042D01*
X260558Y37667D01*
Y36667D01*
G01X259308Y41417D02*
X259183Y41167D01*
X259100Y40875D01*
Y40542D01*
X259225Y40167D01*
X259433Y39875D01*
X259683Y39667D01*
X260100Y39500D01*
X260475Y39458D01*
X260850Y39542D01*
X261100Y39667D01*
X261350Y39917D01*
X261517Y40208D01*
X261600Y40500D01*
Y40792D01*
X261517Y41083D01*
X261392Y41333D01*
X261225Y41542D01*
G01X261600Y43500D02*
X259100D01*
X259600Y43000D01*
G01X261600D02*
Y44000D01*
G01X261100Y45583D02*
X261392Y45833D01*
X261558Y46167D01*
X261600Y46542D01*
X261558Y46875D01*
X261350Y47208D01*
X261100Y47417D01*
X260850Y47458D01*
X260558Y47375D01*
X260350Y47083D01*
X260267Y46792D01*
Y46417D01*
G01Y46792D02*
X260142Y47042D01*
X259933Y47250D01*
X259683Y47333D01*
X259433Y47250D01*
X259225Y47042D01*
X259100Y46667D01*
X259142Y46292D01*
X259308Y45917D01*
G01X256700Y35767D02*
X254200D01*
Y36767D01*
X254325Y37100D01*
X254617Y37350D01*
X254950Y37433D01*
X255283Y37350D01*
X255533Y37142D01*
X255658Y36767D01*
Y35767D01*
G01X254408Y40517D02*
X254283Y40267D01*
X254200Y39975D01*
Y39642D01*
X254325Y39267D01*
X254533Y38975D01*
X254783Y38767D01*
X255200Y38600D01*
X255575Y38558D01*
X255950Y38642D01*
X256200Y38767D01*
X256450Y39017D01*
X256617Y39308D01*
X256700Y39600D01*
Y39892D01*
X256617Y40183D01*
X256492Y40433D01*
X256325Y40642D01*
G01X256700Y42600D02*
X254200D01*
X254700Y42100D01*
G01X256700D02*
Y43100D01*
G01Y46100D02*
X254200D01*
X255992Y44558D01*
Y46642D01*
G01X248000Y35967D02*
X245500D01*
Y36967D01*
X245625Y37300D01*
X245917Y37550D01*
X246250Y37633D01*
X246583Y37550D01*
X246833Y37342D01*
X246958Y36967D01*
Y35967D01*
G01X245708Y40717D02*
X245583Y40467D01*
X245500Y40175D01*
Y39842D01*
X245625Y39467D01*
X245833Y39175D01*
X246083Y38967D01*
X246500Y38800D01*
X246875Y38758D01*
X247250Y38842D01*
X247500Y38967D01*
X247750Y39217D01*
X247917Y39508D01*
X248000Y39800D01*
Y40092D01*
X247917Y40383D01*
X247792Y40633D01*
X247625Y40842D01*
G01X248000Y42800D02*
X245500D01*
X246000Y42300D01*
G01X248000D02*
Y43300D01*
G01X247625Y44883D02*
X247833Y45133D01*
X247958Y45425D01*
X248000Y45800D01*
X247917Y46175D01*
X247750Y46467D01*
X247458Y46675D01*
X247125Y46717D01*
X246792Y46633D01*
X246583Y46425D01*
X246417Y46133D01*
X246375Y45842D01*
X246417Y45550D01*
X246583Y45175D01*
X245500Y45300D01*
Y46425D01*
G01X226967Y99000D02*
Y101500D01*
X227967D01*
X228300Y101375D01*
X228550Y101083D01*
X228633Y100750D01*
X228550Y100417D01*
X228342Y100167D01*
X227967Y100042D01*
X226967D01*
G01X229883Y101500D02*
Y99708D01*
X230050Y99333D01*
X230383Y99083D01*
X230800Y99000D01*
X231217Y99083D01*
X231550Y99333D01*
X231717Y99708D01*
Y101500D01*
G01X232883Y99500D02*
X233133Y99208D01*
X233467Y99042D01*
X233842Y99000D01*
X234175Y99042D01*
X234508Y99250D01*
X234717Y99500D01*
X234758Y99750D01*
X234675Y100042D01*
X234383Y100250D01*
X234092Y100333D01*
X233717D01*
G01X234092D02*
X234342Y100458D01*
X234550Y100667D01*
X234633Y100917D01*
X234550Y101167D01*
X234342Y101375D01*
X233967Y101500D01*
X233592Y101458D01*
X233217Y101292D01*
G01X259544Y67963D02*
Y70463D01*
X260544D01*
X260877Y70338D01*
X261127Y70046D01*
X261210Y69713D01*
X261127Y69380D01*
X260919Y69130D01*
X260544Y69005D01*
X259544D01*
G01X262544Y67963D02*
Y70463D01*
X263585D01*
X263919Y70338D01*
X264127Y70171D01*
X264210Y69838D01*
X264127Y69505D01*
X263877Y69296D01*
X263585Y69171D01*
X262544D01*
G01X263585D02*
X264210Y67963D01*
G01X266377D02*
Y70463D01*
X265877Y69963D01*
G01Y67963D02*
X266877D01*
G01X268585Y69005D02*
X268877Y69296D01*
X269127Y69463D01*
X269460Y69546D01*
X269752Y69463D01*
X269960Y69296D01*
X270127Y69046D01*
X270169Y68755D01*
X270127Y68505D01*
X269960Y68255D01*
X269710Y68046D01*
X269419Y67963D01*
X269085Y68046D01*
X268794Y68296D01*
X268627Y68671D01*
X268585Y69088D01*
X268669Y69630D01*
X268794Y69921D01*
X269002Y70213D01*
X269294Y70421D01*
X269585Y70463D01*
X269877Y70380D01*
X270085Y70171D01*
G01X220867Y109300D02*
Y111800D01*
X221867D01*
X222200Y111675D01*
X222450Y111383D01*
X222533Y111050D01*
X222450Y110717D01*
X222242Y110467D01*
X221867Y110342D01*
X220867D01*
G01X225617Y111592D02*
X225367Y111717D01*
X225075Y111800D01*
X224742D01*
X224367Y111675D01*
X224075Y111467D01*
X223867Y111217D01*
X223700Y110800D01*
X223658Y110425D01*
X223742Y110050D01*
X223867Y109800D01*
X224117Y109550D01*
X224408Y109383D01*
X224700Y109300D01*
X224992D01*
X225283Y109383D01*
X225533Y109508D01*
X225742Y109675D01*
G01X226908Y111383D02*
X227158Y111633D01*
X227450Y111758D01*
X227783Y111800D01*
X228200Y111717D01*
X228492Y111508D01*
X228575Y111258D01*
X228533Y111008D01*
X228367Y110800D01*
X227533Y110383D01*
X227158Y110092D01*
X226908Y109675D01*
X226825Y109300D01*
X228575D01*
G01X229908Y110342D02*
X230200Y110633D01*
X230450Y110800D01*
X230783Y110883D01*
X231075Y110800D01*
X231283Y110633D01*
X231450Y110383D01*
X231492Y110092D01*
X231450Y109842D01*
X231283Y109592D01*
X231033Y109383D01*
X230742Y109300D01*
X230408Y109383D01*
X230117Y109633D01*
X229950Y110008D01*
X229908Y110425D01*
X229992Y110967D01*
X230117Y111258D01*
X230325Y111550D01*
X230617Y111758D01*
X230908Y111800D01*
X231200Y111717D01*
X231408Y111508D01*
G01X274914Y77392D02*
X272414D01*
Y78392D01*
X272539Y78725D01*
X272831Y78975D01*
X273164Y79058D01*
X273497Y78975D01*
X273747Y78767D01*
X273872Y78392D01*
Y77392D01*
G01X272622Y82142D02*
X272497Y81892D01*
X272414Y81600D01*
Y81267D01*
X272539Y80892D01*
X272747Y80600D01*
X272997Y80392D01*
X273414Y80225D01*
X273789Y80183D01*
X274164Y80267D01*
X274414Y80392D01*
X274664Y80642D01*
X274831Y80933D01*
X274914Y81225D01*
Y81517D01*
X274831Y81808D01*
X274706Y82058D01*
X274539Y82267D01*
G01X272831Y83433D02*
X272581Y83683D01*
X272456Y83975D01*
X272414Y84308D01*
X272497Y84725D01*
X272706Y85017D01*
X272956Y85100D01*
X273206Y85058D01*
X273414Y84892D01*
X273831Y84058D01*
X274122Y83683D01*
X274539Y83433D01*
X274914Y83350D01*
Y85100D01*
G01X274539Y86308D02*
X274747Y86558D01*
X274872Y86850D01*
X274914Y87225D01*
X274831Y87600D01*
X274664Y87892D01*
X274372Y88100D01*
X274039Y88142D01*
X273706Y88058D01*
X273497Y87850D01*
X273331Y87558D01*
X273289Y87267D01*
X273331Y86975D01*
X273497Y86600D01*
X272414Y86725D01*
Y87850D01*
G01X267600Y130167D02*
X265100D01*
Y131167D01*
X265225Y131500D01*
X265517Y131750D01*
X265850Y131833D01*
X266183Y131750D01*
X266433Y131542D01*
X266558Y131167D01*
Y130167D01*
G01X265308Y134917D02*
X265183Y134667D01*
X265100Y134375D01*
Y134042D01*
X265225Y133667D01*
X265433Y133375D01*
X265683Y133167D01*
X266100Y133000D01*
X266475Y132958D01*
X266850Y133042D01*
X267100Y133167D01*
X267350Y133417D01*
X267517Y133708D01*
X267600Y134000D01*
Y134292D01*
X267517Y134583D01*
X267392Y134833D01*
X267225Y135042D01*
G01Y136083D02*
X267433Y136333D01*
X267558Y136625D01*
X267600Y137000D01*
X267517Y137375D01*
X267350Y137667D01*
X267058Y137875D01*
X266725Y137917D01*
X266392Y137833D01*
X266183Y137625D01*
X266017Y137333D01*
X265975Y137042D01*
X266017Y136750D01*
X266183Y136375D01*
X265100Y136500D01*
Y137625D01*
G01X265517Y139208D02*
X265267Y139458D01*
X265142Y139750D01*
X265100Y140083D01*
X265183Y140500D01*
X265392Y140792D01*
X265642Y140875D01*
X265892Y140833D01*
X266100Y140667D01*
X266517Y139833D01*
X266808Y139458D01*
X267225Y139208D01*
X267600Y139125D01*
Y140875D01*
G01X220867Y116800D02*
Y119300D01*
X221867D01*
X222200Y119175D01*
X222450Y118883D01*
X222533Y118550D01*
X222450Y118217D01*
X222242Y117967D01*
X221867Y117842D01*
X220867D01*
G01X223867Y116800D02*
Y119300D01*
X224908D01*
X225242Y119175D01*
X225450Y119008D01*
X225533Y118675D01*
X225450Y118342D01*
X225200Y118133D01*
X224908Y118008D01*
X223867D01*
G01X224908D02*
X225533Y116800D01*
G01X226783Y117300D02*
X227033Y117008D01*
X227367Y116842D01*
X227742Y116800D01*
X228075Y116842D01*
X228408Y117050D01*
X228617Y117300D01*
X228658Y117550D01*
X228575Y117842D01*
X228283Y118050D01*
X227992Y118133D01*
X227617D01*
G01X227992D02*
X228242Y118258D01*
X228450Y118467D01*
X228533Y118717D01*
X228450Y118967D01*
X228242Y119175D01*
X227867Y119300D01*
X227492Y119258D01*
X227117Y119092D01*
G01X230700Y119300D02*
X230367Y119217D01*
X230117Y119008D01*
X229950Y118758D01*
X229825Y118425D01*
X229783Y118050D01*
X229825Y117675D01*
X229950Y117342D01*
X230117Y117092D01*
X230367Y116883D01*
X230700Y116800D01*
X231033Y116883D01*
X231283Y117092D01*
X231450Y117342D01*
X231575Y117675D01*
X231617Y118050D01*
X231575Y118425D01*
X231450Y118758D01*
X231283Y119008D01*
X231033Y119217D01*
X230700Y119300D01*
G01X220867Y112900D02*
Y115400D01*
X221867D01*
X222200Y115275D01*
X222450Y114983D01*
X222533Y114650D01*
X222450Y114317D01*
X222242Y114067D01*
X221867Y113942D01*
X220867D01*
G01X223867Y112900D02*
Y115400D01*
X224908D01*
X225242Y115275D01*
X225450Y115108D01*
X225533Y114775D01*
X225450Y114442D01*
X225200Y114233D01*
X224908Y114108D01*
X223867D01*
G01X224908D02*
X225533Y112900D01*
G01X226908Y114983D02*
X227158Y115233D01*
X227450Y115358D01*
X227783Y115400D01*
X228200Y115317D01*
X228492Y115108D01*
X228575Y114858D01*
X228533Y114608D01*
X228367Y114400D01*
X227533Y113983D01*
X227158Y113692D01*
X226908Y113275D01*
X226825Y112900D01*
X228575D01*
G01X229992Y113192D02*
X230283Y112983D01*
X230617Y112900D01*
X230950Y112983D01*
X231242Y113233D01*
X231450Y113608D01*
X231533Y113983D01*
Y114442D01*
X231450Y114817D01*
X231242Y115150D01*
X230992Y115317D01*
X230700Y115400D01*
X230367Y115317D01*
X230117Y115150D01*
X229950Y114900D01*
X229867Y114567D01*
X229950Y114275D01*
X230158Y113983D01*
X230408Y113817D01*
X230700Y113775D01*
X231033Y113858D01*
X231283Y114067D01*
X231533Y114442D01*
G01X254267Y93100D02*
Y95600D01*
X255267D01*
X255600Y95475D01*
X255850Y95183D01*
X255933Y94850D01*
X255850Y94517D01*
X255642Y94267D01*
X255267Y94142D01*
X254267D01*
G01X257267Y93100D02*
Y95600D01*
X258308D01*
X258642Y95475D01*
X258850Y95308D01*
X258933Y94975D01*
X258850Y94642D01*
X258600Y94433D01*
X258308Y94308D01*
X257267D01*
G01X258308D02*
X258933Y93100D01*
G01X260308Y95183D02*
X260558Y95433D01*
X260850Y95558D01*
X261183Y95600D01*
X261600Y95517D01*
X261892Y95308D01*
X261975Y95058D01*
X261933Y94808D01*
X261767Y94600D01*
X260933Y94183D01*
X260558Y93892D01*
X260308Y93475D01*
X260225Y93100D01*
X261975D01*
G01X264017D02*
X264100Y93642D01*
X264225Y94100D01*
X264392Y94517D01*
X264600Y94975D01*
X264933Y95600D01*
X263267D01*
G01X253567Y97064D02*
Y99564D01*
X254567D01*
X254900Y99439D01*
X255150Y99147D01*
X255233Y98814D01*
X255150Y98481D01*
X254942Y98231D01*
X254567Y98106D01*
X253567D01*
G01X256567Y97064D02*
Y99564D01*
X257608D01*
X257942Y99439D01*
X258150Y99272D01*
X258233Y98939D01*
X258150Y98606D01*
X257900Y98397D01*
X257608Y98272D01*
X256567D01*
G01X257608D02*
X258233Y97064D01*
G01X259608Y99147D02*
X259858Y99397D01*
X260150Y99522D01*
X260483Y99564D01*
X260900Y99481D01*
X261192Y99272D01*
X261275Y99022D01*
X261233Y98772D01*
X261067Y98564D01*
X260233Y98147D01*
X259858Y97856D01*
X259608Y97439D01*
X259525Y97064D01*
X261275D01*
G01X262483Y97439D02*
X262733Y97231D01*
X263025Y97106D01*
X263400Y97064D01*
X263775Y97147D01*
X264067Y97314D01*
X264275Y97606D01*
X264317Y97939D01*
X264233Y98272D01*
X264025Y98481D01*
X263733Y98647D01*
X263442Y98689D01*
X263150Y98647D01*
X262775Y98481D01*
X262900Y99564D01*
X264025D01*
G01X255167Y89067D02*
Y91567D01*
X256167D01*
X256500Y91442D01*
X256750Y91150D01*
X256833Y90817D01*
X256750Y90484D01*
X256542Y90234D01*
X256167Y90109D01*
X255167D01*
G01X258167Y89067D02*
Y91567D01*
X259208D01*
X259542Y91442D01*
X259750Y91275D01*
X259833Y90942D01*
X259750Y90609D01*
X259500Y90400D01*
X259208Y90275D01*
X258167D01*
G01X259208D02*
X259833Y89067D01*
G01X261208Y91150D02*
X261458Y91400D01*
X261750Y91525D01*
X262083Y91567D01*
X262500Y91484D01*
X262792Y91275D01*
X262875Y91025D01*
X262833Y90775D01*
X262667Y90567D01*
X261833Y90150D01*
X261458Y89859D01*
X261208Y89442D01*
X261125Y89067D01*
X262875D01*
G01X265000D02*
Y91567D01*
X264500Y91067D01*
G01Y89067D02*
X265500D01*
G01X252592Y76320D02*
Y78820D01*
X253592D01*
X253925Y78695D01*
X254175Y78403D01*
X254258Y78070D01*
X254175Y77737D01*
X253967Y77487D01*
X253592Y77362D01*
X252592D01*
G01X255592Y76320D02*
Y78820D01*
X256633D01*
X256967Y78695D01*
X257175Y78528D01*
X257258Y78195D01*
X257175Y77862D01*
X256925Y77653D01*
X256633Y77528D01*
X255592D01*
G01X256633D02*
X257258Y76320D01*
G01X259425D02*
Y78820D01*
X258925Y78320D01*
G01Y76320D02*
X259925D01*
G01X262925D02*
Y78820D01*
X261383Y77028D01*
X263467D01*
G01X251699Y101366D02*
Y103866D01*
X252699D01*
X253032Y103741D01*
X253282Y103449D01*
X253365Y103116D01*
X253282Y102783D01*
X253074Y102533D01*
X252699Y102408D01*
X251699D01*
G01X254699Y101366D02*
Y103866D01*
X255740D01*
X256074Y103741D01*
X256282Y103574D01*
X256365Y103241D01*
X256282Y102908D01*
X256032Y102699D01*
X255740Y102574D01*
X254699D01*
G01X255740D02*
X256365Y101366D01*
G01X257740Y103449D02*
X257990Y103699D01*
X258282Y103824D01*
X258615Y103866D01*
X259032Y103783D01*
X259324Y103574D01*
X259407Y103324D01*
X259365Y103074D01*
X259199Y102866D01*
X258365Y102449D01*
X257990Y102158D01*
X257740Y101741D01*
X257657Y101366D01*
X259407D01*
G01X261532D02*
X261824Y101408D01*
X262157Y101533D01*
X262365Y101741D01*
X262449Y102033D01*
X262365Y102324D01*
X262115Y102574D01*
X261740Y102699D01*
X261324D01*
X261074Y102783D01*
X260865Y102991D01*
X260782Y103283D01*
X260907Y103574D01*
X261199Y103783D01*
X261532Y103866D01*
X261865Y103783D01*
X262157Y103574D01*
X262282Y103283D01*
X262199Y102991D01*
X261990Y102783D01*
X261740Y102699D01*
X261324D01*
X260949Y102574D01*
X260699Y102324D01*
X260615Y102033D01*
X260699Y101741D01*
X260907Y101533D01*
X261240Y101408D01*
X261532Y101366D01*
G01X252510Y72505D02*
Y75005D01*
X253510D01*
X253843Y74880D01*
X254093Y74588D01*
X254176Y74255D01*
X254093Y73922D01*
X253885Y73672D01*
X253510Y73547D01*
X252510D01*
G01X255510Y72505D02*
Y75005D01*
X256551D01*
X256885Y74880D01*
X257093Y74713D01*
X257176Y74380D01*
X257093Y74047D01*
X256843Y73838D01*
X256551Y73713D01*
X255510D01*
G01X256551D02*
X257176Y72505D01*
G01X258635Y72797D02*
X258926Y72588D01*
X259260Y72505D01*
X259593Y72588D01*
X259885Y72838D01*
X260093Y73213D01*
X260176Y73588D01*
Y74047D01*
X260093Y74422D01*
X259885Y74755D01*
X259635Y74922D01*
X259343Y75005D01*
X259010Y74922D01*
X258760Y74755D01*
X258593Y74505D01*
X258510Y74172D01*
X258593Y73880D01*
X258801Y73588D01*
X259051Y73422D01*
X259343Y73380D01*
X259676Y73463D01*
X259926Y73672D01*
X260176Y74047D01*
G01X271400Y130067D02*
X268900D01*
Y131067D01*
X269025Y131400D01*
X269317Y131650D01*
X269650Y131733D01*
X269983Y131650D01*
X270233Y131442D01*
X270358Y131067D01*
Y130067D01*
G01X271400Y133067D02*
X268900D01*
Y134108D01*
X269025Y134442D01*
X269192Y134650D01*
X269525Y134733D01*
X269858Y134650D01*
X270067Y134400D01*
X270192Y134108D01*
Y133067D01*
G01Y134108D02*
X271400Y134733D01*
G01Y137400D02*
X268900D01*
X270692Y135858D01*
Y137942D01*
G01X263200Y130367D02*
X260700D01*
Y131367D01*
X260825Y131700D01*
X261117Y131950D01*
X261450Y132033D01*
X261783Y131950D01*
X262033Y131742D01*
X262158Y131367D01*
Y130367D01*
G01X263200Y133367D02*
X260700D01*
Y134408D01*
X260825Y134742D01*
X260992Y134950D01*
X261325Y135033D01*
X261658Y134950D01*
X261867Y134700D01*
X261992Y134408D01*
Y133367D01*
G01Y134408D02*
X263200Y135033D01*
G01Y137200D02*
X260700D01*
X261200Y136700D01*
G01X263200D02*
Y137700D01*
G01X259700Y130467D02*
X257200D01*
Y131467D01*
X257325Y131800D01*
X257617Y132050D01*
X257950Y132133D01*
X258283Y132050D01*
X258533Y131842D01*
X258658Y131467D01*
Y130467D01*
G01X257408Y135217D02*
X257283Y134967D01*
X257200Y134675D01*
Y134342D01*
X257325Y133967D01*
X257533Y133675D01*
X257783Y133467D01*
X258200Y133300D01*
X258575Y133258D01*
X258950Y133342D01*
X259200Y133467D01*
X259450Y133717D01*
X259617Y134008D01*
X259700Y134300D01*
Y134592D01*
X259617Y134883D01*
X259492Y135133D01*
X259325Y135342D01*
G01Y136383D02*
X259533Y136633D01*
X259658Y136925D01*
X259700Y137300D01*
X259617Y137675D01*
X259450Y137967D01*
X259158Y138175D01*
X258825Y138217D01*
X258492Y138133D01*
X258283Y137925D01*
X258117Y137633D01*
X258075Y137342D01*
X258117Y137050D01*
X258283Y136675D01*
X257200Y136800D01*
Y137925D01*
G01X259700Y140300D02*
X257200D01*
X257700Y139800D01*
G01X259700D02*
Y140800D01*
G01X270414Y77473D02*
X267914D01*
Y78473D01*
X268039Y78806D01*
X268331Y79056D01*
X268664Y79139D01*
X268997Y79056D01*
X269247Y78848D01*
X269372Y78473D01*
Y77473D01*
G01X268122Y82223D02*
X267997Y81973D01*
X267914Y81681D01*
Y81348D01*
X268039Y80973D01*
X268247Y80681D01*
X268497Y80473D01*
X268914Y80306D01*
X269289Y80264D01*
X269664Y80348D01*
X269914Y80473D01*
X270164Y80723D01*
X270331Y81014D01*
X270414Y81306D01*
Y81598D01*
X270331Y81889D01*
X270206Y82139D01*
X270039Y82348D01*
G01X270414Y84306D02*
X267914D01*
X268414Y83806D01*
G01X270414D02*
Y84806D01*
G01X269372Y86514D02*
X269081Y86806D01*
X268914Y87056D01*
X268831Y87389D01*
X268914Y87681D01*
X269081Y87889D01*
X269331Y88056D01*
X269622Y88098D01*
X269872Y88056D01*
X270122Y87889D01*
X270331Y87639D01*
X270414Y87348D01*
X270331Y87014D01*
X270081Y86723D01*
X269706Y86556D01*
X269289Y86514D01*
X268747Y86598D01*
X268456Y86723D01*
X268164Y86931D01*
X267956Y87223D01*
X267914Y87514D01*
X267997Y87806D01*
X268206Y88014D01*
G01X256000Y130467D02*
X253500D01*
Y131467D01*
X253625Y131800D01*
X253917Y132050D01*
X254250Y132133D01*
X254583Y132050D01*
X254833Y131842D01*
X254958Y131467D01*
Y130467D01*
G01X253708Y135217D02*
X253583Y134967D01*
X253500Y134675D01*
Y134342D01*
X253625Y133967D01*
X253833Y133675D01*
X254083Y133467D01*
X254500Y133300D01*
X254875Y133258D01*
X255250Y133342D01*
X255500Y133467D01*
X255750Y133717D01*
X255917Y134008D01*
X256000Y134300D01*
Y134592D01*
X255917Y134883D01*
X255792Y135133D01*
X255625Y135342D01*
G01Y136383D02*
X255833Y136633D01*
X255958Y136925D01*
X256000Y137300D01*
X255917Y137675D01*
X255750Y137967D01*
X255458Y138175D01*
X255125Y138217D01*
X254792Y138133D01*
X254583Y137925D01*
X254417Y137633D01*
X254375Y137342D01*
X254417Y137050D01*
X254583Y136675D01*
X253500Y136800D01*
Y137925D01*
G01Y140300D02*
X253583Y139967D01*
X253792Y139717D01*
X254042Y139550D01*
X254375Y139425D01*
X254750Y139383D01*
X255125Y139425D01*
X255458Y139550D01*
X255708Y139717D01*
X255917Y139967D01*
X256000Y140300D01*
X255917Y140633D01*
X255708Y140883D01*
X255458Y141050D01*
X255125Y141175D01*
X254750Y141217D01*
X254375Y141175D01*
X254042Y141050D01*
X253792Y140883D01*
X253583Y140633D01*
X253500Y140300D01*
G01X251667Y107167D02*
Y109667D01*
X252667D01*
X253000Y109542D01*
X253250Y109250D01*
X253333Y108917D01*
X253250Y108584D01*
X253042Y108334D01*
X252667Y108209D01*
X251667D01*
G01X255750Y108417D02*
X256583D01*
Y107667D01*
X256333Y107417D01*
X256042Y107250D01*
X255625Y107167D01*
X255208Y107250D01*
X254917Y107417D01*
X254667Y107667D01*
X254500Y107959D01*
X254417Y108292D01*
Y108584D01*
X254500Y108834D01*
X254667Y109125D01*
X254917Y109375D01*
X255167Y109542D01*
X255500Y109667D01*
X255792D01*
X256125Y109584D01*
X256375Y109417D01*
G01X258500Y107167D02*
Y109667D01*
X258000Y109167D01*
G01Y107167D02*
X259000D01*
G01X275000Y130167D02*
X272500D01*
Y131167D01*
X272625Y131500D01*
X272917Y131750D01*
X273250Y131833D01*
X273583Y131750D01*
X273833Y131542D01*
X273958Y131167D01*
Y130167D01*
G01X275000Y133167D02*
X272500D01*
Y134208D01*
X272625Y134542D01*
X272792Y134750D01*
X273125Y134833D01*
X273458Y134750D01*
X273667Y134500D01*
X273792Y134208D01*
Y133167D01*
G01Y134208D02*
X275000Y134833D01*
G01X273958Y136208D02*
X273667Y136500D01*
X273500Y136750D01*
X273417Y137083D01*
X273500Y137375D01*
X273667Y137583D01*
X273917Y137750D01*
X274208Y137792D01*
X274458Y137750D01*
X274708Y137583D01*
X274917Y137333D01*
X275000Y137042D01*
X274917Y136708D01*
X274667Y136417D01*
X274292Y136250D01*
X273875Y136208D01*
X273333Y136292D01*
X273042Y136417D01*
X272750Y136625D01*
X272542Y136917D01*
X272500Y137208D01*
X272583Y137500D01*
X272792Y137708D01*
G01X275000Y140000D02*
X272500D01*
X273000Y139500D01*
G01X275000D02*
Y140500D01*
G01X232100Y192283D02*
X233892D01*
X234267Y192450D01*
X234517Y192783D01*
X234600Y193200D01*
X234517Y193617D01*
X234267Y193950D01*
X233892Y194117D01*
X232100D01*
G01X234600Y196200D02*
X232100D01*
X232600Y195700D01*
G01X234600D02*
Y196700D01*
G01X232100Y199200D02*
X232183Y198867D01*
X232392Y198617D01*
X232642Y198450D01*
X232975Y198325D01*
X233350Y198283D01*
X233725Y198325D01*
X234058Y198450D01*
X234308Y198617D01*
X234517Y198867D01*
X234600Y199200D01*
X234517Y199533D01*
X234308Y199783D01*
X234058Y199950D01*
X233725Y200075D01*
X233350Y200117D01*
X232975Y200075D01*
X232642Y199950D01*
X232392Y199783D01*
X232183Y199533D01*
X232100Y199200D01*
G01X235900Y170067D02*
X233400D01*
Y171108D01*
X233525Y171442D01*
X233692Y171650D01*
X234025Y171733D01*
X234358Y171650D01*
X234567Y171400D01*
X234692Y171108D01*
Y170067D01*
G01Y171108D02*
X235900Y171733D01*
G01Y173900D02*
X233400D01*
X233900Y173400D01*
G01X235900D02*
Y174400D01*
G01X234858Y176108D02*
X234567Y176400D01*
X234400Y176650D01*
X234317Y176983D01*
X234400Y177275D01*
X234567Y177483D01*
X234817Y177650D01*
X235108Y177692D01*
X235358Y177650D01*
X235608Y177483D01*
X235817Y177233D01*
X235900Y176942D01*
X235817Y176608D01*
X235567Y176317D01*
X235192Y176150D01*
X234775Y176108D01*
X234233Y176192D01*
X233942Y176317D01*
X233650Y176525D01*
X233442Y176817D01*
X233400Y177108D01*
X233483Y177400D01*
X233692Y177608D01*
G01X235608Y179192D02*
X235817Y179483D01*
X235900Y179817D01*
X235817Y180150D01*
X235567Y180442D01*
X235192Y180650D01*
X234817Y180733D01*
X234358D01*
X233983Y180650D01*
X233650Y180442D01*
X233483Y180192D01*
X233400Y179900D01*
X233483Y179567D01*
X233650Y179317D01*
X233900Y179150D01*
X234233Y179067D01*
X234525Y179150D01*
X234817Y179358D01*
X234983Y179608D01*
X235025Y179900D01*
X234942Y180233D01*
X234733Y180483D01*
X234358Y180733D01*
G01X232300Y170067D02*
X229800D01*
Y171108D01*
X229925Y171442D01*
X230092Y171650D01*
X230425Y171733D01*
X230758Y171650D01*
X230967Y171400D01*
X231092Y171108D01*
Y170067D01*
G01Y171108D02*
X232300Y171733D01*
G01Y173900D02*
X229800D01*
X230300Y173400D01*
G01X232300D02*
Y174400D01*
G01X231258Y176108D02*
X230967Y176400D01*
X230800Y176650D01*
X230717Y176983D01*
X230800Y177275D01*
X230967Y177483D01*
X231217Y177650D01*
X231508Y177692D01*
X231758Y177650D01*
X232008Y177483D01*
X232217Y177233D01*
X232300Y176942D01*
X232217Y176608D01*
X231967Y176317D01*
X231592Y176150D01*
X231175Y176108D01*
X230633Y176192D01*
X230342Y176317D01*
X230050Y176525D01*
X229842Y176817D01*
X229800Y177108D01*
X229883Y177400D01*
X230092Y177608D01*
G01X231925Y178983D02*
X232133Y179233D01*
X232258Y179525D01*
X232300Y179900D01*
X232217Y180275D01*
X232050Y180567D01*
X231758Y180775D01*
X231425Y180817D01*
X231092Y180733D01*
X230883Y180525D01*
X230717Y180233D01*
X230675Y179942D01*
X230717Y179650D01*
X230883Y179275D01*
X229800Y179400D01*
Y180525D01*
G01X238000Y171800D02*
X240500D01*
G01X238000Y170842D02*
Y172758D01*
G01X240500Y173967D02*
X238000D01*
Y174967D01*
X238125Y175300D01*
X238417Y175550D01*
X238750Y175633D01*
X239083Y175550D01*
X239333Y175342D01*
X239458Y174967D01*
Y173967D01*
G01X240500Y177800D02*
X238000D01*
X238500Y177300D01*
G01X240500D02*
Y178300D01*
G01X240125Y179883D02*
X240333Y180133D01*
X240458Y180425D01*
X240500Y180800D01*
X240417Y181175D01*
X240250Y181467D01*
X239958Y181675D01*
X239625Y181717D01*
X239292Y181633D01*
X239083Y181425D01*
X238917Y181133D01*
X238875Y180842D01*
X238917Y180550D01*
X239083Y180175D01*
X238000Y180300D01*
Y181425D01*
G01X238417Y183008D02*
X238167Y183258D01*
X238042Y183550D01*
X238000Y183883D01*
X238083Y184300D01*
X238292Y184592D01*
X238542Y184675D01*
X238792Y184633D01*
X239000Y184467D01*
X239417Y183633D01*
X239708Y183258D01*
X240125Y183008D01*
X240500Y182925D01*
Y184675D01*
G01X255100Y157767D02*
X252600D01*
Y158767D01*
X252725Y159100D01*
X253017Y159350D01*
X253350Y159433D01*
X253683Y159350D01*
X253933Y159142D01*
X254058Y158767D01*
Y157767D01*
G01X252600Y160683D02*
X254392D01*
X254767Y160850D01*
X255017Y161183D01*
X255100Y161600D01*
X255017Y162017D01*
X254767Y162350D01*
X254392Y162517D01*
X252600D01*
G01X254058Y163808D02*
X253767Y164100D01*
X253600Y164350D01*
X253517Y164683D01*
X253600Y164975D01*
X253767Y165183D01*
X254017Y165350D01*
X254308Y165392D01*
X254558Y165350D01*
X254808Y165183D01*
X255017Y164933D01*
X255100Y164642D01*
X255017Y164308D01*
X254767Y164017D01*
X254392Y163850D01*
X253975Y163808D01*
X253433Y163892D01*
X253142Y164017D01*
X252850Y164225D01*
X252642Y164517D01*
X252600Y164808D01*
X252683Y165100D01*
X252892Y165308D01*
G01X251300Y156067D02*
X248800D01*
Y157067D01*
X248925Y157400D01*
X249217Y157650D01*
X249550Y157733D01*
X249883Y157650D01*
X250133Y157442D01*
X250258Y157067D01*
Y156067D01*
G01X249008Y160817D02*
X248883Y160567D01*
X248800Y160275D01*
Y159942D01*
X248925Y159567D01*
X249133Y159275D01*
X249383Y159067D01*
X249800Y158900D01*
X250175Y158858D01*
X250550Y158942D01*
X250800Y159067D01*
X251050Y159317D01*
X251217Y159608D01*
X251300Y159900D01*
Y160192D01*
X251217Y160483D01*
X251092Y160733D01*
X250925Y160942D01*
G01X251300Y163400D02*
X248800D01*
X250592Y161858D01*
Y163942D01*
G01X251300Y165817D02*
X250758Y165900D01*
X250300Y166025D01*
X249883Y166192D01*
X249425Y166400D01*
X248800Y166733D01*
Y165067D01*
G01X237408Y222254D02*
X234908D01*
Y223295D01*
X235033Y223629D01*
X235200Y223837D01*
X235533Y223920D01*
X235866Y223837D01*
X236075Y223587D01*
X236200Y223295D01*
Y222254D01*
G01Y223295D02*
X237408Y223920D01*
G01Y226087D02*
X234908D01*
X235408Y225587D01*
G01X237408D02*
Y226587D01*
G01Y229004D02*
X236866Y229087D01*
X236408Y229212D01*
X235991Y229379D01*
X235533Y229587D01*
X234908Y229920D01*
Y228254D01*
G01Y232087D02*
X234991Y231754D01*
X235200Y231504D01*
X235450Y231337D01*
X235783Y231212D01*
X236158Y231170D01*
X236533Y231212D01*
X236866Y231337D01*
X237116Y231504D01*
X237325Y231754D01*
X237408Y232087D01*
X237325Y232420D01*
X237116Y232670D01*
X236866Y232837D01*
X236533Y232962D01*
X236158Y233004D01*
X235783Y232962D01*
X235450Y232837D01*
X235200Y232670D01*
X234991Y232420D01*
X234908Y232087D01*
G01X232943Y223797D02*
X230443D01*
Y224838D01*
X230568Y225172D01*
X230735Y225380D01*
X231068Y225463D01*
X231401Y225380D01*
X231610Y225130D01*
X231735Y224838D01*
Y223797D01*
G01Y224838D02*
X232943Y225463D01*
G01Y227630D02*
X230443D01*
X230943Y227130D01*
G01X232943D02*
Y228130D01*
G01X231901Y229838D02*
X231610Y230130D01*
X231443Y230380D01*
X231360Y230713D01*
X231443Y231005D01*
X231610Y231213D01*
X231860Y231380D01*
X232151Y231422D01*
X232401Y231380D01*
X232651Y231213D01*
X232860Y230963D01*
X232943Y230672D01*
X232860Y230338D01*
X232610Y230047D01*
X232235Y229880D01*
X231818Y229838D01*
X231276Y229922D01*
X230985Y230047D01*
X230693Y230255D01*
X230485Y230547D01*
X230443Y230838D01*
X230526Y231130D01*
X230735Y231338D01*
G01X232943Y233547D02*
X232401Y233630D01*
X231943Y233755D01*
X231526Y233922D01*
X231068Y234130D01*
X230443Y234463D01*
Y232797D01*
G01X240563Y344422D02*
X243063D01*
Y346088D01*
G01X240980Y347463D02*
X240730Y347713D01*
X240605Y348005D01*
X240563Y348338D01*
X240646Y348755D01*
X240855Y349047D01*
X241105Y349130D01*
X241355Y349088D01*
X241563Y348922D01*
X241980Y348088D01*
X242271Y347713D01*
X242688Y347463D01*
X243063Y347380D01*
Y349130D01*
G01X242771Y350547D02*
X242980Y350838D01*
X243063Y351172D01*
X242980Y351505D01*
X242730Y351797D01*
X242355Y352005D01*
X241980Y352088D01*
X241521D01*
X241146Y352005D01*
X240813Y351797D01*
X240646Y351547D01*
X240563Y351255D01*
X240646Y350922D01*
X240813Y350672D01*
X241063Y350505D01*
X241396Y350422D01*
X241688Y350505D01*
X241980Y350713D01*
X242146Y350963D01*
X242188Y351255D01*
X242105Y351588D01*
X241896Y351838D01*
X241521Y352088D01*
G01X265200Y392783D02*
X266992D01*
X267367Y392950D01*
X267617Y393283D01*
X267700Y393700D01*
X267617Y394117D01*
X267367Y394450D01*
X266992Y394617D01*
X265200D01*
G01X267700Y396700D02*
X265200D01*
X265700Y396200D01*
G01X267700D02*
Y397200D01*
G01X267200Y398783D02*
X267492Y399033D01*
X267658Y399367D01*
X267700Y399742D01*
X267658Y400075D01*
X267450Y400408D01*
X267200Y400617D01*
X266950Y400658D01*
X266658Y400575D01*
X266450Y400283D01*
X266367Y399992D01*
Y399617D01*
G01Y399992D02*
X266242Y400242D01*
X266033Y400450D01*
X265783Y400533D01*
X265533Y400450D01*
X265325Y400242D01*
X265200Y399867D01*
X265242Y399492D01*
X265408Y399117D01*
G01X268908Y391617D02*
X268783Y391367D01*
X268700Y391075D01*
Y390742D01*
X268825Y390367D01*
X269033Y390075D01*
X269283Y389867D01*
X269700Y389700D01*
X270075Y389658D01*
X270450Y389742D01*
X270700Y389867D01*
X270950Y390117D01*
X271117Y390408D01*
X271200Y390700D01*
Y390992D01*
X271117Y391283D01*
X270992Y391533D01*
X270825Y391742D01*
G01X269117Y392908D02*
X268867Y393158D01*
X268742Y393450D01*
X268700Y393783D01*
X268783Y394200D01*
X268992Y394492D01*
X269242Y394575D01*
X269492Y394533D01*
X269700Y394367D01*
X270117Y393533D01*
X270408Y393158D01*
X270825Y392908D01*
X271200Y392825D01*
Y394575D01*
G01X270700Y395783D02*
X270992Y396033D01*
X271158Y396367D01*
X271200Y396742D01*
X271158Y397075D01*
X270950Y397408D01*
X270700Y397617D01*
X270450Y397658D01*
X270158Y397575D01*
X269950Y397283D01*
X269867Y396992D01*
Y396617D01*
G01Y396992D02*
X269742Y397242D01*
X269533Y397450D01*
X269283Y397533D01*
X269033Y397450D01*
X268825Y397242D01*
X268700Y396867D01*
X268742Y396492D01*
X268908Y396117D01*
G01X270908Y398992D02*
X271117Y399283D01*
X271200Y399617D01*
X271117Y399950D01*
X270867Y400242D01*
X270492Y400450D01*
X270117Y400533D01*
X269658D01*
X269283Y400450D01*
X268950Y400242D01*
X268783Y399992D01*
X268700Y399700D01*
X268783Y399367D01*
X268950Y399117D01*
X269200Y398950D01*
X269533Y398867D01*
X269825Y398950D01*
X270117Y399158D01*
X270283Y399408D01*
X270325Y399700D01*
X270242Y400033D01*
X270033Y400283D01*
X269658Y400533D01*
G01X268317Y404692D02*
X268067Y404817D01*
X267775Y404900D01*
X267442D01*
X267067Y404775D01*
X266775Y404567D01*
X266567Y404317D01*
X266400Y403900D01*
X266358Y403525D01*
X266442Y403150D01*
X266567Y402900D01*
X266817Y402650D01*
X267108Y402483D01*
X267400Y402400D01*
X267692D01*
X267983Y402483D01*
X268233Y402608D01*
X268442Y402775D01*
G01X269608Y404483D02*
X269858Y404733D01*
X270150Y404858D01*
X270483Y404900D01*
X270900Y404817D01*
X271192Y404608D01*
X271275Y404358D01*
X271233Y404108D01*
X271067Y403900D01*
X270233Y403483D01*
X269858Y403192D01*
X269608Y402775D01*
X269525Y402400D01*
X271275D01*
G01X272483Y402900D02*
X272733Y402608D01*
X273067Y402442D01*
X273442Y402400D01*
X273775Y402442D01*
X274108Y402650D01*
X274317Y402900D01*
X274358Y403150D01*
X274275Y403442D01*
X273983Y403650D01*
X273692Y403733D01*
X273317D01*
G01X273692D02*
X273942Y403858D01*
X274150Y404067D01*
X274233Y404317D01*
X274150Y404567D01*
X273942Y404775D01*
X273567Y404900D01*
X273192Y404858D01*
X272817Y404692D01*
G01X276400Y402400D02*
X276692Y402442D01*
X277025Y402567D01*
X277233Y402775D01*
X277317Y403067D01*
X277233Y403358D01*
X276983Y403608D01*
X276608Y403733D01*
X276192D01*
X275942Y403817D01*
X275733Y404025D01*
X275650Y404317D01*
X275775Y404608D01*
X276067Y404817D01*
X276400Y404900D01*
X276733Y404817D01*
X277025Y404608D01*
X277150Y404317D01*
X277067Y404025D01*
X276858Y403817D01*
X276608Y403733D01*
X276192D01*
X275817Y403608D01*
X275567Y403358D01*
X275483Y403067D01*
X275567Y402775D01*
X275775Y402567D01*
X276108Y402442D01*
X276400Y402400D01*
G01X266517Y383892D02*
X266267Y384017D01*
X265975Y384100D01*
X265642D01*
X265267Y383975D01*
X264975Y383767D01*
X264767Y383517D01*
X264600Y383100D01*
X264558Y382725D01*
X264642Y382350D01*
X264767Y382100D01*
X265017Y381850D01*
X265308Y381683D01*
X265600Y381600D01*
X265892D01*
X266183Y381683D01*
X266433Y381808D01*
X266642Y381975D01*
G01X267808Y383683D02*
X268058Y383933D01*
X268350Y384058D01*
X268683Y384100D01*
X269100Y384017D01*
X269392Y383808D01*
X269475Y383558D01*
X269433Y383308D01*
X269267Y383100D01*
X268433Y382683D01*
X268058Y382392D01*
X267808Y381975D01*
X267725Y381600D01*
X269475D01*
G01X270683Y382100D02*
X270933Y381808D01*
X271267Y381642D01*
X271642Y381600D01*
X271975Y381642D01*
X272308Y381850D01*
X272517Y382100D01*
X272558Y382350D01*
X272475Y382642D01*
X272183Y382850D01*
X271892Y382933D01*
X271517D01*
G01X271892D02*
X272142Y383058D01*
X272350Y383267D01*
X272433Y383517D01*
X272350Y383767D01*
X272142Y383975D01*
X271767Y384100D01*
X271392Y384058D01*
X271017Y383892D01*
G01X274517Y381600D02*
X274600Y382142D01*
X274725Y382600D01*
X274892Y383017D01*
X275100Y383475D01*
X275433Y384100D01*
X273767D01*
G01X250338Y375694D02*
X250088Y375819D01*
X249796Y375902D01*
X249463D01*
X249088Y375777D01*
X248796Y375569D01*
X248588Y375319D01*
X248421Y374902D01*
X248379Y374527D01*
X248463Y374152D01*
X248588Y373902D01*
X248838Y373652D01*
X249129Y373485D01*
X249421Y373402D01*
X249713D01*
X250004Y373485D01*
X250254Y373610D01*
X250463Y373777D01*
G01X251629Y375485D02*
X251879Y375735D01*
X252171Y375860D01*
X252504Y375902D01*
X252921Y375819D01*
X253213Y375610D01*
X253296Y375360D01*
X253254Y375110D01*
X253088Y374902D01*
X252254Y374485D01*
X251879Y374194D01*
X251629Y373777D01*
X251546Y373402D01*
X253296D01*
G01X255338D02*
X255421Y373944D01*
X255546Y374402D01*
X255713Y374819D01*
X255921Y375277D01*
X256254Y375902D01*
X254588D01*
G01X250313Y372215D02*
X250063Y372340D01*
X249771Y372423D01*
X249438D01*
X249063Y372298D01*
X248771Y372090D01*
X248563Y371840D01*
X248396Y371423D01*
X248354Y371048D01*
X248438Y370673D01*
X248563Y370423D01*
X248813Y370173D01*
X249104Y370006D01*
X249396Y369923D01*
X249688D01*
X249979Y370006D01*
X250229Y370131D01*
X250438Y370298D01*
G01X251604Y372006D02*
X251854Y372256D01*
X252146Y372381D01*
X252479Y372423D01*
X252896Y372340D01*
X253188Y372131D01*
X253271Y371881D01*
X253229Y371631D01*
X253063Y371423D01*
X252229Y371006D01*
X251854Y370715D01*
X251604Y370298D01*
X251521Y369923D01*
X253271D01*
G01X254604Y370965D02*
X254896Y371256D01*
X255146Y371423D01*
X255479Y371506D01*
X255771Y371423D01*
X255979Y371256D01*
X256146Y371006D01*
X256188Y370715D01*
X256146Y370465D01*
X255979Y370215D01*
X255729Y370006D01*
X255438Y369923D01*
X255104Y370006D01*
X254813Y370256D01*
X254646Y370631D01*
X254604Y371048D01*
X254688Y371590D01*
X254813Y371881D01*
X255021Y372173D01*
X255313Y372381D01*
X255604Y372423D01*
X255896Y372340D01*
X256104Y372131D01*
G01X254114Y365461D02*
X253864Y365586D01*
X253572Y365669D01*
X253239D01*
X252864Y365544D01*
X252572Y365336D01*
X252364Y365086D01*
X252197Y364669D01*
X252155Y364294D01*
X252239Y363919D01*
X252364Y363669D01*
X252614Y363419D01*
X252905Y363252D01*
X253197Y363169D01*
X253489D01*
X253780Y363252D01*
X254030Y363377D01*
X254239Y363544D01*
G01X255405Y365252D02*
X255655Y365502D01*
X255947Y365627D01*
X256280Y365669D01*
X256697Y365586D01*
X256989Y365377D01*
X257072Y365127D01*
X257030Y364877D01*
X256864Y364669D01*
X256030Y364252D01*
X255655Y363961D01*
X255405Y363544D01*
X255322Y363169D01*
X257072D01*
G01X258280Y363544D02*
X258530Y363336D01*
X258822Y363211D01*
X259197Y363169D01*
X259572Y363252D01*
X259864Y363419D01*
X260072Y363711D01*
X260114Y364044D01*
X260030Y364377D01*
X259822Y364586D01*
X259530Y364752D01*
X259239Y364794D01*
X258947Y364752D01*
X258572Y364586D01*
X258697Y365669D01*
X259822D01*
G01X254077Y361948D02*
X253827Y362073D01*
X253535Y362156D01*
X253202D01*
X252827Y362031D01*
X252535Y361823D01*
X252327Y361573D01*
X252160Y361156D01*
X252118Y360781D01*
X252202Y360406D01*
X252327Y360156D01*
X252577Y359906D01*
X252868Y359739D01*
X253160Y359656D01*
X253452D01*
X253743Y359739D01*
X253993Y359864D01*
X254202Y360031D01*
G01X255368Y361739D02*
X255618Y361989D01*
X255910Y362114D01*
X256243Y362156D01*
X256660Y362073D01*
X256952Y361864D01*
X257035Y361614D01*
X256993Y361364D01*
X256827Y361156D01*
X255993Y360739D01*
X255618Y360448D01*
X255368Y360031D01*
X255285Y359656D01*
X257035D01*
G01X259660D02*
Y362156D01*
X258118Y360364D01*
X260202D01*
G01X231352Y353873D02*
X231227Y353623D01*
X231144Y353331D01*
Y352998D01*
X231269Y352623D01*
X231477Y352331D01*
X231727Y352123D01*
X232144Y351956D01*
X232519Y351914D01*
X232894Y351998D01*
X233144Y352123D01*
X233394Y352373D01*
X233561Y352664D01*
X233644Y352956D01*
Y353248D01*
X233561Y353539D01*
X233436Y353789D01*
X233269Y353998D01*
G01X231561Y355164D02*
X231311Y355414D01*
X231186Y355706D01*
X231144Y356039D01*
X231227Y356456D01*
X231436Y356748D01*
X231686Y356831D01*
X231936Y356789D01*
X232144Y356623D01*
X232561Y355789D01*
X232852Y355414D01*
X233269Y355164D01*
X233644Y355081D01*
Y356831D01*
G01X233144Y358039D02*
X233436Y358289D01*
X233602Y358623D01*
X233644Y358998D01*
X233602Y359331D01*
X233394Y359664D01*
X233144Y359873D01*
X232894Y359914D01*
X232602Y359831D01*
X232394Y359539D01*
X232311Y359248D01*
Y358873D01*
G01Y359248D02*
X232186Y359498D01*
X231977Y359706D01*
X231727Y359789D01*
X231477Y359706D01*
X231269Y359498D01*
X231144Y359123D01*
X231186Y358748D01*
X231352Y358373D01*
G01X227208Y354117D02*
X227083Y353867D01*
X227000Y353575D01*
Y353242D01*
X227125Y352867D01*
X227333Y352575D01*
X227583Y352367D01*
X228000Y352200D01*
X228375Y352158D01*
X228750Y352242D01*
X229000Y352367D01*
X229250Y352617D01*
X229417Y352908D01*
X229500Y353200D01*
Y353492D01*
X229417Y353783D01*
X229292Y354033D01*
X229125Y354242D01*
G01X227417Y355408D02*
X227167Y355658D01*
X227042Y355950D01*
X227000Y356283D01*
X227083Y356700D01*
X227292Y356992D01*
X227542Y357075D01*
X227792Y357033D01*
X228000Y356867D01*
X228417Y356033D01*
X228708Y355658D01*
X229125Y355408D01*
X229500Y355325D01*
Y357075D01*
G01X227417Y358408D02*
X227167Y358658D01*
X227042Y358950D01*
X227000Y359283D01*
X227083Y359700D01*
X227292Y359992D01*
X227542Y360075D01*
X227792Y360033D01*
X228000Y359867D01*
X228417Y359033D01*
X228708Y358658D01*
X229125Y358408D01*
X229500Y358325D01*
Y360075D01*
G01X278800Y416800D02*
X281300D01*
G01X278800Y415842D02*
Y417758D01*
G01X279008Y420717D02*
X278883Y420467D01*
X278800Y420175D01*
Y419842D01*
X278925Y419467D01*
X279133Y419175D01*
X279383Y418967D01*
X279800Y418800D01*
X280175Y418758D01*
X280550Y418842D01*
X280800Y418967D01*
X281050Y419217D01*
X281217Y419508D01*
X281300Y419800D01*
Y420092D01*
X281217Y420383D01*
X281092Y420633D01*
X280925Y420842D01*
G01X279217Y422008D02*
X278967Y422258D01*
X278842Y422550D01*
X278800Y422883D01*
X278883Y423300D01*
X279092Y423592D01*
X279342Y423675D01*
X279592Y423633D01*
X279800Y423467D01*
X280217Y422633D01*
X280508Y422258D01*
X280925Y422008D01*
X281300Y421925D01*
Y423675D01*
G01X251800Y411767D02*
X249300D01*
Y412808D01*
X249425Y413142D01*
X249592Y413350D01*
X249925Y413433D01*
X250258Y413350D01*
X250467Y413100D01*
X250592Y412808D01*
Y411767D01*
G01Y412808D02*
X251800Y413433D01*
G01X251300Y414683D02*
X251592Y414933D01*
X251758Y415267D01*
X251800Y415642D01*
X251758Y415975D01*
X251550Y416308D01*
X251300Y416517D01*
X251050Y416558D01*
X250758Y416475D01*
X250550Y416183D01*
X250467Y415892D01*
Y415517D01*
G01Y415892D02*
X250342Y416142D01*
X250133Y416350D01*
X249883Y416433D01*
X249633Y416350D01*
X249425Y416142D01*
X249300Y415767D01*
X249342Y415392D01*
X249508Y415017D01*
G01X249717Y417808D02*
X249467Y418058D01*
X249342Y418350D01*
X249300Y418683D01*
X249383Y419100D01*
X249592Y419392D01*
X249842Y419475D01*
X250092Y419433D01*
X250300Y419267D01*
X250717Y418433D01*
X251008Y418058D01*
X251425Y417808D01*
X251800Y417725D01*
Y419475D01*
G01Y421600D02*
X249300D01*
X249800Y421100D01*
G01X251800D02*
Y422100D01*
G01X244300Y411767D02*
X241800D01*
Y412808D01*
X241925Y413142D01*
X242092Y413350D01*
X242425Y413433D01*
X242758Y413350D01*
X242967Y413100D01*
X243092Y412808D01*
Y411767D01*
G01Y412808D02*
X244300Y413433D01*
G01X243800Y414683D02*
X244092Y414933D01*
X244258Y415267D01*
X244300Y415642D01*
X244258Y415975D01*
X244050Y416308D01*
X243800Y416517D01*
X243550Y416558D01*
X243258Y416475D01*
X243050Y416183D01*
X242967Y415892D01*
Y415517D01*
G01Y415892D02*
X242842Y416142D01*
X242633Y416350D01*
X242383Y416433D01*
X242133Y416350D01*
X241925Y416142D01*
X241800Y415767D01*
X241842Y415392D01*
X242008Y415017D01*
G01X243925Y417683D02*
X244133Y417933D01*
X244258Y418225D01*
X244300Y418600D01*
X244217Y418975D01*
X244050Y419267D01*
X243758Y419475D01*
X243425Y419517D01*
X243092Y419433D01*
X242883Y419225D01*
X242717Y418933D01*
X242675Y418642D01*
X242717Y418350D01*
X242883Y417975D01*
X241800Y418100D01*
Y419225D01*
G01X244300Y421517D02*
X243758Y421600D01*
X243300Y421725D01*
X242883Y421892D01*
X242425Y422100D01*
X241800Y422433D01*
Y420767D01*
G01X248100Y411767D02*
X245600D01*
Y412808D01*
X245725Y413142D01*
X245892Y413350D01*
X246225Y413433D01*
X246558Y413350D01*
X246767Y413100D01*
X246892Y412808D01*
Y411767D01*
G01Y412808D02*
X248100Y413433D01*
G01X247600Y414683D02*
X247892Y414933D01*
X248058Y415267D01*
X248100Y415642D01*
X248058Y415975D01*
X247850Y416308D01*
X247600Y416517D01*
X247350Y416558D01*
X247058Y416475D01*
X246850Y416183D01*
X246767Y415892D01*
Y415517D01*
G01Y415892D02*
X246642Y416142D01*
X246433Y416350D01*
X246183Y416433D01*
X245933Y416350D01*
X245725Y416142D01*
X245600Y415767D01*
X245642Y415392D01*
X245808Y415017D01*
G01X247725Y417683D02*
X247933Y417933D01*
X248058Y418225D01*
X248100Y418600D01*
X248017Y418975D01*
X247850Y419267D01*
X247558Y419475D01*
X247225Y419517D01*
X246892Y419433D01*
X246683Y419225D01*
X246517Y418933D01*
X246475Y418642D01*
X246517Y418350D01*
X246683Y417975D01*
X245600Y418100D01*
Y419225D01*
G01X248100Y421600D02*
X248058Y421892D01*
X247933Y422225D01*
X247725Y422433D01*
X247433Y422517D01*
X247142Y422433D01*
X246892Y422183D01*
X246767Y421808D01*
Y421392D01*
X246683Y421142D01*
X246475Y420933D01*
X246183Y420850D01*
X245892Y420975D01*
X245683Y421267D01*
X245600Y421600D01*
X245683Y421933D01*
X245892Y422225D01*
X246183Y422350D01*
X246475Y422267D01*
X246683Y422058D01*
X246767Y421808D01*
Y421392D01*
X246892Y421017D01*
X247142Y420767D01*
X247433Y420683D01*
X247725Y420767D01*
X247933Y420975D01*
X248058Y421308D01*
X248100Y421600D01*
G01X264767Y385600D02*
Y388100D01*
X265808D01*
X266142Y387975D01*
X266350Y387808D01*
X266433Y387475D01*
X266350Y387142D01*
X266100Y386933D01*
X265808Y386808D01*
X264767D01*
G01X265808D02*
X266433Y385600D01*
G01X268600D02*
Y388100D01*
X268100Y387600D01*
G01Y385600D02*
X269100D01*
G01X270892Y385892D02*
X271183Y385683D01*
X271517Y385600D01*
X271850Y385683D01*
X272142Y385933D01*
X272350Y386308D01*
X272433Y386683D01*
Y387142D01*
X272350Y387517D01*
X272142Y387850D01*
X271892Y388017D01*
X271600Y388100D01*
X271267Y388017D01*
X271017Y387850D01*
X270850Y387600D01*
X270767Y387267D01*
X270850Y386975D01*
X271058Y386683D01*
X271308Y386517D01*
X271600Y386475D01*
X271933Y386558D01*
X272183Y386767D01*
X272433Y387142D01*
G01X274600Y385600D02*
Y388100D01*
X274100Y387600D01*
G01Y385600D02*
X275100D01*
G01X262900Y377867D02*
X260400D01*
Y378908D01*
X260525Y379242D01*
X260692Y379450D01*
X261025Y379533D01*
X261358Y379450D01*
X261567Y379200D01*
X261692Y378908D01*
Y377867D01*
G01Y378908D02*
X262900Y379533D01*
G01Y381700D02*
X260400D01*
X260900Y381200D01*
G01X262900D02*
Y382200D01*
G01Y384700D02*
X262858Y384992D01*
X262733Y385325D01*
X262525Y385533D01*
X262233Y385617D01*
X261942Y385533D01*
X261692Y385283D01*
X261567Y384908D01*
Y384492D01*
X261483Y384242D01*
X261275Y384033D01*
X260983Y383950D01*
X260692Y384075D01*
X260483Y384367D01*
X260400Y384700D01*
X260483Y385033D01*
X260692Y385325D01*
X260983Y385450D01*
X261275Y385367D01*
X261483Y385158D01*
X261567Y384908D01*
Y384492D01*
X261692Y384117D01*
X261942Y383867D01*
X262233Y383783D01*
X262525Y383867D01*
X262733Y384075D01*
X262858Y384408D01*
X262900Y384700D01*
G01Y387700D02*
X262858Y387992D01*
X262733Y388325D01*
X262525Y388533D01*
X262233Y388617D01*
X261942Y388533D01*
X261692Y388283D01*
X261567Y387908D01*
Y387492D01*
X261483Y387242D01*
X261275Y387033D01*
X260983Y386950D01*
X260692Y387075D01*
X260483Y387367D01*
X260400Y387700D01*
X260483Y388033D01*
X260692Y388325D01*
X260983Y388450D01*
X261275Y388367D01*
X261483Y388158D01*
X261567Y387908D01*
Y387492D01*
X261692Y387117D01*
X261942Y386867D01*
X262233Y386783D01*
X262525Y386867D01*
X262733Y387075D01*
X262858Y387408D01*
X262900Y387700D01*
G01X235367Y408100D02*
Y410600D01*
X236408D01*
X236742Y410475D01*
X236950Y410308D01*
X237033Y409975D01*
X236950Y409642D01*
X236700Y409433D01*
X236408Y409308D01*
X235367D01*
G01X236408D02*
X237033Y408100D01*
G01X239200D02*
Y410600D01*
X238700Y410100D01*
G01Y408100D02*
X239700D01*
G01X241492Y408392D02*
X241783Y408183D01*
X242117Y408100D01*
X242450Y408183D01*
X242742Y408433D01*
X242950Y408808D01*
X243033Y409183D01*
Y409642D01*
X242950Y410017D01*
X242742Y410350D01*
X242492Y410517D01*
X242200Y410600D01*
X241867Y410517D01*
X241617Y410350D01*
X241450Y410100D01*
X241367Y409767D01*
X241450Y409475D01*
X241658Y409183D01*
X241908Y409017D01*
X242200Y408975D01*
X242533Y409058D01*
X242783Y409267D01*
X243033Y409642D01*
G01X244283Y408600D02*
X244533Y408308D01*
X244867Y408142D01*
X245242Y408100D01*
X245575Y408142D01*
X245908Y408350D01*
X246117Y408600D01*
X246158Y408850D01*
X246075Y409142D01*
X245783Y409350D01*
X245492Y409433D01*
X245117D01*
G01X245492D02*
X245742Y409558D01*
X245950Y409767D01*
X246033Y410017D01*
X245950Y410267D01*
X245742Y410475D01*
X245367Y410600D01*
X244992Y410558D01*
X244617Y410392D01*
G01X266967Y406000D02*
Y408500D01*
X268008D01*
X268342Y408375D01*
X268550Y408208D01*
X268633Y407875D01*
X268550Y407542D01*
X268300Y407333D01*
X268008Y407208D01*
X266967D01*
G01X268008D02*
X268633Y406000D01*
G01X270800D02*
Y408500D01*
X270300Y408000D01*
G01Y406000D02*
X271300D01*
G01X273800D02*
X274092Y406042D01*
X274425Y406167D01*
X274633Y406375D01*
X274717Y406667D01*
X274633Y406958D01*
X274383Y407208D01*
X274008Y407333D01*
X273592D01*
X273342Y407417D01*
X273133Y407625D01*
X273050Y407917D01*
X273175Y408208D01*
X273467Y408417D01*
X273800Y408500D01*
X274133Y408417D01*
X274425Y408208D01*
X274550Y407917D01*
X274467Y407625D01*
X274258Y407417D01*
X274008Y407333D01*
X273592D01*
X273217Y407208D01*
X272967Y406958D01*
X272883Y406667D01*
X272967Y406375D01*
X273175Y406167D01*
X273508Y406042D01*
X273800Y406000D01*
G01X276800D02*
Y408500D01*
X276300Y408000D01*
G01Y406000D02*
X277300D01*
G01X263000Y391767D02*
X260500D01*
Y392808D01*
X260625Y393142D01*
X260792Y393350D01*
X261125Y393433D01*
X261458Y393350D01*
X261667Y393100D01*
X261792Y392808D01*
Y391767D01*
G01Y392808D02*
X263000Y393433D01*
G01Y395600D02*
X260500D01*
X261000Y395100D01*
G01X263000D02*
Y396100D01*
G01Y398600D02*
X262958Y398892D01*
X262833Y399225D01*
X262625Y399433D01*
X262333Y399517D01*
X262042Y399433D01*
X261792Y399183D01*
X261667Y398808D01*
Y398392D01*
X261583Y398142D01*
X261375Y397933D01*
X261083Y397850D01*
X260792Y397975D01*
X260583Y398267D01*
X260500Y398600D01*
X260583Y398933D01*
X260792Y399225D01*
X261083Y399350D01*
X261375Y399267D01*
X261583Y399058D01*
X261667Y398808D01*
Y398392D01*
X261792Y398017D01*
X262042Y397767D01*
X262333Y397683D01*
X262625Y397767D01*
X262833Y397975D01*
X262958Y398308D01*
X263000Y398600D01*
G01Y401517D02*
X262458Y401600D01*
X262000Y401725D01*
X261583Y401892D01*
X261125Y402100D01*
X260500Y402433D01*
Y400767D01*
G01X259300Y391767D02*
X256800D01*
Y392808D01*
X256925Y393142D01*
X257092Y393350D01*
X257425Y393433D01*
X257758Y393350D01*
X257967Y393100D01*
X258092Y392808D01*
Y391767D01*
G01Y392808D02*
X259300Y393433D01*
G01Y395600D02*
X256800D01*
X257300Y395100D01*
G01X259300D02*
Y396100D01*
G01Y398600D02*
X259258Y398892D01*
X259133Y399225D01*
X258925Y399433D01*
X258633Y399517D01*
X258342Y399433D01*
X258092Y399183D01*
X257967Y398808D01*
Y398392D01*
X257883Y398142D01*
X257675Y397933D01*
X257383Y397850D01*
X257092Y397975D01*
X256883Y398267D01*
X256800Y398600D01*
X256883Y398933D01*
X257092Y399225D01*
X257383Y399350D01*
X257675Y399267D01*
X257883Y399058D01*
X257967Y398808D01*
Y398392D01*
X258092Y398017D01*
X258342Y397767D01*
X258633Y397683D01*
X258925Y397767D01*
X259133Y397975D01*
X259258Y398308D01*
X259300Y398600D01*
G01X256800Y401600D02*
X256883Y401267D01*
X257092Y401017D01*
X257342Y400850D01*
X257675Y400725D01*
X258050Y400683D01*
X258425Y400725D01*
X258758Y400850D01*
X259008Y401017D01*
X259217Y401267D01*
X259300Y401600D01*
X259217Y401933D01*
X259008Y402183D01*
X258758Y402350D01*
X258425Y402475D01*
X258050Y402517D01*
X257675Y402475D01*
X257342Y402350D01*
X257092Y402183D01*
X256883Y401933D01*
X256800Y401600D01*
G01X220567Y375300D02*
Y377800D01*
X221608D01*
X221942Y377675D01*
X222150Y377508D01*
X222233Y377175D01*
X222150Y376842D01*
X221900Y376633D01*
X221608Y376508D01*
X220567D01*
G01X221608D02*
X222233Y375300D01*
G01X223692Y375592D02*
X223983Y375383D01*
X224317Y375300D01*
X224650Y375383D01*
X224942Y375633D01*
X225150Y376008D01*
X225233Y376383D01*
Y376842D01*
X225150Y377217D01*
X224942Y377550D01*
X224692Y377717D01*
X224400Y377800D01*
X224067Y377717D01*
X223817Y377550D01*
X223650Y377300D01*
X223567Y376967D01*
X223650Y376675D01*
X223858Y376383D01*
X224108Y376217D01*
X224400Y376175D01*
X224733Y376258D01*
X224983Y376467D01*
X225233Y376842D01*
G01X226608Y377383D02*
X226858Y377633D01*
X227150Y377758D01*
X227483Y377800D01*
X227900Y377717D01*
X228192Y377508D01*
X228275Y377258D01*
X228233Y377008D01*
X228067Y376800D01*
X227233Y376383D01*
X226858Y376092D01*
X226608Y375675D01*
X226525Y375300D01*
X228275D01*
G01X256500Y379767D02*
X259000D01*
Y381433D01*
G01X257958Y382808D02*
X257667Y383100D01*
X257500Y383350D01*
X257417Y383683D01*
X257500Y383975D01*
X257667Y384183D01*
X257917Y384350D01*
X258208Y384392D01*
X258458Y384350D01*
X258708Y384183D01*
X258917Y383933D01*
X259000Y383642D01*
X258917Y383308D01*
X258667Y383017D01*
X258292Y382850D01*
X257875Y382808D01*
X257333Y382892D01*
X257042Y383017D01*
X256750Y383225D01*
X256542Y383517D01*
X256500Y383808D01*
X256583Y384100D01*
X256792Y384308D01*
G01X258625Y385683D02*
X258833Y385933D01*
X258958Y386225D01*
X259000Y386600D01*
X258917Y386975D01*
X258750Y387267D01*
X258458Y387475D01*
X258125Y387517D01*
X257792Y387433D01*
X257583Y387225D01*
X257417Y386933D01*
X257375Y386642D01*
X257417Y386350D01*
X257583Y385975D01*
X256500Y386100D01*
Y387225D01*
G01X222967Y371200D02*
Y368700D01*
X224633D01*
G01X225883Y369200D02*
X226133Y368908D01*
X226467Y368742D01*
X226842Y368700D01*
X227175Y368742D01*
X227508Y368950D01*
X227717Y369200D01*
X227758Y369450D01*
X227675Y369742D01*
X227383Y369950D01*
X227092Y370033D01*
X226717D01*
G01X227092D02*
X227342Y370158D01*
X227550Y370367D01*
X227633Y370617D01*
X227550Y370867D01*
X227342Y371075D01*
X226967Y371200D01*
X226592Y371158D01*
X226217Y370992D01*
G01X229800Y371200D02*
X229467Y371117D01*
X229217Y370908D01*
X229050Y370658D01*
X228925Y370325D01*
X228883Y369950D01*
X228925Y369575D01*
X229050Y369242D01*
X229217Y368992D01*
X229467Y368783D01*
X229800Y368700D01*
X230133Y368783D01*
X230383Y368992D01*
X230550Y369242D01*
X230675Y369575D01*
X230717Y369950D01*
X230675Y370325D01*
X230550Y370658D01*
X230383Y370908D01*
X230133Y371117D01*
X229800Y371200D01*
G01X246167Y369000D02*
Y366500D01*
X247833D01*
G01X249208Y368583D02*
X249458Y368833D01*
X249750Y368958D01*
X250083Y369000D01*
X250500Y368917D01*
X250792Y368708D01*
X250875Y368458D01*
X250833Y368208D01*
X250667Y368000D01*
X249833Y367583D01*
X249458Y367292D01*
X249208Y366875D01*
X249125Y366500D01*
X250875D01*
G01X253000D02*
X253292Y366542D01*
X253625Y366667D01*
X253833Y366875D01*
X253917Y367167D01*
X253833Y367458D01*
X253583Y367708D01*
X253208Y367833D01*
X252792D01*
X252542Y367917D01*
X252333Y368125D01*
X252250Y368417D01*
X252375Y368708D01*
X252667Y368917D01*
X253000Y369000D01*
X253333Y368917D01*
X253625Y368708D01*
X253750Y368417D01*
X253667Y368125D01*
X253458Y367917D01*
X253208Y367833D01*
X252792D01*
X252417Y367708D01*
X252167Y367458D01*
X252083Y367167D01*
X252167Y366875D01*
X252375Y366667D01*
X252708Y366542D01*
X253000Y366500D01*
G01X232000Y362167D02*
X234500D01*
Y363833D01*
G01X232417Y365208D02*
X232167Y365458D01*
X232042Y365750D01*
X232000Y366083D01*
X232083Y366500D01*
X232292Y366792D01*
X232542Y366875D01*
X232792Y366833D01*
X233000Y366667D01*
X233417Y365833D01*
X233708Y365458D01*
X234125Y365208D01*
X234500Y365125D01*
Y366875D01*
G01Y368917D02*
X233958Y369000D01*
X233500Y369125D01*
X233083Y369292D01*
X232625Y369500D01*
X232000Y369833D01*
Y368167D01*
G01X231400Y371767D02*
X233900D01*
Y373433D01*
G01X231817Y374808D02*
X231567Y375058D01*
X231442Y375350D01*
X231400Y375683D01*
X231483Y376100D01*
X231692Y376392D01*
X231942Y376475D01*
X232192Y376433D01*
X232400Y376267D01*
X232817Y375433D01*
X233108Y375058D01*
X233525Y374808D01*
X233900Y374725D01*
Y376475D01*
G01X232858Y377808D02*
X232567Y378100D01*
X232400Y378350D01*
X232317Y378683D01*
X232400Y378975D01*
X232567Y379183D01*
X232817Y379350D01*
X233108Y379392D01*
X233358Y379350D01*
X233608Y379183D01*
X233817Y378933D01*
X233900Y378642D01*
X233817Y378308D01*
X233567Y378017D01*
X233192Y377850D01*
X232775Y377808D01*
X232233Y377892D01*
X231942Y378017D01*
X231650Y378225D01*
X231442Y378517D01*
X231400Y378808D01*
X231483Y379100D01*
X231692Y379308D01*
G01X220100Y406467D02*
X222600D01*
Y408133D01*
G01X222225Y409383D02*
X222433Y409633D01*
X222558Y409925D01*
X222600Y410300D01*
X222517Y410675D01*
X222350Y410967D01*
X222058Y411175D01*
X221725Y411217D01*
X221392Y411133D01*
X221183Y410925D01*
X221017Y410633D01*
X220975Y410342D01*
X221017Y410050D01*
X221183Y409675D01*
X220100Y409800D01*
Y410925D01*
G01X222600Y413217D02*
X222058Y413300D01*
X221600Y413425D01*
X221183Y413592D01*
X220725Y413800D01*
X220100Y414133D01*
Y412467D01*
G01X220300Y415867D02*
X222800D01*
Y417533D01*
G01X222425Y418783D02*
X222633Y419033D01*
X222758Y419325D01*
X222800Y419700D01*
X222717Y420075D01*
X222550Y420367D01*
X222258Y420575D01*
X221925Y420617D01*
X221592Y420533D01*
X221383Y420325D01*
X221217Y420033D01*
X221175Y419742D01*
X221217Y419450D01*
X221383Y419075D01*
X220300Y419200D01*
Y420325D01*
G01X221758Y421908D02*
X221467Y422200D01*
X221300Y422450D01*
X221217Y422783D01*
X221300Y423075D01*
X221467Y423283D01*
X221717Y423450D01*
X222008Y423492D01*
X222258Y423450D01*
X222508Y423283D01*
X222717Y423033D01*
X222800Y422742D01*
X222717Y422408D01*
X222467Y422117D01*
X222092Y421950D01*
X221675Y421908D01*
X221133Y421992D01*
X220842Y422117D01*
X220550Y422325D01*
X220342Y422617D01*
X220300Y422908D01*
X220383Y423200D01*
X220592Y423408D01*
G01X241983Y451300D02*
Y449508D01*
X242150Y449133D01*
X242483Y448883D01*
X242900Y448800D01*
X243317Y448883D01*
X243650Y449133D01*
X243817Y449508D01*
Y451300D01*
G01X245108Y450883D02*
X245358Y451133D01*
X245650Y451258D01*
X245983Y451300D01*
X246400Y451217D01*
X246692Y451008D01*
X246775Y450758D01*
X246733Y450508D01*
X246567Y450300D01*
X245733Y449883D01*
X245358Y449592D01*
X245108Y449175D01*
X245025Y448800D01*
X246775D01*
G01X248900D02*
Y451300D01*
X248400Y450800D01*
G01Y448800D02*
X249400D01*
G01X224700Y486100D02*
X224658Y485767D01*
X224492Y485475D01*
X224242Y485225D01*
X223950Y485058D01*
X223617Y484975D01*
X223283D01*
X222950Y485058D01*
X222658Y485225D01*
X222408Y485475D01*
X222242Y485767D01*
X222200Y486100D01*
X222242Y486433D01*
X222408Y486725D01*
X222658Y486975D01*
X222950Y487142D01*
X223283Y487225D01*
X223617D01*
X223950Y487142D01*
X224242Y486975D01*
X224492Y486725D01*
X224658Y486433D01*
X224700Y486100D01*
G01X224367Y488225D02*
X224575Y488558D01*
X224700Y488933D01*
Y489267D01*
X224575Y489600D01*
X224367Y489850D01*
X224075Y489975D01*
X223783Y489892D01*
X223533Y489683D01*
X223367Y489308D01*
X223283Y488808D01*
X223117Y488517D01*
X222825Y488392D01*
X222533Y488475D01*
X222325Y488683D01*
X222200Y488975D01*
Y489267D01*
X222283Y489558D01*
X222492Y489808D01*
G01X222408Y493017D02*
X222283Y492767D01*
X222200Y492475D01*
Y492142D01*
X222325Y491767D01*
X222533Y491475D01*
X222783Y491267D01*
X223200Y491100D01*
X223575Y491058D01*
X223950Y491142D01*
X224200Y491267D01*
X224450Y491517D01*
X224617Y491808D01*
X224700Y492100D01*
Y492392D01*
X224617Y492683D01*
X224492Y492933D01*
X224325Y493142D01*
G01X224700Y495100D02*
X222200D01*
X222700Y494600D01*
G01X224700D02*
Y495600D01*
G01X280312Y474201D02*
Y476701D01*
X281353D01*
X281687Y476576D01*
X281895Y476409D01*
X281978Y476076D01*
X281895Y475743D01*
X281645Y475534D01*
X281353Y475409D01*
X280312D01*
G01X281353D02*
X281978Y474201D01*
G01X283437Y474493D02*
X283728Y474284D01*
X284062Y474201D01*
X284395Y474284D01*
X284687Y474534D01*
X284895Y474909D01*
X284978Y475284D01*
Y475743D01*
X284895Y476118D01*
X284687Y476451D01*
X284437Y476618D01*
X284145Y476701D01*
X283812Y476618D01*
X283562Y476451D01*
X283395Y476201D01*
X283312Y475868D01*
X283395Y475576D01*
X283603Y475284D01*
X283853Y475118D01*
X284145Y475076D01*
X284478Y475159D01*
X284728Y475368D01*
X284978Y475743D01*
G01X287145Y476701D02*
X286812Y476618D01*
X286562Y476409D01*
X286395Y476159D01*
X286270Y475826D01*
X286228Y475451D01*
X286270Y475076D01*
X286395Y474743D01*
X286562Y474493D01*
X286812Y474284D01*
X287145Y474201D01*
X287478Y474284D01*
X287728Y474493D01*
X287895Y474743D01*
X288020Y475076D01*
X288062Y475451D01*
X288020Y475826D01*
X287895Y476159D01*
X287728Y476409D01*
X287478Y476618D01*
X287145Y476701D01*
G01X261317Y455492D02*
X261067Y455617D01*
X260775Y455700D01*
X260442D01*
X260067Y455575D01*
X259775Y455367D01*
X259567Y455117D01*
X259400Y454700D01*
X259358Y454325D01*
X259442Y453950D01*
X259567Y453700D01*
X259817Y453450D01*
X260108Y453283D01*
X260400Y453200D01*
X260692D01*
X260983Y453283D01*
X261233Y453408D01*
X261442Y453575D01*
G01X262608Y455283D02*
X262858Y455533D01*
X263150Y455658D01*
X263483Y455700D01*
X263900Y455617D01*
X264192Y455408D01*
X264275Y455158D01*
X264233Y454908D01*
X264067Y454700D01*
X263233Y454283D01*
X262858Y453992D01*
X262608Y453575D01*
X262525Y453200D01*
X264275D01*
G01X265483Y453575D02*
X265733Y453367D01*
X266025Y453242D01*
X266400Y453200D01*
X266775Y453283D01*
X267067Y453450D01*
X267275Y453742D01*
X267317Y454075D01*
X267233Y454408D01*
X267025Y454617D01*
X266733Y454783D01*
X266442Y454825D01*
X266150Y454783D01*
X265775Y454617D01*
X265900Y455700D01*
X267025D01*
G01X268483Y453575D02*
X268733Y453367D01*
X269025Y453242D01*
X269400Y453200D01*
X269775Y453283D01*
X270067Y453450D01*
X270275Y453742D01*
X270317Y454075D01*
X270233Y454408D01*
X270025Y454617D01*
X269733Y454783D01*
X269442Y454825D01*
X269150Y454783D01*
X268775Y454617D01*
X268900Y455700D01*
X270025D01*
G01X248217Y455592D02*
X247967Y455717D01*
X247675Y455800D01*
X247342D01*
X246967Y455675D01*
X246675Y455467D01*
X246467Y455217D01*
X246300Y454800D01*
X246258Y454425D01*
X246342Y454050D01*
X246467Y453800D01*
X246717Y453550D01*
X247008Y453383D01*
X247300Y453300D01*
X247592D01*
X247883Y453383D01*
X248133Y453508D01*
X248342Y453675D01*
G01X249508Y455383D02*
X249758Y455633D01*
X250050Y455758D01*
X250383Y455800D01*
X250800Y455717D01*
X251092Y455508D01*
X251175Y455258D01*
X251133Y455008D01*
X250967Y454800D01*
X250133Y454383D01*
X249758Y454092D01*
X249508Y453675D01*
X249425Y453300D01*
X251175D01*
G01X253300Y455800D02*
X252967Y455717D01*
X252717Y455508D01*
X252550Y455258D01*
X252425Y454925D01*
X252383Y454550D01*
X252425Y454175D01*
X252550Y453842D01*
X252717Y453592D01*
X252967Y453383D01*
X253300Y453300D01*
X253633Y453383D01*
X253883Y453592D01*
X254050Y453842D01*
X254175Y454175D01*
X254217Y454550D01*
X254175Y454925D01*
X254050Y455258D01*
X253883Y455508D01*
X253633Y455717D01*
X253300Y455800D01*
G01X255508Y455383D02*
X255758Y455633D01*
X256050Y455758D01*
X256383Y455800D01*
X256800Y455717D01*
X257092Y455508D01*
X257175Y455258D01*
X257133Y455008D01*
X256967Y454800D01*
X256133Y454383D01*
X255758Y454092D01*
X255508Y453675D01*
X255425Y453300D01*
X257175D01*
G01X281211Y467756D02*
X280961Y467881D01*
X280669Y467964D01*
X280336D01*
X279961Y467839D01*
X279669Y467631D01*
X279461Y467381D01*
X279294Y466964D01*
X279252Y466589D01*
X279336Y466214D01*
X279461Y465964D01*
X279711Y465714D01*
X280002Y465547D01*
X280294Y465464D01*
X280586D01*
X280877Y465547D01*
X281127Y465672D01*
X281336Y465839D01*
G01X283294Y465464D02*
Y467964D01*
X282794Y467464D01*
G01Y465464D02*
X283794D01*
G01X285377Y465839D02*
X285627Y465631D01*
X285919Y465506D01*
X286294Y465464D01*
X286669Y465547D01*
X286961Y465714D01*
X287169Y466006D01*
X287211Y466339D01*
X287127Y466672D01*
X286919Y466881D01*
X286627Y467047D01*
X286336Y467089D01*
X286044Y467047D01*
X285669Y466881D01*
X285794Y467964D01*
X286919D01*
G01X289294Y465464D02*
Y467964D01*
X288794Y467464D01*
G01Y465464D02*
X289794D01*
G01X257315Y473758D02*
X257190Y473508D01*
X257107Y473216D01*
Y472883D01*
X257232Y472508D01*
X257440Y472216D01*
X257690Y472008D01*
X258107Y471841D01*
X258482Y471799D01*
X258857Y471883D01*
X259107Y472008D01*
X259357Y472258D01*
X259524Y472549D01*
X259607Y472841D01*
Y473133D01*
X259524Y473424D01*
X259399Y473674D01*
X259232Y473883D01*
G01X259607Y475841D02*
X257107D01*
X257607Y475341D01*
G01X259607D02*
Y476341D01*
G01X259107Y477924D02*
X259399Y478174D01*
X259565Y478508D01*
X259607Y478883D01*
X259565Y479216D01*
X259357Y479549D01*
X259107Y479758D01*
X258857Y479799D01*
X258565Y479716D01*
X258357Y479424D01*
X258274Y479133D01*
Y478758D01*
G01Y479133D02*
X258149Y479383D01*
X257940Y479591D01*
X257690Y479674D01*
X257440Y479591D01*
X257232Y479383D01*
X257107Y479008D01*
X257149Y478633D01*
X257315Y478258D01*
G01X259607Y481841D02*
X259565Y482133D01*
X259440Y482466D01*
X259232Y482674D01*
X258940Y482758D01*
X258649Y482674D01*
X258399Y482424D01*
X258274Y482049D01*
Y481633D01*
X258190Y481383D01*
X257982Y481174D01*
X257690Y481091D01*
X257399Y481216D01*
X257190Y481508D01*
X257107Y481841D01*
X257190Y482174D01*
X257399Y482466D01*
X257690Y482591D01*
X257982Y482508D01*
X258190Y482299D01*
X258274Y482049D01*
Y481633D01*
X258399Y481258D01*
X258649Y481008D01*
X258940Y480924D01*
X259232Y481008D01*
X259440Y481216D01*
X259565Y481549D01*
X259607Y481841D01*
G01X261202Y472853D02*
X261077Y472603D01*
X260994Y472311D01*
Y471978D01*
X261119Y471603D01*
X261327Y471311D01*
X261577Y471103D01*
X261994Y470936D01*
X262369Y470894D01*
X262744Y470978D01*
X262994Y471103D01*
X263244Y471353D01*
X263411Y471644D01*
X263494Y471936D01*
Y472228D01*
X263411Y472519D01*
X263286Y472769D01*
X263119Y472978D01*
G01X263494Y474936D02*
X260994D01*
X261494Y474436D01*
G01X263494D02*
Y475436D01*
G01X262994Y477019D02*
X263286Y477269D01*
X263452Y477603D01*
X263494Y477978D01*
X263452Y478311D01*
X263244Y478644D01*
X262994Y478853D01*
X262744Y478894D01*
X262452Y478811D01*
X262244Y478519D01*
X262161Y478228D01*
Y477853D01*
G01Y478228D02*
X262036Y478478D01*
X261827Y478686D01*
X261577Y478769D01*
X261327Y478686D01*
X261119Y478478D01*
X260994Y478103D01*
X261036Y477728D01*
X261202Y477353D01*
G01X263202Y480228D02*
X263411Y480519D01*
X263494Y480853D01*
X263411Y481186D01*
X263161Y481478D01*
X262786Y481686D01*
X262411Y481769D01*
X261952D01*
X261577Y481686D01*
X261244Y481478D01*
X261077Y481228D01*
X260994Y480936D01*
X261077Y480603D01*
X261244Y480353D01*
X261494Y480186D01*
X261827Y480103D01*
X262119Y480186D01*
X262411Y480394D01*
X262577Y480644D01*
X262619Y480936D01*
X262536Y481269D01*
X262327Y481519D01*
X261952Y481769D01*
G01X249867Y423300D02*
Y425800D01*
X250908D01*
X251242Y425675D01*
X251450Y425508D01*
X251533Y425175D01*
X251450Y424842D01*
X251200Y424633D01*
X250908Y424508D01*
X249867D01*
G01X250908D02*
X251533Y423300D01*
G01X252783Y423800D02*
X253033Y423508D01*
X253367Y423342D01*
X253742Y423300D01*
X254075Y423342D01*
X254408Y423550D01*
X254617Y423800D01*
X254658Y424050D01*
X254575Y424342D01*
X254283Y424550D01*
X253992Y424633D01*
X253617D01*
G01X253992D02*
X254242Y424758D01*
X254450Y424967D01*
X254533Y425217D01*
X254450Y425467D01*
X254242Y425675D01*
X253867Y425800D01*
X253492Y425758D01*
X253117Y425592D01*
G01X255908Y425383D02*
X256158Y425633D01*
X256450Y425758D01*
X256783Y425800D01*
X257200Y425717D01*
X257492Y425508D01*
X257575Y425258D01*
X257533Y425008D01*
X257367Y424800D01*
X256533Y424383D01*
X256158Y424092D01*
X255908Y423675D01*
X255825Y423300D01*
X257575D01*
G01X260200D02*
Y425800D01*
X258658Y424008D01*
X260742D01*
G01X249767Y431400D02*
Y433900D01*
X250808D01*
X251142Y433775D01*
X251350Y433608D01*
X251433Y433275D01*
X251350Y432942D01*
X251100Y432733D01*
X250808Y432608D01*
X249767D01*
G01X250808D02*
X251433Y431400D01*
G01X252808Y433483D02*
X253058Y433733D01*
X253350Y433858D01*
X253683Y433900D01*
X254100Y433817D01*
X254392Y433608D01*
X254475Y433358D01*
X254433Y433108D01*
X254267Y432900D01*
X253433Y432483D01*
X253058Y432192D01*
X252808Y431775D01*
X252725Y431400D01*
X254475D01*
G01X255683Y431900D02*
X255933Y431608D01*
X256267Y431442D01*
X256642Y431400D01*
X256975Y431442D01*
X257308Y431650D01*
X257517Y431900D01*
X257558Y432150D01*
X257475Y432442D01*
X257183Y432650D01*
X256892Y432733D01*
X256517D01*
G01X256892D02*
X257142Y432858D01*
X257350Y433067D01*
X257433Y433317D01*
X257350Y433567D01*
X257142Y433775D01*
X256767Y433900D01*
X256392Y433858D01*
X256017Y433692D01*
G01X260100Y431400D02*
Y433900D01*
X258558Y432108D01*
X260642D01*
G01X255300Y438267D02*
X252800D01*
Y439308D01*
X252925Y439642D01*
X253092Y439850D01*
X253425Y439933D01*
X253758Y439850D01*
X253967Y439600D01*
X254092Y439308D01*
Y438267D01*
G01Y439308D02*
X255300Y439933D01*
G01X253217Y441308D02*
X252967Y441558D01*
X252842Y441850D01*
X252800Y442183D01*
X252883Y442600D01*
X253092Y442892D01*
X253342Y442975D01*
X253592Y442933D01*
X253800Y442767D01*
X254217Y441933D01*
X254508Y441558D01*
X254925Y441308D01*
X255300Y441225D01*
Y442975D01*
G01X254800Y444183D02*
X255092Y444433D01*
X255258Y444767D01*
X255300Y445142D01*
X255258Y445475D01*
X255050Y445808D01*
X254800Y446017D01*
X254550Y446058D01*
X254258Y445975D01*
X254050Y445683D01*
X253967Y445392D01*
Y445017D01*
G01Y445392D02*
X253842Y445642D01*
X253633Y445850D01*
X253383Y445933D01*
X253133Y445850D01*
X252925Y445642D01*
X252800Y445267D01*
X252842Y444892D01*
X253008Y444517D01*
G01X254800Y447183D02*
X255092Y447433D01*
X255258Y447767D01*
X255300Y448142D01*
X255258Y448475D01*
X255050Y448808D01*
X254800Y449017D01*
X254550Y449058D01*
X254258Y448975D01*
X254050Y448683D01*
X253967Y448392D01*
Y448017D01*
G01Y448392D02*
X253842Y448642D01*
X253633Y448850D01*
X253383Y448933D01*
X253133Y448850D01*
X252925Y448642D01*
X252800Y448267D01*
X252842Y447892D01*
X253008Y447517D01*
G01X259000Y438267D02*
X256500D01*
Y439308D01*
X256625Y439642D01*
X256792Y439850D01*
X257125Y439933D01*
X257458Y439850D01*
X257667Y439600D01*
X257792Y439308D01*
Y438267D01*
G01Y439308D02*
X259000Y439933D01*
G01X256917Y441308D02*
X256667Y441558D01*
X256542Y441850D01*
X256500Y442183D01*
X256583Y442600D01*
X256792Y442892D01*
X257042Y442975D01*
X257292Y442933D01*
X257500Y442767D01*
X257917Y441933D01*
X258208Y441558D01*
X258625Y441308D01*
X259000Y441225D01*
Y442975D01*
G01Y445600D02*
X256500D01*
X258292Y444058D01*
Y446142D01*
G01X259000Y448600D02*
X256500D01*
X258292Y447058D01*
Y449142D01*
G01X255467Y457800D02*
Y460300D01*
X256508D01*
X256842Y460175D01*
X257050Y460008D01*
X257133Y459675D01*
X257050Y459342D01*
X256800Y459133D01*
X256508Y459008D01*
X255467D01*
G01X256508D02*
X257133Y457800D01*
G01X258508Y459883D02*
X258758Y460133D01*
X259050Y460258D01*
X259383Y460300D01*
X259800Y460217D01*
X260092Y460008D01*
X260175Y459758D01*
X260133Y459508D01*
X259967Y459300D01*
X259133Y458883D01*
X258758Y458592D01*
X258508Y458175D01*
X258425Y457800D01*
X260175D01*
G01X261508Y458842D02*
X261800Y459133D01*
X262050Y459300D01*
X262383Y459383D01*
X262675Y459300D01*
X262883Y459133D01*
X263050Y458883D01*
X263092Y458592D01*
X263050Y458342D01*
X262883Y458092D01*
X262633Y457883D01*
X262342Y457800D01*
X262008Y457883D01*
X261717Y458133D01*
X261550Y458508D01*
X261508Y458925D01*
X261592Y459467D01*
X261717Y459758D01*
X261925Y460050D01*
X262217Y460258D01*
X262508Y460300D01*
X262800Y460217D01*
X263008Y460008D01*
G01X237067Y486600D02*
Y489100D01*
X238108D01*
X238442Y488975D01*
X238650Y488808D01*
X238733Y488475D01*
X238650Y488142D01*
X238400Y487933D01*
X238108Y487808D01*
X237067D01*
G01X238108D02*
X238733Y486600D01*
G01X240900D02*
Y489100D01*
X240400Y488600D01*
G01Y486600D02*
X241400D01*
G01X243108Y488683D02*
X243358Y488933D01*
X243650Y489058D01*
X243983Y489100D01*
X244400Y489017D01*
X244692Y488808D01*
X244775Y488558D01*
X244733Y488308D01*
X244567Y488100D01*
X243733Y487683D01*
X243358Y487392D01*
X243108Y486975D01*
X243025Y486600D01*
X244775D01*
G01X247867Y472650D02*
Y475150D01*
X248908D01*
X249242Y475025D01*
X249450Y474858D01*
X249533Y474525D01*
X249450Y474192D01*
X249200Y473983D01*
X248908Y473858D01*
X247867D01*
G01X248908D02*
X249533Y472650D01*
G01X251700D02*
Y475150D01*
X251200Y474650D01*
G01Y472650D02*
X252200D01*
G01X254700D02*
Y475150D01*
X254200Y474650D01*
G01Y472650D02*
X255200D01*
G01X231000Y471167D02*
X228500D01*
Y472208D01*
X228625Y472542D01*
X228792Y472750D01*
X229125Y472833D01*
X229458Y472750D01*
X229667Y472500D01*
X229792Y472208D01*
Y471167D01*
G01Y472208D02*
X231000Y472833D01*
G01X230625Y474083D02*
X230833Y474333D01*
X230958Y474625D01*
X231000Y475000D01*
X230917Y475375D01*
X230750Y475667D01*
X230458Y475875D01*
X230125Y475917D01*
X229792Y475833D01*
X229583Y475625D01*
X229417Y475333D01*
X229375Y475042D01*
X229417Y474750D01*
X229583Y474375D01*
X228500Y474500D01*
Y475625D01*
G01X224800Y478067D02*
X222300D01*
Y479108D01*
X222425Y479442D01*
X222592Y479650D01*
X222925Y479733D01*
X223258Y479650D01*
X223467Y479400D01*
X223592Y479108D01*
Y478067D01*
G01Y479108D02*
X224800Y479733D01*
G01X222717Y481108D02*
X222467Y481358D01*
X222342Y481650D01*
X222300Y481983D01*
X222383Y482400D01*
X222592Y482692D01*
X222842Y482775D01*
X223092Y482733D01*
X223300Y482567D01*
X223717Y481733D01*
X224008Y481358D01*
X224425Y481108D01*
X224800Y481025D01*
Y482775D01*
G01X265542Y472917D02*
X265417Y472667D01*
X265334Y472375D01*
Y472042D01*
X265459Y471667D01*
X265667Y471375D01*
X265917Y471167D01*
X266334Y471000D01*
X266709Y470958D01*
X267084Y471042D01*
X267334Y471167D01*
X267584Y471417D01*
X267751Y471708D01*
X267834Y472000D01*
Y472292D01*
X267751Y472583D01*
X267626Y472833D01*
X267459Y473042D01*
G01X267834Y475000D02*
X265334D01*
X265834Y474500D01*
G01X267834D02*
Y475500D01*
G01Y478500D02*
X265334D01*
X267126Y476958D01*
Y479042D01*
G01X265334Y481000D02*
X265417Y480667D01*
X265626Y480417D01*
X265876Y480250D01*
X266209Y480125D01*
X266584Y480083D01*
X266959Y480125D01*
X267292Y480250D01*
X267542Y480417D01*
X267751Y480667D01*
X267834Y481000D01*
X267751Y481333D01*
X267542Y481583D01*
X267292Y481750D01*
X266959Y481875D01*
X266584Y481917D01*
X266209Y481875D01*
X265876Y481750D01*
X265626Y481583D01*
X265417Y481333D01*
X265334Y481000D01*
G01X279259Y462886D02*
X279009Y463011D01*
X278717Y463094D01*
X278384D01*
X278009Y462969D01*
X277717Y462761D01*
X277509Y462511D01*
X277342Y462094D01*
X277300Y461719D01*
X277384Y461344D01*
X277509Y461094D01*
X277759Y460844D01*
X278050Y460677D01*
X278342Y460594D01*
X278634D01*
X278925Y460677D01*
X279175Y460802D01*
X279384Y460969D01*
G01X281342Y460594D02*
Y463094D01*
X280842Y462594D01*
G01Y460594D02*
X281842D01*
G01X283425Y460969D02*
X283675Y460761D01*
X283967Y460636D01*
X284342Y460594D01*
X284717Y460677D01*
X285009Y460844D01*
X285217Y461136D01*
X285259Y461469D01*
X285175Y461802D01*
X284967Y462011D01*
X284675Y462177D01*
X284384Y462219D01*
X284092Y462177D01*
X283717Y462011D01*
X283842Y463094D01*
X284967D01*
G01X287342D02*
X287009Y463011D01*
X286759Y462802D01*
X286592Y462552D01*
X286467Y462219D01*
X286425Y461844D01*
X286467Y461469D01*
X286592Y461136D01*
X286759Y460886D01*
X287009Y460677D01*
X287342Y460594D01*
X287675Y460677D01*
X287925Y460886D01*
X288092Y461136D01*
X288217Y461469D01*
X288259Y461844D01*
X288217Y462219D01*
X288092Y462552D01*
X287925Y462802D01*
X287675Y463011D01*
X287342Y463094D01*
G01X288800Y430267D02*
X286300D01*
Y431267D01*
X286425Y431600D01*
X286717Y431850D01*
X287050Y431933D01*
X287383Y431850D01*
X287633Y431642D01*
X287758Y431267D01*
Y430267D01*
G01X286508Y435017D02*
X286383Y434767D01*
X286300Y434475D01*
Y434142D01*
X286425Y433767D01*
X286633Y433475D01*
X286883Y433267D01*
X287300Y433100D01*
X287675Y433058D01*
X288050Y433142D01*
X288300Y433267D01*
X288550Y433517D01*
X288717Y433808D01*
X288800Y434100D01*
Y434392D01*
X288717Y434683D01*
X288592Y434933D01*
X288425Y435142D01*
G01X288800Y437100D02*
X288758Y437392D01*
X288633Y437725D01*
X288425Y437933D01*
X288133Y438017D01*
X287842Y437933D01*
X287592Y437683D01*
X287467Y437308D01*
Y436892D01*
X287383Y436642D01*
X287175Y436433D01*
X286883Y436350D01*
X286592Y436475D01*
X286383Y436767D01*
X286300Y437100D01*
X286383Y437433D01*
X286592Y437725D01*
X286883Y437850D01*
X287175Y437767D01*
X287383Y437558D01*
X287467Y437308D01*
Y436892D01*
X287592Y436517D01*
X287842Y436267D01*
X288133Y436183D01*
X288425Y436267D01*
X288633Y436475D01*
X288758Y436808D01*
X288800Y437100D01*
G01X279717Y457391D02*
X279467Y457516D01*
X279175Y457599D01*
X278842D01*
X278467Y457474D01*
X278175Y457266D01*
X277967Y457016D01*
X277800Y456599D01*
X277758Y456224D01*
X277842Y455849D01*
X277967Y455599D01*
X278217Y455349D01*
X278508Y455182D01*
X278800Y455099D01*
X279092D01*
X279383Y455182D01*
X279633Y455307D01*
X279842Y455474D01*
G01X281800Y455099D02*
Y457599D01*
X281300Y457099D01*
G01Y455099D02*
X282300D01*
G01X285300D02*
Y457599D01*
X283758Y455807D01*
X285842D01*
G01X287092Y455391D02*
X287383Y455182D01*
X287717Y455099D01*
X288050Y455182D01*
X288342Y455432D01*
X288550Y455807D01*
X288633Y456182D01*
Y456641D01*
X288550Y457016D01*
X288342Y457349D01*
X288092Y457516D01*
X287800Y457599D01*
X287467Y457516D01*
X287217Y457349D01*
X287050Y457099D01*
X286967Y456766D01*
X287050Y456474D01*
X287258Y456182D01*
X287508Y456016D01*
X287800Y455974D01*
X288133Y456057D01*
X288383Y456266D01*
X288633Y456641D01*
G01X255167Y465200D02*
Y462700D01*
X256833D01*
G01X259833D02*
X258167D01*
Y465200D01*
X259833D01*
G01X259167Y463992D02*
X258167D01*
G01X261083Y462700D02*
Y465200D01*
X261917D01*
X262250Y465075D01*
X262500Y464908D01*
X262708Y464658D01*
X262875Y464367D01*
X262917Y463950D01*
X262875Y463533D01*
X262708Y463242D01*
X262500Y462992D01*
X262250Y462825D01*
X261917Y462700D01*
X261083D01*
G01X265500D02*
Y465200D01*
X263958Y463408D01*
X266042D01*
G01X244967Y480200D02*
Y477700D01*
X246633D01*
G01X249633D02*
X247967D01*
Y480200D01*
X249633D01*
G01X248967Y478992D02*
X247967D01*
G01X250883Y477700D02*
Y480200D01*
X251717D01*
X252050Y480075D01*
X252300Y479908D01*
X252508Y479658D01*
X252675Y479367D01*
X252717Y478950D01*
X252675Y478533D01*
X252508Y478242D01*
X252300Y477992D01*
X252050Y477825D01*
X251717Y477700D01*
X250883D01*
G01X254008Y479783D02*
X254258Y480033D01*
X254550Y480158D01*
X254883Y480200D01*
X255300Y480117D01*
X255592Y479908D01*
X255675Y479658D01*
X255633Y479408D01*
X255467Y479200D01*
X254633Y478783D01*
X254258Y478492D01*
X254008Y478075D01*
X253925Y477700D01*
X255675D01*
G01X251467Y470280D02*
Y467780D01*
X253133D01*
G01X256133D02*
X254467D01*
Y470280D01*
X256133D01*
G01X255467Y469072D02*
X254467D01*
G01X257383Y467780D02*
Y470280D01*
X258217D01*
X258550Y470155D01*
X258800Y469988D01*
X259008Y469738D01*
X259175Y469447D01*
X259217Y469030D01*
X259175Y468613D01*
X259008Y468322D01*
X258800Y468072D01*
X258550Y467905D01*
X258217Y467780D01*
X257383D01*
G01X261300D02*
Y470280D01*
X260800Y469780D01*
G01Y467780D02*
X261800D01*
G01X280540Y472344D02*
Y469844D01*
X282206D01*
G01X283581Y470886D02*
X283873Y471177D01*
X284123Y471344D01*
X284456Y471427D01*
X284748Y471344D01*
X284956Y471177D01*
X285123Y470927D01*
X285165Y470636D01*
X285123Y470386D01*
X284956Y470136D01*
X284706Y469927D01*
X284415Y469844D01*
X284081Y469927D01*
X283790Y470177D01*
X283623Y470552D01*
X283581Y470969D01*
X283665Y471511D01*
X283790Y471802D01*
X283998Y472094D01*
X284290Y472302D01*
X284581Y472344D01*
X284873Y472261D01*
X285081Y472052D01*
G01X286581Y471927D02*
X286831Y472177D01*
X287123Y472302D01*
X287456Y472344D01*
X287873Y472261D01*
X288165Y472052D01*
X288248Y471802D01*
X288206Y471552D01*
X288040Y471344D01*
X287206Y470927D01*
X286831Y470636D01*
X286581Y470219D01*
X286498Y469844D01*
X288248D01*
G01X242608Y534717D02*
X242483Y534467D01*
X242400Y534175D01*
Y533842D01*
X242525Y533467D01*
X242733Y533175D01*
X242983Y532967D01*
X243400Y532800D01*
X243775Y532758D01*
X244150Y532842D01*
X244400Y532967D01*
X244650Y533217D01*
X244817Y533508D01*
X244900Y533800D01*
Y534092D01*
X244817Y534383D01*
X244692Y534633D01*
X244525Y534842D01*
G01X244900Y536800D02*
X242400D01*
X242900Y536300D01*
G01X244900D02*
Y537300D01*
G01X244400Y538883D02*
X244692Y539133D01*
X244858Y539467D01*
X244900Y539842D01*
X244858Y540175D01*
X244650Y540508D01*
X244400Y540717D01*
X244150Y540758D01*
X243858Y540675D01*
X243650Y540383D01*
X243567Y540092D01*
Y539717D01*
G01Y540092D02*
X243442Y540342D01*
X243233Y540550D01*
X242983Y540633D01*
X242733Y540550D01*
X242525Y540342D01*
X242400Y539967D01*
X242442Y539592D01*
X242608Y539217D01*
G01X242400Y542800D02*
X242483Y542467D01*
X242692Y542217D01*
X242942Y542050D01*
X243275Y541925D01*
X243650Y541883D01*
X244025Y541925D01*
X244358Y542050D01*
X244608Y542217D01*
X244817Y542467D01*
X244900Y542800D01*
X244817Y543133D01*
X244608Y543383D01*
X244358Y543550D01*
X244025Y543675D01*
X243650Y543717D01*
X243275Y543675D01*
X242942Y543550D01*
X242692Y543383D01*
X242483Y543133D01*
X242400Y542800D01*
G01X251317Y508700D02*
Y511200D01*
X252358D01*
X252692Y511075D01*
X252900Y510908D01*
X252983Y510575D01*
X252900Y510242D01*
X252650Y510033D01*
X252358Y509908D01*
X251317D01*
G01X252358D02*
X252983Y508700D01*
G01X255150D02*
X255442Y508742D01*
X255775Y508867D01*
X255983Y509075D01*
X256067Y509367D01*
X255983Y509658D01*
X255733Y509908D01*
X255358Y510033D01*
X254942D01*
X254692Y510117D01*
X254483Y510325D01*
X254400Y510617D01*
X254525Y510908D01*
X254817Y511117D01*
X255150Y511200D01*
X255483Y511117D01*
X255775Y510908D01*
X255900Y510617D01*
X255817Y510325D01*
X255608Y510117D01*
X255358Y510033D01*
X254942D01*
X254567Y509908D01*
X254317Y509658D01*
X254233Y509367D01*
X254317Y509075D01*
X254525Y508867D01*
X254858Y508742D01*
X255150Y508700D01*
G01X257442Y508992D02*
X257733Y508783D01*
X258067Y508700D01*
X258400Y508783D01*
X258692Y509033D01*
X258900Y509408D01*
X258983Y509783D01*
Y510242D01*
X258900Y510617D01*
X258692Y510950D01*
X258442Y511117D01*
X258150Y511200D01*
X257817Y511117D01*
X257567Y510950D01*
X257400Y510700D01*
X257317Y510367D01*
X257400Y510075D01*
X257608Y509783D01*
X257858Y509617D01*
X258150Y509575D01*
X258483Y509658D01*
X258733Y509867D01*
X258983Y510242D01*
G01X232117Y513500D02*
Y516000D01*
X233158D01*
X233492Y515875D01*
X233700Y515708D01*
X233783Y515375D01*
X233700Y515042D01*
X233450Y514833D01*
X233158Y514708D01*
X232117D01*
G01X233158D02*
X233783Y513500D01*
G01X235950D02*
X236242Y513542D01*
X236575Y513667D01*
X236783Y513875D01*
X236867Y514167D01*
X236783Y514458D01*
X236533Y514708D01*
X236158Y514833D01*
X235742D01*
X235492Y514917D01*
X235283Y515125D01*
X235200Y515417D01*
X235325Y515708D01*
X235617Y515917D01*
X235950Y516000D01*
X236283Y515917D01*
X236575Y515708D01*
X236700Y515417D01*
X236617Y515125D01*
X236408Y514917D01*
X236158Y514833D01*
X235742D01*
X235367Y514708D01*
X235117Y514458D01*
X235033Y514167D01*
X235117Y513875D01*
X235325Y513667D01*
X235658Y513542D01*
X235950Y513500D01*
G01X238950D02*
X239242Y513542D01*
X239575Y513667D01*
X239783Y513875D01*
X239867Y514167D01*
X239783Y514458D01*
X239533Y514708D01*
X239158Y514833D01*
X238742D01*
X238492Y514917D01*
X238283Y515125D01*
X238200Y515417D01*
X238325Y515708D01*
X238617Y515917D01*
X238950Y516000D01*
X239283Y515917D01*
X239575Y515708D01*
X239700Y515417D01*
X239617Y515125D01*
X239408Y514917D01*
X239158Y514833D01*
X238742D01*
X238367Y514708D01*
X238117Y514458D01*
X238033Y514167D01*
X238117Y513875D01*
X238325Y513667D01*
X238658Y513542D01*
X238950Y513500D01*
G01X220408Y533517D02*
X220283Y533267D01*
X220200Y532975D01*
Y532642D01*
X220325Y532267D01*
X220533Y531975D01*
X220783Y531767D01*
X221200Y531600D01*
X221575Y531558D01*
X221950Y531642D01*
X222200Y531767D01*
X222450Y532017D01*
X222617Y532308D01*
X222700Y532600D01*
Y532892D01*
X222617Y533183D01*
X222492Y533433D01*
X222325Y533642D01*
G01X222700Y535600D02*
X220200D01*
X220700Y535100D01*
G01X222700D02*
Y536100D01*
G01X220617Y537808D02*
X220367Y538058D01*
X220242Y538350D01*
X220200Y538683D01*
X220283Y539100D01*
X220492Y539392D01*
X220742Y539475D01*
X220992Y539433D01*
X221200Y539267D01*
X221617Y538433D01*
X221908Y538058D01*
X222325Y537808D01*
X222700Y537725D01*
Y539475D01*
G01X221658Y540808D02*
X221367Y541100D01*
X221200Y541350D01*
X221117Y541683D01*
X221200Y541975D01*
X221367Y542183D01*
X221617Y542350D01*
X221908Y542392D01*
X222158Y542350D01*
X222408Y542183D01*
X222617Y541933D01*
X222700Y541642D01*
X222617Y541308D01*
X222367Y541017D01*
X221992Y540850D01*
X221575Y540808D01*
X221033Y540892D01*
X220742Y541017D01*
X220450Y541225D01*
X220242Y541517D01*
X220200Y541808D01*
X220283Y542100D01*
X220492Y542308D01*
G01X247308Y532617D02*
X247183Y532367D01*
X247100Y532075D01*
Y531742D01*
X247225Y531367D01*
X247433Y531075D01*
X247683Y530867D01*
X248100Y530700D01*
X248475Y530658D01*
X248850Y530742D01*
X249100Y530867D01*
X249350Y531117D01*
X249517Y531408D01*
X249600Y531700D01*
Y531992D01*
X249517Y532283D01*
X249392Y532533D01*
X249225Y532742D01*
G01X249600Y534700D02*
X247100D01*
X247600Y534200D01*
G01X249600D02*
Y535200D01*
G01X249100Y536783D02*
X249392Y537033D01*
X249558Y537367D01*
X249600Y537742D01*
X249558Y538075D01*
X249350Y538408D01*
X249100Y538617D01*
X248850Y538658D01*
X248558Y538575D01*
X248350Y538283D01*
X248267Y537992D01*
Y537617D01*
G01Y537992D02*
X248142Y538242D01*
X247933Y538450D01*
X247683Y538533D01*
X247433Y538450D01*
X247225Y538242D01*
X247100Y537867D01*
X247142Y537492D01*
X247308Y537117D01*
G01X249100Y539783D02*
X249392Y540033D01*
X249558Y540367D01*
X249600Y540742D01*
X249558Y541075D01*
X249350Y541408D01*
X249100Y541617D01*
X248850Y541658D01*
X248558Y541575D01*
X248350Y541283D01*
X248267Y540992D01*
Y540617D01*
G01Y540992D02*
X248142Y541242D01*
X247933Y541450D01*
X247683Y541533D01*
X247433Y541450D01*
X247225Y541242D01*
X247100Y540867D01*
X247142Y540492D01*
X247308Y540117D01*
G01X259708Y532917D02*
X259583Y532667D01*
X259500Y532375D01*
Y532042D01*
X259625Y531667D01*
X259833Y531375D01*
X260083Y531167D01*
X260500Y531000D01*
X260875Y530958D01*
X261250Y531042D01*
X261500Y531167D01*
X261750Y531417D01*
X261917Y531708D01*
X262000Y532000D01*
Y532292D01*
X261917Y532583D01*
X261792Y532833D01*
X261625Y533042D01*
G01X262000Y535000D02*
X259500D01*
X260000Y534500D01*
G01X262000D02*
Y535500D01*
G01X259917Y537208D02*
X259667Y537458D01*
X259542Y537750D01*
X259500Y538083D01*
X259583Y538500D01*
X259792Y538792D01*
X260042Y538875D01*
X260292Y538833D01*
X260500Y538667D01*
X260917Y537833D01*
X261208Y537458D01*
X261625Y537208D01*
X262000Y537125D01*
Y538875D01*
G01Y541000D02*
X261958Y541292D01*
X261833Y541625D01*
X261625Y541833D01*
X261333Y541917D01*
X261042Y541833D01*
X260792Y541583D01*
X260667Y541208D01*
Y540792D01*
X260583Y540542D01*
X260375Y540333D01*
X260083Y540250D01*
X259792Y540375D01*
X259583Y540667D01*
X259500Y541000D01*
X259583Y541333D01*
X259792Y541625D01*
X260083Y541750D01*
X260375Y541667D01*
X260583Y541458D01*
X260667Y541208D01*
Y540792D01*
X260792Y540417D01*
X261042Y540167D01*
X261333Y540083D01*
X261625Y540167D01*
X261833Y540375D01*
X261958Y540708D01*
X262000Y541000D01*
G01X252908Y533317D02*
X252783Y533067D01*
X252700Y532775D01*
Y532442D01*
X252825Y532067D01*
X253033Y531775D01*
X253283Y531567D01*
X253700Y531400D01*
X254075Y531358D01*
X254450Y531442D01*
X254700Y531567D01*
X254950Y531817D01*
X255117Y532108D01*
X255200Y532400D01*
Y532692D01*
X255117Y532983D01*
X254992Y533233D01*
X254825Y533442D01*
G01X255200Y535400D02*
X252700D01*
X253200Y534900D01*
G01X255200D02*
Y535900D01*
G01X253117Y537608D02*
X252867Y537858D01*
X252742Y538150D01*
X252700Y538483D01*
X252783Y538900D01*
X252992Y539192D01*
X253242Y539275D01*
X253492Y539233D01*
X253700Y539067D01*
X254117Y538233D01*
X254408Y537858D01*
X254825Y537608D01*
X255200Y537525D01*
Y539275D01*
G01X254908Y540692D02*
X255117Y540983D01*
X255200Y541317D01*
X255117Y541650D01*
X254867Y541942D01*
X254492Y542150D01*
X254117Y542233D01*
X253658D01*
X253283Y542150D01*
X252950Y541942D01*
X252783Y541692D01*
X252700Y541400D01*
X252783Y541067D01*
X252950Y540817D01*
X253200Y540650D01*
X253533Y540567D01*
X253825Y540650D01*
X254117Y540858D01*
X254283Y541108D01*
X254325Y541400D01*
X254242Y541733D01*
X254033Y541983D01*
X253658Y542233D01*
G01X230708Y495317D02*
X230583Y495067D01*
X230500Y494775D01*
Y494442D01*
X230625Y494067D01*
X230833Y493775D01*
X231083Y493567D01*
X231500Y493400D01*
X231875Y493358D01*
X232250Y493442D01*
X232500Y493567D01*
X232750Y493817D01*
X232917Y494108D01*
X233000Y494400D01*
Y494692D01*
X232917Y494983D01*
X232792Y495233D01*
X232625Y495442D01*
G01X233000Y497400D02*
X230500D01*
X231000Y496900D01*
G01X233000D02*
Y497900D01*
G01X232500Y499483D02*
X232792Y499733D01*
X232958Y500067D01*
X233000Y500442D01*
X232958Y500775D01*
X232750Y501108D01*
X232500Y501317D01*
X232250Y501358D01*
X231958Y501275D01*
X231750Y500983D01*
X231667Y500692D01*
Y500317D01*
G01Y500692D02*
X231542Y500942D01*
X231333Y501150D01*
X231083Y501233D01*
X230833Y501150D01*
X230625Y500942D01*
X230500Y500567D01*
X230542Y500192D01*
X230708Y499817D01*
G01X233000Y503900D02*
X230500D01*
X232292Y502358D01*
Y504442D01*
G01X240517Y510192D02*
X240267Y510317D01*
X239975Y510400D01*
X239642D01*
X239267Y510275D01*
X238975Y510067D01*
X238767Y509817D01*
X238600Y509400D01*
X238558Y509025D01*
X238642Y508650D01*
X238767Y508400D01*
X239017Y508150D01*
X239308Y507983D01*
X239600Y507900D01*
X239892D01*
X240183Y507983D01*
X240433Y508108D01*
X240642Y508275D01*
G01X242600Y507900D02*
Y510400D01*
X242100Y509900D01*
G01Y507900D02*
X243100D01*
G01X244683Y508400D02*
X244933Y508108D01*
X245267Y507942D01*
X245642Y507900D01*
X245975Y507942D01*
X246308Y508150D01*
X246517Y508400D01*
X246558Y508650D01*
X246475Y508942D01*
X246183Y509150D01*
X245892Y509233D01*
X245517D01*
G01X245892D02*
X246142Y509358D01*
X246350Y509567D01*
X246433Y509817D01*
X246350Y510067D01*
X246142Y510275D01*
X245767Y510400D01*
X245392Y510358D01*
X245017Y510192D01*
G01X247683Y508275D02*
X247933Y508067D01*
X248225Y507942D01*
X248600Y507900D01*
X248975Y507983D01*
X249267Y508150D01*
X249475Y508442D01*
X249517Y508775D01*
X249433Y509108D01*
X249225Y509317D01*
X248933Y509483D01*
X248642Y509525D01*
X248350Y509483D01*
X247975Y509317D01*
X248100Y510400D01*
X249225D01*
G01X261867Y511166D02*
Y508666D01*
X263533D01*
G01X264908Y509708D02*
X265200Y509999D01*
X265450Y510166D01*
X265783Y510249D01*
X266075Y510166D01*
X266283Y509999D01*
X266450Y509749D01*
X266492Y509458D01*
X266450Y509208D01*
X266283Y508958D01*
X266033Y508749D01*
X265742Y508666D01*
X265408Y508749D01*
X265117Y508999D01*
X264950Y509374D01*
X264908Y509791D01*
X264992Y510333D01*
X265117Y510624D01*
X265325Y510916D01*
X265617Y511124D01*
X265908Y511166D01*
X266200Y511083D01*
X266408Y510874D01*
G01X268700Y508666D02*
Y511166D01*
X268200Y510666D01*
G01Y508666D02*
X269200D01*
G01X225967Y534500D02*
Y532000D01*
X227633D01*
G01X229008Y533042D02*
X229300Y533333D01*
X229550Y533500D01*
X229883Y533583D01*
X230175Y533500D01*
X230383Y533333D01*
X230550Y533083D01*
X230592Y532792D01*
X230550Y532542D01*
X230383Y532292D01*
X230133Y532083D01*
X229842Y532000D01*
X229508Y532083D01*
X229217Y532333D01*
X229050Y532708D01*
X229008Y533125D01*
X229092Y533667D01*
X229217Y533958D01*
X229425Y534250D01*
X229717Y534458D01*
X230008Y534500D01*
X230300Y534417D01*
X230508Y534208D01*
G01X232800Y534500D02*
X232467Y534417D01*
X232217Y534208D01*
X232050Y533958D01*
X231925Y533625D01*
X231883Y533250D01*
X231925Y532875D01*
X232050Y532542D01*
X232217Y532292D01*
X232467Y532083D01*
X232800Y532000D01*
X233133Y532083D01*
X233383Y532292D01*
X233550Y532542D01*
X233675Y532875D01*
X233717Y533250D01*
X233675Y533625D01*
X233550Y533958D01*
X233383Y534208D01*
X233133Y534417D01*
X232800Y534500D01*
G01X230800Y734867D02*
X228300D01*
Y735908D01*
X228425Y736242D01*
X228592Y736450D01*
X228925Y736533D01*
X229258Y736450D01*
X229467Y736200D01*
X229592Y735908D01*
Y734867D01*
G01Y735908D02*
X230800Y736533D01*
G01Y738700D02*
X228300D01*
X228800Y738200D01*
G01X230800D02*
Y739200D01*
G01X230425Y740783D02*
X230633Y741033D01*
X230758Y741325D01*
X230800Y741700D01*
X230717Y742075D01*
X230550Y742367D01*
X230258Y742575D01*
X229925Y742617D01*
X229592Y742533D01*
X229383Y742325D01*
X229217Y742033D01*
X229175Y741742D01*
X229217Y741450D01*
X229383Y741075D01*
X228300Y741200D01*
Y742325D01*
G01X230800Y744617D02*
X230258Y744700D01*
X229800Y744825D01*
X229383Y744992D01*
X228925Y745200D01*
X228300Y745533D01*
Y743867D01*
G01X235300Y751800D02*
Y749300D01*
G01X234342Y751800D02*
X236258D01*
G01X237467Y749300D02*
Y751800D01*
X238467D01*
X238800Y751675D01*
X239050Y751383D01*
X239133Y751050D01*
X239050Y750717D01*
X238842Y750467D01*
X238467Y750342D01*
X237467D01*
G01X241300Y749300D02*
Y751800D01*
X240800Y751300D01*
G01Y749300D02*
X241800D01*
G01X243383Y749675D02*
X243633Y749467D01*
X243925Y749342D01*
X244300Y749300D01*
X244675Y749383D01*
X244967Y749550D01*
X245175Y749842D01*
X245217Y750175D01*
X245133Y750508D01*
X244925Y750717D01*
X244633Y750883D01*
X244342Y750925D01*
X244050Y750883D01*
X243675Y750717D01*
X243800Y751800D01*
X244925D01*
G01X247300Y749300D02*
Y751800D01*
X246800Y751300D01*
G01Y749300D02*
X247800D01*
G01X260383Y787792D02*
Y790292D01*
X261424D01*
X261758Y790167D01*
X261966Y790000D01*
X262049Y789667D01*
X261966Y789334D01*
X261716Y789125D01*
X261424Y789000D01*
X260383D01*
G01X261424D02*
X262049Y787792D01*
G01X263424Y789875D02*
X263674Y790125D01*
X263966Y790250D01*
X264299Y790292D01*
X264716Y790209D01*
X265008Y790000D01*
X265091Y789750D01*
X265049Y789500D01*
X264883Y789292D01*
X264049Y788875D01*
X263674Y788584D01*
X263424Y788167D01*
X263341Y787792D01*
X265091D01*
G01X266424Y788834D02*
X266716Y789125D01*
X266966Y789292D01*
X267299Y789375D01*
X267591Y789292D01*
X267799Y789125D01*
X267966Y788875D01*
X268008Y788584D01*
X267966Y788334D01*
X267799Y788084D01*
X267549Y787875D01*
X267258Y787792D01*
X266924Y787875D01*
X266633Y788125D01*
X266466Y788500D01*
X266424Y788917D01*
X266508Y789459D01*
X266633Y789750D01*
X266841Y790042D01*
X267133Y790250D01*
X267424Y790292D01*
X267716Y790209D01*
X267924Y790000D01*
G01X269424Y789875D02*
X269674Y790125D01*
X269966Y790250D01*
X270299Y790292D01*
X270716Y790209D01*
X271008Y790000D01*
X271091Y789750D01*
X271049Y789500D01*
X270883Y789292D01*
X270049Y788875D01*
X269674Y788584D01*
X269424Y788167D01*
X269341Y787792D01*
X271091D01*
G01X240479Y777670D02*
Y780170D01*
X241520D01*
X241854Y780045D01*
X242062Y779878D01*
X242145Y779545D01*
X242062Y779212D01*
X241812Y779003D01*
X241520Y778878D01*
X240479D01*
G01X241520D02*
X242145Y777670D01*
G01X244312D02*
Y780170D01*
X243812Y779670D01*
G01Y777670D02*
X244812D01*
G01X246520Y778712D02*
X246812Y779003D01*
X247062Y779170D01*
X247395Y779253D01*
X247687Y779170D01*
X247895Y779003D01*
X248062Y778753D01*
X248104Y778462D01*
X248062Y778212D01*
X247895Y777962D01*
X247645Y777753D01*
X247354Y777670D01*
X247020Y777753D01*
X246729Y778003D01*
X246562Y778378D01*
X246520Y778795D01*
X246604Y779337D01*
X246729Y779628D01*
X246937Y779920D01*
X247229Y780128D01*
X247520Y780170D01*
X247812Y780087D01*
X248020Y779878D01*
G01X250312Y777670D02*
Y780170D01*
X249812Y779670D01*
G01Y777670D02*
X250812D01*
G01X240467Y773800D02*
Y776300D01*
X241508D01*
X241842Y776175D01*
X242050Y776008D01*
X242133Y775675D01*
X242050Y775342D01*
X241800Y775133D01*
X241508Y775008D01*
X240467D01*
G01X241508D02*
X242133Y773800D01*
G01X244300D02*
Y776300D01*
X243800Y775800D01*
G01Y773800D02*
X244800D01*
G01X246508Y774842D02*
X246800Y775133D01*
X247050Y775300D01*
X247383Y775383D01*
X247675Y775300D01*
X247883Y775133D01*
X248050Y774883D01*
X248092Y774592D01*
X248050Y774342D01*
X247883Y774092D01*
X247633Y773883D01*
X247342Y773800D01*
X247008Y773883D01*
X246717Y774133D01*
X246550Y774508D01*
X246508Y774925D01*
X246592Y775467D01*
X246717Y775758D01*
X246925Y776050D01*
X247217Y776258D01*
X247508Y776300D01*
X247800Y776217D01*
X248008Y776008D01*
G01X250300Y776300D02*
X249967Y776217D01*
X249717Y776008D01*
X249550Y775758D01*
X249425Y775425D01*
X249383Y775050D01*
X249425Y774675D01*
X249550Y774342D01*
X249717Y774092D01*
X249967Y773883D01*
X250300Y773800D01*
X250633Y773883D01*
X250883Y774092D01*
X251050Y774342D01*
X251175Y774675D01*
X251217Y775050D01*
X251175Y775425D01*
X251050Y775758D01*
X250883Y776008D01*
X250633Y776217D01*
X250300Y776300D01*
G01X242667Y781700D02*
Y784200D01*
X243708D01*
X244042Y784075D01*
X244250Y783908D01*
X244333Y783575D01*
X244250Y783242D01*
X244000Y783033D01*
X243708Y782908D01*
X242667D01*
G01X243708D02*
X244333Y781700D01*
G01X246500D02*
Y784200D01*
X246000Y783700D01*
G01Y781700D02*
X247000D01*
G01X248583Y782075D02*
X248833Y781867D01*
X249125Y781742D01*
X249500Y781700D01*
X249875Y781783D01*
X250167Y781950D01*
X250375Y782242D01*
X250417Y782575D01*
X250333Y782908D01*
X250125Y783117D01*
X249833Y783283D01*
X249542Y783325D01*
X249250Y783283D01*
X248875Y783117D01*
X249000Y784200D01*
X250125D01*
G01X251792Y781992D02*
X252083Y781783D01*
X252417Y781700D01*
X252750Y781783D01*
X253042Y782033D01*
X253250Y782408D01*
X253333Y782783D01*
Y783242D01*
X253250Y783617D01*
X253042Y783950D01*
X252792Y784117D01*
X252500Y784200D01*
X252167Y784117D01*
X251917Y783950D01*
X251750Y783700D01*
X251667Y783367D01*
X251750Y783075D01*
X251958Y782783D01*
X252208Y782617D01*
X252500Y782575D01*
X252833Y782658D01*
X253083Y782867D01*
X253333Y783242D01*
G01X237667Y786000D02*
Y788500D01*
X238708D01*
X239042Y788375D01*
X239250Y788208D01*
X239333Y787875D01*
X239250Y787542D01*
X239000Y787333D01*
X238708Y787208D01*
X237667D01*
G01X238708D02*
X239333Y786000D01*
G01X241500D02*
Y788500D01*
X241000Y788000D01*
G01Y786000D02*
X242000D01*
G01X243583Y786375D02*
X243833Y786167D01*
X244125Y786042D01*
X244500Y786000D01*
X244875Y786083D01*
X245167Y786250D01*
X245375Y786542D01*
X245417Y786875D01*
X245333Y787208D01*
X245125Y787417D01*
X244833Y787583D01*
X244542Y787625D01*
X244250Y787583D01*
X243875Y787417D01*
X244000Y788500D01*
X245125D01*
G01X247500Y786000D02*
X247792Y786042D01*
X248125Y786167D01*
X248333Y786375D01*
X248417Y786667D01*
X248333Y786958D01*
X248083Y787208D01*
X247708Y787333D01*
X247292D01*
X247042Y787417D01*
X246833Y787625D01*
X246750Y787917D01*
X246875Y788208D01*
X247167Y788417D01*
X247500Y788500D01*
X247833Y788417D01*
X248125Y788208D01*
X248250Y787917D01*
X248167Y787625D01*
X247958Y787417D01*
X247708Y787333D01*
X247292D01*
X246917Y787208D01*
X246667Y786958D01*
X246583Y786667D01*
X246667Y786375D01*
X246875Y786167D01*
X247208Y786042D01*
X247500Y786000D01*
G01X275136Y787496D02*
Y789996D01*
X276177D01*
X276511Y789871D01*
X276719Y789704D01*
X276802Y789371D01*
X276719Y789038D01*
X276469Y788829D01*
X276177Y788704D01*
X275136D01*
G01X276177D02*
X276802Y787496D01*
G01X278969D02*
Y789996D01*
X278469Y789496D01*
G01Y787496D02*
X279469D01*
G01X281969D02*
X282261Y787538D01*
X282594Y787663D01*
X282802Y787871D01*
X282886Y788163D01*
X282802Y788454D01*
X282552Y788704D01*
X282177Y788829D01*
X281761D01*
X281511Y788913D01*
X281302Y789121D01*
X281219Y789413D01*
X281344Y789704D01*
X281636Y789913D01*
X281969Y789996D01*
X282302Y789913D01*
X282594Y789704D01*
X282719Y789413D01*
X282636Y789121D01*
X282427Y788913D01*
X282177Y788829D01*
X281761D01*
X281386Y788704D01*
X281136Y788454D01*
X281052Y788163D01*
X281136Y787871D01*
X281344Y787663D01*
X281677Y787538D01*
X281969Y787496D01*
G01X284177Y789579D02*
X284427Y789829D01*
X284719Y789954D01*
X285052Y789996D01*
X285469Y789913D01*
X285761Y789704D01*
X285844Y789454D01*
X285802Y789204D01*
X285636Y788996D01*
X284802Y788579D01*
X284427Y788288D01*
X284177Y787871D01*
X284094Y787496D01*
X285844D01*
G01X280903Y847168D02*
X280778Y846918D01*
X280695Y846626D01*
Y846293D01*
X280820Y845918D01*
X281028Y845626D01*
X281278Y845418D01*
X281695Y845251D01*
X282070Y845209D01*
X282445Y845293D01*
X282695Y845418D01*
X282945Y845668D01*
X283112Y845959D01*
X283195Y846251D01*
Y846543D01*
X283112Y846834D01*
X282987Y847084D01*
X282820Y847293D01*
G01X282695Y848334D02*
X282987Y848584D01*
X283153Y848918D01*
X283195Y849293D01*
X283153Y849626D01*
X282945Y849959D01*
X282695Y850168D01*
X282445Y850209D01*
X282153Y850126D01*
X281945Y849834D01*
X281862Y849543D01*
Y849168D01*
G01Y849543D02*
X281737Y849793D01*
X281528Y850001D01*
X281278Y850084D01*
X281028Y850001D01*
X280820Y849793D01*
X280695Y849418D01*
X280737Y849043D01*
X280903Y848668D01*
G01X280695Y852251D02*
X280778Y851918D01*
X280987Y851668D01*
X281237Y851501D01*
X281570Y851376D01*
X281945Y851334D01*
X282320Y851376D01*
X282653Y851501D01*
X282903Y851668D01*
X283112Y851918D01*
X283195Y852251D01*
X283112Y852584D01*
X282903Y852834D01*
X282653Y853001D01*
X282320Y853126D01*
X281945Y853168D01*
X281570Y853126D01*
X281237Y853001D01*
X280987Y852834D01*
X280778Y852584D01*
X280695Y852251D01*
G01X282820Y854334D02*
X283028Y854584D01*
X283153Y854876D01*
X283195Y855251D01*
X283112Y855626D01*
X282945Y855918D01*
X282653Y856126D01*
X282320Y856168D01*
X281987Y856084D01*
X281778Y855876D01*
X281612Y855584D01*
X281570Y855293D01*
X281612Y855001D01*
X281778Y854626D01*
X280695Y854751D01*
Y855876D01*
G01X337417Y76492D02*
X337167Y76617D01*
X336875Y76700D01*
X336542D01*
X336167Y76575D01*
X335875Y76367D01*
X335667Y76117D01*
X335500Y75700D01*
X335458Y75325D01*
X335542Y74950D01*
X335667Y74700D01*
X335917Y74450D01*
X336208Y74283D01*
X336500Y74200D01*
X336792D01*
X337083Y74283D01*
X337333Y74408D01*
X337542Y74575D01*
G01X338583Y74700D02*
X338833Y74408D01*
X339167Y74242D01*
X339542Y74200D01*
X339875Y74242D01*
X340208Y74450D01*
X340417Y74700D01*
X340458Y74950D01*
X340375Y75242D01*
X340083Y75450D01*
X339792Y75533D01*
X339417D01*
G01X339792D02*
X340042Y75658D01*
X340250Y75867D01*
X340333Y76117D01*
X340250Y76367D01*
X340042Y76575D01*
X339667Y76700D01*
X339292Y76658D01*
X338917Y76492D01*
G01X342500Y76700D02*
X342167Y76617D01*
X341917Y76408D01*
X341750Y76158D01*
X341625Y75825D01*
X341583Y75450D01*
X341625Y75075D01*
X341750Y74742D01*
X341917Y74492D01*
X342167Y74283D01*
X342500Y74200D01*
X342833Y74283D01*
X343083Y74492D01*
X343250Y74742D01*
X343375Y75075D01*
X343417Y75450D01*
X343375Y75825D01*
X343250Y76158D01*
X343083Y76408D01*
X342833Y76617D01*
X342500Y76700D01*
G01X344708Y76283D02*
X344958Y76533D01*
X345250Y76658D01*
X345583Y76700D01*
X346000Y76617D01*
X346292Y76408D01*
X346375Y76158D01*
X346333Y75908D01*
X346167Y75700D01*
X345333Y75283D01*
X344958Y74992D01*
X344708Y74575D01*
X344625Y74200D01*
X346375D01*
G01X307717Y76192D02*
X307467Y76317D01*
X307175Y76400D01*
X306842D01*
X306467Y76275D01*
X306175Y76067D01*
X305967Y75817D01*
X305800Y75400D01*
X305758Y75025D01*
X305842Y74650D01*
X305967Y74400D01*
X306217Y74150D01*
X306508Y73983D01*
X306800Y73900D01*
X307092D01*
X307383Y73983D01*
X307633Y74108D01*
X307842Y74275D01*
G01X308883Y74400D02*
X309133Y74108D01*
X309467Y73942D01*
X309842Y73900D01*
X310175Y73942D01*
X310508Y74150D01*
X310717Y74400D01*
X310758Y74650D01*
X310675Y74942D01*
X310383Y75150D01*
X310092Y75233D01*
X309717D01*
G01X310092D02*
X310342Y75358D01*
X310550Y75567D01*
X310633Y75817D01*
X310550Y76067D01*
X310342Y76275D01*
X309967Y76400D01*
X309592Y76358D01*
X309217Y76192D01*
G01X312800Y76400D02*
X312467Y76317D01*
X312217Y76108D01*
X312050Y75858D01*
X311925Y75525D01*
X311883Y75150D01*
X311925Y74775D01*
X312050Y74442D01*
X312217Y74192D01*
X312467Y73983D01*
X312800Y73900D01*
X313133Y73983D01*
X313383Y74192D01*
X313550Y74442D01*
X313675Y74775D01*
X313717Y75150D01*
X313675Y75525D01*
X313550Y75858D01*
X313383Y76108D01*
X313133Y76317D01*
X312800Y76400D01*
G01X315800Y73900D02*
Y76400D01*
X315300Y75900D01*
G01Y73900D02*
X316300D01*
G01X356417Y415945D02*
X358917D01*
G01X356417Y414987D02*
Y416903D01*
G01X356625Y419862D02*
X356500Y419612D01*
X356417Y419320D01*
Y418987D01*
X356542Y418612D01*
X356750Y418320D01*
X357000Y418112D01*
X357417Y417945D01*
X357792Y417903D01*
X358167Y417987D01*
X358417Y418112D01*
X358667Y418362D01*
X358834Y418653D01*
X358917Y418945D01*
Y419237D01*
X358834Y419528D01*
X358709Y419778D01*
X358542Y419987D01*
G01X358917Y421945D02*
X356417D01*
X356917Y421445D01*
G01X358917D02*
Y422445D01*
G01X335507Y439411D02*
X335382Y439161D01*
X335299Y438869D01*
Y438536D01*
X335424Y438161D01*
X335632Y437869D01*
X335882Y437661D01*
X336299Y437494D01*
X336674Y437452D01*
X337049Y437536D01*
X337299Y437661D01*
X337549Y437911D01*
X337716Y438202D01*
X337799Y438494D01*
Y438786D01*
X337716Y439077D01*
X337591Y439327D01*
X337424Y439536D01*
G01X337799Y441411D02*
X337257Y441494D01*
X336799Y441619D01*
X336382Y441786D01*
X335924Y441994D01*
X335299Y442327D01*
Y440661D01*
G01X337799Y444411D02*
X337257Y444494D01*
X336799Y444619D01*
X336382Y444786D01*
X335924Y444994D01*
X335299Y445327D01*
Y443661D01*
G01X339608Y440717D02*
X339483Y440467D01*
X339400Y440175D01*
Y439842D01*
X339525Y439467D01*
X339733Y439175D01*
X339983Y438967D01*
X340400Y438800D01*
X340775Y438758D01*
X341150Y438842D01*
X341400Y438967D01*
X341650Y439217D01*
X341817Y439508D01*
X341900Y439800D01*
Y440092D01*
X341817Y440383D01*
X341692Y440633D01*
X341525Y440842D01*
G01X341900Y442800D02*
X341858Y443092D01*
X341733Y443425D01*
X341525Y443633D01*
X341233Y443717D01*
X340942Y443633D01*
X340692Y443383D01*
X340567Y443008D01*
Y442592D01*
X340483Y442342D01*
X340275Y442133D01*
X339983Y442050D01*
X339692Y442175D01*
X339483Y442467D01*
X339400Y442800D01*
X339483Y443133D01*
X339692Y443425D01*
X339983Y443550D01*
X340275Y443467D01*
X340483Y443258D01*
X340567Y443008D01*
Y442592D01*
X340692Y442217D01*
X340942Y441967D01*
X341233Y441883D01*
X341525Y441967D01*
X341733Y442175D01*
X341858Y442508D01*
X341900Y442800D01*
G01Y446300D02*
X339400D01*
X341192Y444758D01*
Y446842D01*
G01X359063Y439111D02*
X358938Y438861D01*
X358855Y438569D01*
Y438236D01*
X358980Y437861D01*
X359188Y437569D01*
X359438Y437361D01*
X359855Y437194D01*
X360230Y437152D01*
X360605Y437236D01*
X360855Y437361D01*
X361105Y437611D01*
X361272Y437902D01*
X361355Y438194D01*
Y438486D01*
X361272Y438777D01*
X361147Y439027D01*
X360980Y439236D01*
G01X361355Y441194D02*
X361313Y441486D01*
X361188Y441819D01*
X360980Y442027D01*
X360688Y442111D01*
X360397Y442027D01*
X360147Y441777D01*
X360022Y441402D01*
Y440986D01*
X359938Y440736D01*
X359730Y440527D01*
X359438Y440444D01*
X359147Y440569D01*
X358938Y440861D01*
X358855Y441194D01*
X358938Y441527D01*
X359147Y441819D01*
X359438Y441944D01*
X359730Y441861D01*
X359938Y441652D01*
X360022Y441402D01*
Y440986D01*
X360147Y440611D01*
X360397Y440361D01*
X360688Y440277D01*
X360980Y440361D01*
X361188Y440569D01*
X361313Y440902D01*
X361355Y441194D01*
G01Y444111D02*
X360813Y444194D01*
X360355Y444319D01*
X359938Y444486D01*
X359480Y444694D01*
X358855Y445027D01*
Y443361D01*
G01X355308Y440917D02*
X355183Y440667D01*
X355100Y440375D01*
Y440042D01*
X355225Y439667D01*
X355433Y439375D01*
X355683Y439167D01*
X356100Y439000D01*
X356475Y438958D01*
X356850Y439042D01*
X357100Y439167D01*
X357350Y439417D01*
X357517Y439708D01*
X357600Y440000D01*
Y440292D01*
X357517Y440583D01*
X357392Y440833D01*
X357225Y441042D01*
G01X357600Y443000D02*
X355100D01*
X355600Y442500D01*
G01X357600D02*
Y443500D01*
G01X355100Y446000D02*
X355183Y445667D01*
X355392Y445417D01*
X355642Y445250D01*
X355975Y445125D01*
X356350Y445083D01*
X356725Y445125D01*
X357058Y445250D01*
X357308Y445417D01*
X357517Y445667D01*
X357600Y446000D01*
X357517Y446333D01*
X357308Y446583D01*
X357058Y446750D01*
X356725Y446875D01*
X356350Y446917D01*
X355975Y446875D01*
X355642Y446750D01*
X355392Y446583D01*
X355183Y446333D01*
X355100Y446000D01*
G01X355517Y448208D02*
X355267Y448458D01*
X355142Y448750D01*
X355100Y449083D01*
X355183Y449500D01*
X355392Y449792D01*
X355642Y449875D01*
X355892Y449833D01*
X356100Y449667D01*
X356517Y448833D01*
X356808Y448458D01*
X357225Y448208D01*
X357600Y448125D01*
Y449875D01*
G01X351392Y438501D02*
X351267Y438251D01*
X351184Y437959D01*
Y437626D01*
X351309Y437251D01*
X351517Y436959D01*
X351767Y436751D01*
X352184Y436584D01*
X352559Y436542D01*
X352934Y436626D01*
X353184Y436751D01*
X353434Y437001D01*
X353601Y437292D01*
X353684Y437584D01*
Y437876D01*
X353601Y438167D01*
X353476Y438417D01*
X353309Y438626D01*
G01X353684Y440584D02*
X351184D01*
X351684Y440084D01*
G01X353684D02*
Y441084D01*
G01X351184Y443584D02*
X351267Y443251D01*
X351476Y443001D01*
X351726Y442834D01*
X352059Y442709D01*
X352434Y442667D01*
X352809Y442709D01*
X353142Y442834D01*
X353392Y443001D01*
X353601Y443251D01*
X353684Y443584D01*
X353601Y443917D01*
X353392Y444167D01*
X353142Y444334D01*
X352809Y444459D01*
X352434Y444501D01*
X352059Y444459D01*
X351726Y444334D01*
X351476Y444167D01*
X351267Y443917D01*
X351184Y443584D01*
G01X353184Y445667D02*
X353476Y445917D01*
X353642Y446251D01*
X353684Y446626D01*
X353642Y446959D01*
X353434Y447292D01*
X353184Y447501D01*
X352934Y447542D01*
X352642Y447459D01*
X352434Y447167D01*
X352351Y446876D01*
Y446501D01*
G01Y446876D02*
X352226Y447126D01*
X352017Y447334D01*
X351767Y447417D01*
X351517Y447334D01*
X351309Y447126D01*
X351184Y446751D01*
X351226Y446376D01*
X351392Y446001D01*
G01X347708Y440917D02*
X347583Y440667D01*
X347500Y440375D01*
Y440042D01*
X347625Y439667D01*
X347833Y439375D01*
X348083Y439167D01*
X348500Y439000D01*
X348875Y438958D01*
X349250Y439042D01*
X349500Y439167D01*
X349750Y439417D01*
X349917Y439708D01*
X350000Y440000D01*
Y440292D01*
X349917Y440583D01*
X349792Y440833D01*
X349625Y441042D01*
G01X350000Y443000D02*
X347500D01*
X348000Y442500D01*
G01X350000D02*
Y443500D01*
G01X347500Y446000D02*
X347583Y445667D01*
X347792Y445417D01*
X348042Y445250D01*
X348375Y445125D01*
X348750Y445083D01*
X349125Y445125D01*
X349458Y445250D01*
X349708Y445417D01*
X349917Y445667D01*
X350000Y446000D01*
X349917Y446333D01*
X349708Y446583D01*
X349458Y446750D01*
X349125Y446875D01*
X348750Y446917D01*
X348375Y446875D01*
X348042Y446750D01*
X347792Y446583D01*
X347583Y446333D01*
X347500Y446000D01*
G01X350000Y449500D02*
X347500D01*
X349292Y447958D01*
Y450042D01*
G01X343923Y438460D02*
X343798Y438210D01*
X343715Y437918D01*
Y437585D01*
X343840Y437210D01*
X344048Y436918D01*
X344298Y436710D01*
X344715Y436543D01*
X345090Y436501D01*
X345465Y436585D01*
X345715Y436710D01*
X345965Y436960D01*
X346132Y437251D01*
X346215Y437543D01*
Y437835D01*
X346132Y438126D01*
X346007Y438376D01*
X345840Y438585D01*
G01X346215Y440543D02*
X343715D01*
X344215Y440043D01*
G01X346215D02*
Y441043D01*
G01X343715Y443543D02*
X343798Y443210D01*
X344007Y442960D01*
X344257Y442793D01*
X344590Y442668D01*
X344965Y442626D01*
X345340Y442668D01*
X345673Y442793D01*
X345923Y442960D01*
X346132Y443210D01*
X346215Y443543D01*
X346132Y443876D01*
X345923Y444126D01*
X345673Y444293D01*
X345340Y444418D01*
X344965Y444460D01*
X344590Y444418D01*
X344257Y444293D01*
X344007Y444126D01*
X343798Y443876D01*
X343715Y443543D01*
G01X345840Y445626D02*
X346048Y445876D01*
X346173Y446168D01*
X346215Y446543D01*
X346132Y446918D01*
X345965Y447210D01*
X345673Y447418D01*
X345340Y447460D01*
X345007Y447376D01*
X344798Y447168D01*
X344632Y446876D01*
X344590Y446585D01*
X344632Y446293D01*
X344798Y445918D01*
X343715Y446043D01*
Y447168D01*
G01X357821Y487210D02*
X360321D01*
G01X357821Y486252D02*
Y488168D01*
G01X358029Y491127D02*
X357904Y490877D01*
X357821Y490585D01*
Y490252D01*
X357946Y489877D01*
X358154Y489585D01*
X358404Y489377D01*
X358821Y489210D01*
X359196Y489168D01*
X359571Y489252D01*
X359821Y489377D01*
X360071Y489627D01*
X360238Y489918D01*
X360321Y490210D01*
Y490502D01*
X360238Y490793D01*
X360113Y491043D01*
X359946Y491252D01*
G01X360321Y493710D02*
X357821D01*
X359613Y492168D01*
Y494252D01*
G01X335300Y454446D02*
X337800D01*
G01X335300Y453488D02*
Y455404D01*
G01X335508Y458363D02*
X335383Y458113D01*
X335300Y457821D01*
Y457488D01*
X335425Y457113D01*
X335633Y456821D01*
X335883Y456613D01*
X336300Y456446D01*
X336675Y456404D01*
X337050Y456488D01*
X337300Y456613D01*
X337550Y456863D01*
X337717Y457154D01*
X337800Y457446D01*
Y457738D01*
X337717Y458029D01*
X337592Y458279D01*
X337425Y458488D01*
G01X336758Y459654D02*
X336467Y459946D01*
X336300Y460196D01*
X336217Y460529D01*
X336300Y460821D01*
X336467Y461029D01*
X336717Y461196D01*
X337008Y461238D01*
X337258Y461196D01*
X337508Y461029D01*
X337717Y460779D01*
X337800Y460488D01*
X337717Y460154D01*
X337467Y459863D01*
X337092Y459696D01*
X336675Y459654D01*
X336133Y459738D01*
X335842Y459863D01*
X335550Y460071D01*
X335342Y460363D01*
X335300Y460654D01*
X335383Y460946D01*
X335592Y461154D01*
G01X312000Y432767D02*
X309500D01*
Y433767D01*
X309625Y434100D01*
X309917Y434350D01*
X310250Y434433D01*
X310583Y434350D01*
X310833Y434142D01*
X310958Y433767D01*
Y432767D01*
G01X309708Y437517D02*
X309583Y437267D01*
X309500Y436975D01*
Y436642D01*
X309625Y436267D01*
X309833Y435975D01*
X310083Y435767D01*
X310500Y435600D01*
X310875Y435558D01*
X311250Y435642D01*
X311500Y435767D01*
X311750Y436017D01*
X311917Y436308D01*
X312000Y436600D01*
Y436892D01*
X311917Y437183D01*
X311792Y437433D01*
X311625Y437642D01*
G01X312000Y439517D02*
X311458Y439600D01*
X311000Y439725D01*
X310583Y439892D01*
X310125Y440100D01*
X309500Y440433D01*
Y438767D01*
G01X341159Y530010D02*
X338659D01*
Y531051D01*
X338784Y531385D01*
X338951Y531593D01*
X339284Y531676D01*
X339617Y531593D01*
X339826Y531343D01*
X339951Y531051D01*
Y530010D01*
G01Y531051D02*
X341159Y531676D01*
G01Y534343D02*
X338659D01*
X340451Y532801D01*
Y534885D01*
G01X341159Y536843D02*
X338659D01*
X339159Y536343D01*
G01X341159D02*
Y537343D01*
G01X341071Y539077D02*
X338571D01*
Y540118D01*
X338696Y540452D01*
X338863Y540660D01*
X339196Y540743D01*
X339529Y540660D01*
X339738Y540410D01*
X339863Y540118D01*
Y539077D01*
G01Y540118D02*
X341071Y540743D01*
G01Y542910D02*
X338571D01*
X339071Y542410D01*
G01X341071D02*
Y543410D01*
G01X355850Y531496D02*
X355725Y531246D01*
X355642Y530954D01*
Y530621D01*
X355767Y530246D01*
X355975Y529954D01*
X356225Y529746D01*
X356642Y529579D01*
X357017Y529537D01*
X357392Y529621D01*
X357642Y529746D01*
X357892Y529996D01*
X358059Y530287D01*
X358142Y530579D01*
Y530871D01*
X358059Y531162D01*
X357934Y531412D01*
X357767Y531621D01*
G01X357100Y532787D02*
X356809Y533079D01*
X356642Y533329D01*
X356559Y533662D01*
X356642Y533954D01*
X356809Y534162D01*
X357059Y534329D01*
X357350Y534371D01*
X357600Y534329D01*
X357850Y534162D01*
X358059Y533912D01*
X358142Y533621D01*
X358059Y533287D01*
X357809Y532996D01*
X357434Y532829D01*
X357017Y532787D01*
X356475Y532871D01*
X356184Y532996D01*
X355892Y533204D01*
X355684Y533496D01*
X355642Y533787D01*
X355725Y534079D01*
X355934Y534287D01*
G01X358142Y536496D02*
X357600Y536579D01*
X357142Y536704D01*
X356725Y536871D01*
X356267Y537079D01*
X355642Y537412D01*
Y535746D01*
G01X296690Y494654D02*
X299190D01*
G01X296690Y493696D02*
Y495612D01*
G01X296898Y498571D02*
X296773Y498321D01*
X296690Y498029D01*
Y497696D01*
X296815Y497321D01*
X297023Y497029D01*
X297273Y496821D01*
X297690Y496654D01*
X298065Y496612D01*
X298440Y496696D01*
X298690Y496821D01*
X298940Y497071D01*
X299107Y497362D01*
X299190Y497654D01*
Y497946D01*
X299107Y498237D01*
X298982Y498487D01*
X298815Y498696D01*
G01Y499737D02*
X299023Y499987D01*
X299148Y500279D01*
X299190Y500654D01*
X299107Y501029D01*
X298940Y501321D01*
X298648Y501529D01*
X298315Y501571D01*
X297982Y501487D01*
X297773Y501279D01*
X297607Y500987D01*
X297565Y500696D01*
X297607Y500404D01*
X297773Y500029D01*
X296690Y500154D01*
Y501279D01*
G01X326731Y494636D02*
X329231D01*
G01X326731Y493678D02*
Y495594D01*
G01X326939Y498553D02*
X326814Y498303D01*
X326731Y498011D01*
Y497678D01*
X326856Y497303D01*
X327064Y497011D01*
X327314Y496803D01*
X327731Y496636D01*
X328106Y496594D01*
X328481Y496678D01*
X328731Y496803D01*
X328981Y497053D01*
X329148Y497344D01*
X329231Y497636D01*
Y497928D01*
X329148Y498219D01*
X329023Y498469D01*
X328856Y498678D01*
G01X328731Y499719D02*
X329023Y499969D01*
X329189Y500303D01*
X329231Y500678D01*
X329189Y501011D01*
X328981Y501344D01*
X328731Y501553D01*
X328481Y501594D01*
X328189Y501511D01*
X327981Y501219D01*
X327898Y500928D01*
Y500553D01*
G01Y500928D02*
X327773Y501178D01*
X327564Y501386D01*
X327314Y501469D01*
X327064Y501386D01*
X326856Y501178D01*
X326731Y500803D01*
X326773Y500428D01*
X326939Y500053D01*
G01X342655Y545241D02*
Y547741D01*
X343696D01*
X344030Y547616D01*
X344238Y547449D01*
X344321Y547116D01*
X344238Y546783D01*
X343988Y546574D01*
X343696Y546449D01*
X342655D01*
G01X343696D02*
X344321Y545241D01*
G01X346488D02*
X346780Y545283D01*
X347113Y545408D01*
X347321Y545616D01*
X347405Y545908D01*
X347321Y546199D01*
X347071Y546449D01*
X346696Y546574D01*
X346280D01*
X346030Y546658D01*
X345821Y546866D01*
X345738Y547158D01*
X345863Y547449D01*
X346155Y547658D01*
X346488Y547741D01*
X346821Y547658D01*
X347113Y547449D01*
X347238Y547158D01*
X347155Y546866D01*
X346946Y546658D01*
X346696Y546574D01*
X346280D01*
X345905Y546449D01*
X345655Y546199D01*
X345571Y545908D01*
X345655Y545616D01*
X345863Y545408D01*
X346196Y545283D01*
X346488Y545241D01*
G01X340895Y554740D02*
X338395D01*
Y555781D01*
X338520Y556115D01*
X338687Y556323D01*
X339020Y556406D01*
X339353Y556323D01*
X339562Y556073D01*
X339687Y555781D01*
Y554740D01*
G01Y555781D02*
X340895Y556406D01*
G01Y558490D02*
X340353Y558573D01*
X339895Y558698D01*
X339478Y558865D01*
X339020Y559073D01*
X338395Y559406D01*
Y557740D01*
G01X340719Y546821D02*
X338219D01*
Y547862D01*
X338344Y548196D01*
X338511Y548404D01*
X338844Y548487D01*
X339177Y548404D01*
X339386Y548154D01*
X339511Y547862D01*
Y546821D01*
G01Y547862D02*
X340719Y548487D01*
G01X339677Y549862D02*
X339386Y550154D01*
X339219Y550404D01*
X339136Y550737D01*
X339219Y551029D01*
X339386Y551237D01*
X339636Y551404D01*
X339927Y551446D01*
X340177Y551404D01*
X340427Y551237D01*
X340636Y550987D01*
X340719Y550696D01*
X340636Y550362D01*
X340386Y550071D01*
X340011Y549904D01*
X339594Y549862D01*
X339052Y549946D01*
X338761Y550071D01*
X338469Y550279D01*
X338261Y550571D01*
X338219Y550862D01*
X338302Y551154D01*
X338511Y551362D01*
G01X342655Y549113D02*
Y551613D01*
X343696D01*
X344030Y551488D01*
X344238Y551321D01*
X344321Y550988D01*
X344238Y550655D01*
X343988Y550446D01*
X343696Y550321D01*
X342655D01*
G01X343696D02*
X344321Y549113D01*
G01X346988D02*
Y551613D01*
X345446Y549821D01*
X347530D01*
G01X342655Y553512D02*
Y556012D01*
X343696D01*
X344030Y555887D01*
X344238Y555720D01*
X344321Y555387D01*
X344238Y555054D01*
X343988Y554845D01*
X343696Y554720D01*
X342655D01*
G01X343696D02*
X344321Y553512D01*
G01X345571Y554012D02*
X345821Y553720D01*
X346155Y553554D01*
X346530Y553512D01*
X346863Y553554D01*
X347196Y553762D01*
X347405Y554012D01*
X347446Y554262D01*
X347363Y554554D01*
X347071Y554762D01*
X346780Y554845D01*
X346405D01*
G01X346780D02*
X347030Y554970D01*
X347238Y555179D01*
X347321Y555429D01*
X347238Y555679D01*
X347030Y555887D01*
X346655Y556012D01*
X346280Y555970D01*
X345905Y555804D01*
G01X352154Y531496D02*
X352029Y531246D01*
X351946Y530954D01*
Y530621D01*
X352071Y530246D01*
X352279Y529954D01*
X352529Y529746D01*
X352946Y529579D01*
X353321Y529537D01*
X353696Y529621D01*
X353946Y529746D01*
X354196Y529996D01*
X354363Y530287D01*
X354446Y530579D01*
Y530871D01*
X354363Y531162D01*
X354238Y531412D01*
X354071Y531621D01*
G01X353404Y532787D02*
X353113Y533079D01*
X352946Y533329D01*
X352863Y533662D01*
X352946Y533954D01*
X353113Y534162D01*
X353363Y534329D01*
X353654Y534371D01*
X353904Y534329D01*
X354154Y534162D01*
X354363Y533912D01*
X354446Y533621D01*
X354363Y533287D01*
X354113Y532996D01*
X353738Y532829D01*
X353321Y532787D01*
X352779Y532871D01*
X352488Y532996D01*
X352196Y533204D01*
X351988Y533496D01*
X351946Y533787D01*
X352029Y534079D01*
X352238Y534287D01*
G01X353404Y535787D02*
X353113Y536079D01*
X352946Y536329D01*
X352863Y536662D01*
X352946Y536954D01*
X353113Y537162D01*
X353363Y537329D01*
X353654Y537371D01*
X353904Y537329D01*
X354154Y537162D01*
X354363Y536912D01*
X354446Y536621D01*
X354363Y536287D01*
X354113Y535996D01*
X353738Y535829D01*
X353321Y535787D01*
X352779Y535871D01*
X352488Y535996D01*
X352196Y536204D01*
X351988Y536496D01*
X351946Y536787D01*
X352029Y537079D01*
X352238Y537287D01*
G01X347402Y531496D02*
X347277Y531246D01*
X347194Y530954D01*
Y530621D01*
X347319Y530246D01*
X347527Y529954D01*
X347777Y529746D01*
X348194Y529579D01*
X348569Y529537D01*
X348944Y529621D01*
X349194Y529746D01*
X349444Y529996D01*
X349611Y530287D01*
X349694Y530579D01*
Y530871D01*
X349611Y531162D01*
X349486Y531412D01*
X349319Y531621D01*
G01X348652Y532787D02*
X348361Y533079D01*
X348194Y533329D01*
X348111Y533662D01*
X348194Y533954D01*
X348361Y534162D01*
X348611Y534329D01*
X348902Y534371D01*
X349152Y534329D01*
X349402Y534162D01*
X349611Y533912D01*
X349694Y533621D01*
X349611Y533287D01*
X349361Y532996D01*
X348986Y532829D01*
X348569Y532787D01*
X348027Y532871D01*
X347736Y532996D01*
X347444Y533204D01*
X347236Y533496D01*
X347194Y533787D01*
X347277Y534079D01*
X347486Y534287D01*
G01X349319Y535662D02*
X349527Y535912D01*
X349652Y536204D01*
X349694Y536579D01*
X349611Y536954D01*
X349444Y537246D01*
X349152Y537454D01*
X348819Y537496D01*
X348486Y537412D01*
X348277Y537204D01*
X348111Y536912D01*
X348069Y536621D01*
X348111Y536329D01*
X348277Y535954D01*
X347194Y536079D01*
Y537204D01*
G01X342970Y529922D02*
X345470D01*
Y531588D01*
G01X345095Y532838D02*
X345303Y533088D01*
X345428Y533380D01*
X345470Y533755D01*
X345387Y534130D01*
X345220Y534422D01*
X344928Y534630D01*
X344595Y534672D01*
X344262Y534588D01*
X344053Y534380D01*
X343887Y534088D01*
X343845Y533797D01*
X343887Y533505D01*
X344053Y533130D01*
X342970Y533255D01*
Y534380D01*
G01X345470Y536755D02*
X345428Y537047D01*
X345303Y537380D01*
X345095Y537588D01*
X344803Y537672D01*
X344512Y537588D01*
X344262Y537338D01*
X344137Y536963D01*
Y536547D01*
X344053Y536297D01*
X343845Y536088D01*
X343553Y536005D01*
X343262Y536130D01*
X343053Y536422D01*
X342970Y536755D01*
X343053Y537088D01*
X343262Y537380D01*
X343553Y537505D01*
X343845Y537422D01*
X344053Y537213D01*
X344137Y536963D01*
Y536547D01*
X344262Y536172D01*
X344512Y535922D01*
X344803Y535838D01*
X345095Y535922D01*
X345303Y536130D01*
X345428Y536463D01*
X345470Y536755D01*
G01X342618Y539165D02*
X345118D01*
Y540831D01*
G01Y542998D02*
X342618D01*
X343118Y542498D01*
G01X345118D02*
Y543498D01*
G01X344405Y560028D02*
X344155Y560153D01*
X343863Y560236D01*
X343530D01*
X343155Y560111D01*
X342863Y559903D01*
X342655Y559653D01*
X342488Y559236D01*
X342446Y558861D01*
X342530Y558486D01*
X342655Y558236D01*
X342905Y557986D01*
X343196Y557819D01*
X343488Y557736D01*
X343780D01*
X344071Y557819D01*
X344321Y557944D01*
X344530Y558111D01*
G01X345571Y558236D02*
X345821Y557944D01*
X346155Y557778D01*
X346530Y557736D01*
X346863Y557778D01*
X347196Y557986D01*
X347405Y558236D01*
X347446Y558486D01*
X347363Y558778D01*
X347071Y558986D01*
X346780Y559069D01*
X346405D01*
G01X346780D02*
X347030Y559194D01*
X347238Y559403D01*
X347321Y559653D01*
X347238Y559903D01*
X347030Y560111D01*
X346655Y560236D01*
X346280Y560194D01*
X345905Y560028D01*
G01X331633Y768694D02*
X334133D01*
G01X331633Y767736D02*
Y769652D01*
G01X334133Y770861D02*
X331633D01*
Y771861D01*
X331758Y772194D01*
X332050Y772444D01*
X332383Y772527D01*
X332716Y772444D01*
X332966Y772236D01*
X333091Y771861D01*
Y770861D01*
G01X334133Y774694D02*
X331633D01*
X332133Y774194D01*
G01X334133D02*
Y775194D01*
G01X333091Y776902D02*
X332800Y777194D01*
X332633Y777444D01*
X332550Y777777D01*
X332633Y778069D01*
X332800Y778277D01*
X333050Y778444D01*
X333341Y778486D01*
X333591Y778444D01*
X333841Y778277D01*
X334050Y778027D01*
X334133Y777736D01*
X334050Y777402D01*
X333800Y777111D01*
X333425Y776944D01*
X333008Y776902D01*
X332466Y776986D01*
X332175Y777111D01*
X331883Y777319D01*
X331675Y777611D01*
X331633Y777902D01*
X331716Y778194D01*
X331925Y778402D01*
G01X333633Y779777D02*
X333925Y780027D01*
X334091Y780361D01*
X334133Y780736D01*
X334091Y781069D01*
X333883Y781402D01*
X333633Y781611D01*
X333383Y781652D01*
X333091Y781569D01*
X332883Y781277D01*
X332800Y780986D01*
Y780611D01*
G01Y780986D02*
X332675Y781236D01*
X332466Y781444D01*
X332216Y781527D01*
X331966Y781444D01*
X331758Y781236D01*
X331633Y780861D01*
X331675Y780486D01*
X331841Y780111D01*
G01X331329Y797176D02*
Y799676D01*
X332370D01*
X332704Y799551D01*
X332912Y799384D01*
X332995Y799051D01*
X332912Y798718D01*
X332662Y798509D01*
X332370Y798384D01*
X331329D01*
G01X332370D02*
X332995Y797176D01*
G01X335162D02*
Y799676D01*
X334662Y799176D01*
G01Y797176D02*
X335662D01*
G01X337454Y797468D02*
X337745Y797259D01*
X338079Y797176D01*
X338412Y797259D01*
X338704Y797509D01*
X338912Y797884D01*
X338995Y798259D01*
Y798718D01*
X338912Y799093D01*
X338704Y799426D01*
X338454Y799593D01*
X338162Y799676D01*
X337829Y799593D01*
X337579Y799426D01*
X337412Y799176D01*
X337329Y798843D01*
X337412Y798551D01*
X337620Y798259D01*
X337870Y798093D01*
X338162Y798051D01*
X338495Y798134D01*
X338745Y798343D01*
X338995Y798718D01*
G01X340370Y799259D02*
X340620Y799509D01*
X340912Y799634D01*
X341245Y799676D01*
X341662Y799593D01*
X341954Y799384D01*
X342037Y799134D01*
X341995Y798884D01*
X341829Y798676D01*
X340995Y798259D01*
X340620Y797968D01*
X340370Y797551D01*
X340287Y797176D01*
X342037D01*
G01X348107Y786852D02*
Y789352D01*
X349148D01*
X349482Y789227D01*
X349690Y789060D01*
X349773Y788727D01*
X349690Y788394D01*
X349440Y788185D01*
X349148Y788060D01*
X348107D01*
G01X349148D02*
X349773Y786852D01*
G01X351940D02*
Y789352D01*
X351440Y788852D01*
G01Y786852D02*
X352440D01*
G01X354232Y787144D02*
X354523Y786935D01*
X354857Y786852D01*
X355190Y786935D01*
X355482Y787185D01*
X355690Y787560D01*
X355773Y787935D01*
Y788394D01*
X355690Y788769D01*
X355482Y789102D01*
X355232Y789269D01*
X354940Y789352D01*
X354607Y789269D01*
X354357Y789102D01*
X354190Y788852D01*
X354107Y788519D01*
X354190Y788227D01*
X354398Y787935D01*
X354648Y787769D01*
X354940Y787727D01*
X355273Y787810D01*
X355523Y788019D01*
X355773Y788394D01*
G01X358440Y786852D02*
Y789352D01*
X356898Y787560D01*
X358982D01*
G01X299889Y800021D02*
Y802521D01*
X300930D01*
X301264Y802396D01*
X301472Y802229D01*
X301555Y801896D01*
X301472Y801563D01*
X301222Y801354D01*
X300930Y801229D01*
X299889D01*
G01X300930D02*
X301555Y800021D01*
G01X303722D02*
Y802521D01*
X303222Y802021D01*
G01Y800021D02*
X304222D01*
G01X306722D02*
X307014Y800063D01*
X307347Y800188D01*
X307555Y800396D01*
X307639Y800688D01*
X307555Y800979D01*
X307305Y801229D01*
X306930Y801354D01*
X306514D01*
X306264Y801438D01*
X306055Y801646D01*
X305972Y801938D01*
X306097Y802229D01*
X306389Y802438D01*
X306722Y802521D01*
X307055Y802438D01*
X307347Y802229D01*
X307472Y801938D01*
X307389Y801646D01*
X307180Y801438D01*
X306930Y801354D01*
X306514D01*
X306139Y801229D01*
X305889Y800979D01*
X305805Y800688D01*
X305889Y800396D01*
X306097Y800188D01*
X306430Y800063D01*
X306722Y800021D01*
G01X309014Y800313D02*
X309305Y800104D01*
X309639Y800021D01*
X309972Y800104D01*
X310264Y800354D01*
X310472Y800729D01*
X310555Y801104D01*
Y801563D01*
X310472Y801938D01*
X310264Y802271D01*
X310014Y802438D01*
X309722Y802521D01*
X309389Y802438D01*
X309139Y802271D01*
X308972Y802021D01*
X308889Y801688D01*
X308972Y801396D01*
X309180Y801104D01*
X309430Y800938D01*
X309722Y800896D01*
X310055Y800979D01*
X310305Y801188D01*
X310555Y801563D01*
G01X345906Y777848D02*
X343406D01*
Y778889D01*
X343531Y779223D01*
X343698Y779431D01*
X344031Y779514D01*
X344364Y779431D01*
X344573Y779181D01*
X344698Y778889D01*
Y777848D01*
G01Y778889D02*
X345906Y779514D01*
G01Y781681D02*
X343406D01*
X343906Y781181D01*
G01X345906D02*
Y782181D01*
G01Y784681D02*
X345864Y784973D01*
X345739Y785306D01*
X345531Y785514D01*
X345239Y785598D01*
X344948Y785514D01*
X344698Y785264D01*
X344573Y784889D01*
Y784473D01*
X344489Y784223D01*
X344281Y784014D01*
X343989Y783931D01*
X343698Y784056D01*
X343489Y784348D01*
X343406Y784681D01*
X343489Y785014D01*
X343698Y785306D01*
X343989Y785431D01*
X344281Y785348D01*
X344489Y785139D01*
X344573Y784889D01*
Y784473D01*
X344698Y784098D01*
X344948Y783848D01*
X345239Y783764D01*
X345531Y783848D01*
X345739Y784056D01*
X345864Y784389D01*
X345906Y784681D01*
G01X344864Y786889D02*
X344573Y787181D01*
X344406Y787431D01*
X344323Y787764D01*
X344406Y788056D01*
X344573Y788264D01*
X344823Y788431D01*
X345114Y788473D01*
X345364Y788431D01*
X345614Y788264D01*
X345823Y788014D01*
X345906Y787723D01*
X345823Y787389D01*
X345573Y787098D01*
X345198Y786931D01*
X344781Y786889D01*
X344239Y786973D01*
X343948Y787098D01*
X343656Y787306D01*
X343448Y787598D01*
X343406Y787889D01*
X343489Y788181D01*
X343698Y788389D01*
G01X309493Y787050D02*
Y789550D01*
X310534D01*
X310868Y789425D01*
X311076Y789258D01*
X311159Y788925D01*
X311076Y788592D01*
X310826Y788383D01*
X310534Y788258D01*
X309493D01*
G01X310534D02*
X311159Y787050D01*
G01X313326D02*
Y789550D01*
X312826Y789050D01*
G01Y787050D02*
X313826D01*
G01X316326D02*
X316618Y787092D01*
X316951Y787217D01*
X317159Y787425D01*
X317243Y787717D01*
X317159Y788008D01*
X316909Y788258D01*
X316534Y788383D01*
X316118D01*
X315868Y788467D01*
X315659Y788675D01*
X315576Y788967D01*
X315701Y789258D01*
X315993Y789467D01*
X316326Y789550D01*
X316659Y789467D01*
X316951Y789258D01*
X317076Y788967D01*
X316993Y788675D01*
X316784Y788467D01*
X316534Y788383D01*
X316118D01*
X315743Y788258D01*
X315493Y788008D01*
X315409Y787717D01*
X315493Y787425D01*
X315701Y787217D01*
X316034Y787092D01*
X316326Y787050D01*
G01X319826D02*
Y789550D01*
X318284Y787758D01*
X320368D01*
G01X292017Y787001D02*
Y789501D01*
X293058D01*
X293392Y789376D01*
X293600Y789209D01*
X293683Y788876D01*
X293600Y788543D01*
X293350Y788334D01*
X293058Y788209D01*
X292017D01*
G01X293058D02*
X293683Y787001D01*
G01X295850D02*
Y789501D01*
X295350Y789001D01*
G01Y787001D02*
X296350D01*
G01X298850D02*
X299142Y787043D01*
X299475Y787168D01*
X299683Y787376D01*
X299767Y787668D01*
X299683Y787959D01*
X299433Y788209D01*
X299058Y788334D01*
X298642D01*
X298392Y788418D01*
X298183Y788626D01*
X298100Y788918D01*
X298225Y789209D01*
X298517Y789418D01*
X298850Y789501D01*
X299183Y789418D01*
X299475Y789209D01*
X299600Y788918D01*
X299517Y788626D01*
X299308Y788418D01*
X299058Y788334D01*
X298642D01*
X298267Y788209D01*
X298017Y787959D01*
X297933Y787668D01*
X298017Y787376D01*
X298225Y787168D01*
X298558Y787043D01*
X298850Y787001D01*
G01X300933Y787501D02*
X301183Y787209D01*
X301517Y787043D01*
X301892Y787001D01*
X302225Y787043D01*
X302558Y787251D01*
X302767Y787501D01*
X302808Y787751D01*
X302725Y788043D01*
X302433Y788251D01*
X302142Y788334D01*
X301767D01*
G01X302142D02*
X302392Y788459D01*
X302600Y788668D01*
X302683Y788918D01*
X302600Y789168D01*
X302392Y789376D01*
X302017Y789501D01*
X301642Y789459D01*
X301267Y789293D01*
G01X323580Y772049D02*
X326080D01*
G01X323580Y771091D02*
Y773007D01*
G01X326080Y774216D02*
X323580D01*
Y775216D01*
X323705Y775549D01*
X323997Y775799D01*
X324330Y775882D01*
X324663Y775799D01*
X324913Y775591D01*
X325038Y775216D01*
Y774216D01*
G01X326080Y778049D02*
X323580D01*
X324080Y777549D01*
G01X326080D02*
Y778549D01*
G01X325038Y780257D02*
X324747Y780549D01*
X324580Y780799D01*
X324497Y781132D01*
X324580Y781424D01*
X324747Y781632D01*
X324997Y781799D01*
X325288Y781841D01*
X325538Y781799D01*
X325788Y781632D01*
X325997Y781382D01*
X326080Y781091D01*
X325997Y780757D01*
X325747Y780466D01*
X325372Y780299D01*
X324955Y780257D01*
X324413Y780341D01*
X324122Y780466D01*
X323830Y780674D01*
X323622Y780966D01*
X323580Y781257D01*
X323663Y781549D01*
X323872Y781757D01*
G01X323997Y783257D02*
X323747Y783507D01*
X323622Y783799D01*
X323580Y784132D01*
X323663Y784549D01*
X323872Y784841D01*
X324122Y784924D01*
X324372Y784882D01*
X324580Y784716D01*
X324997Y783882D01*
X325288Y783507D01*
X325705Y783257D01*
X326080Y783174D01*
Y784924D01*
G01X319917Y846459D02*
X319667Y846584D01*
X319375Y846667D01*
X319042D01*
X318667Y846542D01*
X318375Y846334D01*
X318167Y846084D01*
X318000Y845667D01*
X317958Y845292D01*
X318042Y844917D01*
X318167Y844667D01*
X318417Y844417D01*
X318708Y844250D01*
X319000Y844167D01*
X319292D01*
X319583Y844250D01*
X319833Y844375D01*
X320042Y844542D01*
G01X321042Y844167D02*
Y846667D01*
X322958Y844167D01*
Y846667D01*
G01X325000Y844167D02*
Y846667D01*
X324500Y846167D01*
G01Y844167D02*
X325500D01*
G01X328000Y846667D02*
X327667Y846584D01*
X327417Y846375D01*
X327250Y846125D01*
X327125Y845792D01*
X327083Y845417D01*
X327125Y845042D01*
X327250Y844709D01*
X327417Y844459D01*
X327667Y844250D01*
X328000Y844167D01*
X328333Y844250D01*
X328583Y844459D01*
X328750Y844709D01*
X328875Y845042D01*
X328917Y845417D01*
X328875Y845792D01*
X328750Y846125D01*
X328583Y846375D01*
X328333Y846584D01*
X328000Y846667D01*
G01X367917Y76192D02*
X367667Y76317D01*
X367375Y76400D01*
X367042D01*
X366667Y76275D01*
X366375Y76067D01*
X366167Y75817D01*
X366000Y75400D01*
X365958Y75025D01*
X366042Y74650D01*
X366167Y74400D01*
X366417Y74150D01*
X366708Y73983D01*
X367000Y73900D01*
X367292D01*
X367583Y73983D01*
X367833Y74108D01*
X368042Y74275D01*
G01X369083Y74400D02*
X369333Y74108D01*
X369667Y73942D01*
X370042Y73900D01*
X370375Y73942D01*
X370708Y74150D01*
X370917Y74400D01*
X370958Y74650D01*
X370875Y74942D01*
X370583Y75150D01*
X370292Y75233D01*
X369917D01*
G01X370292D02*
X370542Y75358D01*
X370750Y75567D01*
X370833Y75817D01*
X370750Y76067D01*
X370542Y76275D01*
X370167Y76400D01*
X369792Y76358D01*
X369417Y76192D01*
G01X373000Y76400D02*
X372667Y76317D01*
X372417Y76108D01*
X372250Y75858D01*
X372125Y75525D01*
X372083Y75150D01*
X372125Y74775D01*
X372250Y74442D01*
X372417Y74192D01*
X372667Y73983D01*
X373000Y73900D01*
X373333Y73983D01*
X373583Y74192D01*
X373750Y74442D01*
X373875Y74775D01*
X373917Y75150D01*
X373875Y75525D01*
X373750Y75858D01*
X373583Y76108D01*
X373333Y76317D01*
X373000Y76400D01*
G01X375083Y74400D02*
X375333Y74108D01*
X375667Y73942D01*
X376042Y73900D01*
X376375Y73942D01*
X376708Y74150D01*
X376917Y74400D01*
X376958Y74650D01*
X376875Y74942D01*
X376583Y75150D01*
X376292Y75233D01*
X375917D01*
G01X376292D02*
X376542Y75358D01*
X376750Y75567D01*
X376833Y75817D01*
X376750Y76067D01*
X376542Y76275D01*
X376167Y76400D01*
X375792Y76358D01*
X375417Y76192D01*
G01X393408Y383417D02*
X393283Y383167D01*
X393200Y382875D01*
Y382542D01*
X393325Y382167D01*
X393533Y381875D01*
X393783Y381667D01*
X394200Y381500D01*
X394575Y381458D01*
X394950Y381542D01*
X395200Y381667D01*
X395450Y381917D01*
X395617Y382208D01*
X395700Y382500D01*
Y382792D01*
X395617Y383083D01*
X395492Y383333D01*
X395325Y383542D01*
G01X395700Y385417D02*
X395158Y385500D01*
X394700Y385625D01*
X394283Y385792D01*
X393825Y386000D01*
X393200Y386333D01*
Y384667D01*
G01X395325Y387583D02*
X395533Y387833D01*
X395658Y388125D01*
X395700Y388500D01*
X395617Y388875D01*
X395450Y389167D01*
X395158Y389375D01*
X394825Y389417D01*
X394492Y389333D01*
X394283Y389125D01*
X394117Y388833D01*
X394075Y388542D01*
X394117Y388250D01*
X394283Y387875D01*
X393200Y388000D01*
Y389125D01*
G01X389708Y383417D02*
X389583Y383167D01*
X389500Y382875D01*
Y382542D01*
X389625Y382167D01*
X389833Y381875D01*
X390083Y381667D01*
X390500Y381500D01*
X390875Y381458D01*
X391250Y381542D01*
X391500Y381667D01*
X391750Y381917D01*
X391917Y382208D01*
X392000Y382500D01*
Y382792D01*
X391917Y383083D01*
X391792Y383333D01*
X391625Y383542D01*
G01X392000Y385417D02*
X391458Y385500D01*
X391000Y385625D01*
X390583Y385792D01*
X390125Y386000D01*
X389500Y386333D01*
Y384667D01*
G01X392000Y389000D02*
X389500D01*
X391292Y387458D01*
Y389542D01*
G01X382008Y383517D02*
X381883Y383267D01*
X381800Y382975D01*
Y382642D01*
X381925Y382267D01*
X382133Y381975D01*
X382383Y381767D01*
X382800Y381600D01*
X383175Y381558D01*
X383550Y381642D01*
X383800Y381767D01*
X384050Y382017D01*
X384217Y382308D01*
X384300Y382600D01*
Y382892D01*
X384217Y383183D01*
X384092Y383433D01*
X383925Y383642D01*
G01X384300Y385600D02*
X384258Y385892D01*
X384133Y386225D01*
X383925Y386433D01*
X383633Y386517D01*
X383342Y386433D01*
X383092Y386183D01*
X382967Y385808D01*
Y385392D01*
X382883Y385142D01*
X382675Y384933D01*
X382383Y384850D01*
X382092Y384975D01*
X381883Y385267D01*
X381800Y385600D01*
X381883Y385933D01*
X382092Y386225D01*
X382383Y386350D01*
X382675Y386267D01*
X382883Y386058D01*
X382967Y385808D01*
Y385392D01*
X383092Y385017D01*
X383342Y384767D01*
X383633Y384683D01*
X383925Y384767D01*
X384133Y384975D01*
X384258Y385308D01*
X384300Y385600D01*
G01X383800Y387683D02*
X384092Y387933D01*
X384258Y388267D01*
X384300Y388642D01*
X384258Y388975D01*
X384050Y389308D01*
X383800Y389517D01*
X383550Y389558D01*
X383258Y389475D01*
X383050Y389183D01*
X382967Y388892D01*
Y388517D01*
G01Y388892D02*
X382842Y389142D01*
X382633Y389350D01*
X382383Y389433D01*
X382133Y389350D01*
X381925Y389142D01*
X381800Y388767D01*
X381842Y388392D01*
X382008Y388017D01*
G01X378308Y383417D02*
X378183Y383167D01*
X378100Y382875D01*
Y382542D01*
X378225Y382167D01*
X378433Y381875D01*
X378683Y381667D01*
X379100Y381500D01*
X379475Y381458D01*
X379850Y381542D01*
X380100Y381667D01*
X380350Y381917D01*
X380517Y382208D01*
X380600Y382500D01*
Y382792D01*
X380517Y383083D01*
X380392Y383333D01*
X380225Y383542D01*
G01X380600Y385417D02*
X380058Y385500D01*
X379600Y385625D01*
X379183Y385792D01*
X378725Y386000D01*
X378100Y386333D01*
Y384667D01*
G01X378517Y387708D02*
X378267Y387958D01*
X378142Y388250D01*
X378100Y388583D01*
X378183Y389000D01*
X378392Y389292D01*
X378642Y389375D01*
X378892Y389333D01*
X379100Y389167D01*
X379517Y388333D01*
X379808Y387958D01*
X380225Y387708D01*
X380600Y387625D01*
Y389375D01*
G01X397208Y383617D02*
X397083Y383367D01*
X397000Y383075D01*
Y382742D01*
X397125Y382367D01*
X397333Y382075D01*
X397583Y381867D01*
X398000Y381700D01*
X398375Y381658D01*
X398750Y381742D01*
X399000Y381867D01*
X399250Y382117D01*
X399417Y382408D01*
X399500Y382700D01*
Y382992D01*
X399417Y383283D01*
X399292Y383533D01*
X399125Y383742D01*
G01X399500Y385617D02*
X398958Y385700D01*
X398500Y385825D01*
X398083Y385992D01*
X397625Y386200D01*
X397000Y386533D01*
Y384867D01*
G01X398458Y387908D02*
X398167Y388200D01*
X398000Y388450D01*
X397917Y388783D01*
X398000Y389075D01*
X398167Y389283D01*
X398417Y389450D01*
X398708Y389492D01*
X398958Y389450D01*
X399208Y389283D01*
X399417Y389033D01*
X399500Y388742D01*
X399417Y388408D01*
X399167Y388117D01*
X398792Y387950D01*
X398375Y387908D01*
X397833Y387992D01*
X397542Y388117D01*
X397250Y388325D01*
X397042Y388617D01*
X397000Y388908D01*
X397083Y389200D01*
X397292Y389408D01*
G01X385908Y383517D02*
X385783Y383267D01*
X385700Y382975D01*
Y382642D01*
X385825Y382267D01*
X386033Y381975D01*
X386283Y381767D01*
X386700Y381600D01*
X387075Y381558D01*
X387450Y381642D01*
X387700Y381767D01*
X387950Y382017D01*
X388117Y382308D01*
X388200Y382600D01*
Y382892D01*
X388117Y383183D01*
X387992Y383433D01*
X387825Y383642D01*
G01X388200Y385517D02*
X387658Y385600D01*
X387200Y385725D01*
X386783Y385892D01*
X386325Y386100D01*
X385700Y386433D01*
Y384767D01*
G01X387700Y387683D02*
X387992Y387933D01*
X388158Y388267D01*
X388200Y388642D01*
X388158Y388975D01*
X387950Y389308D01*
X387700Y389517D01*
X387450Y389558D01*
X387158Y389475D01*
X386950Y389183D01*
X386867Y388892D01*
Y388517D01*
G01Y388892D02*
X386742Y389142D01*
X386533Y389350D01*
X386283Y389433D01*
X386033Y389350D01*
X385825Y389142D01*
X385700Y388767D01*
X385742Y388392D01*
X385908Y388017D01*
G01X374708Y383617D02*
X374583Y383367D01*
X374500Y383075D01*
Y382742D01*
X374625Y382367D01*
X374833Y382075D01*
X375083Y381867D01*
X375500Y381700D01*
X375875Y381658D01*
X376250Y381742D01*
X376500Y381867D01*
X376750Y382117D01*
X376917Y382408D01*
X377000Y382700D01*
Y382992D01*
X376917Y383283D01*
X376792Y383533D01*
X376625Y383742D01*
G01X377000Y385617D02*
X376458Y385700D01*
X376000Y385825D01*
X375583Y385992D01*
X375125Y386200D01*
X374500Y386533D01*
Y384867D01*
G01X377000Y388700D02*
X374500D01*
X375000Y388200D01*
G01X377000D02*
Y389200D01*
G01X370508Y383517D02*
X370383Y383267D01*
X370300Y382975D01*
Y382642D01*
X370425Y382267D01*
X370633Y381975D01*
X370883Y381767D01*
X371300Y381600D01*
X371675Y381558D01*
X372050Y381642D01*
X372300Y381767D01*
X372550Y382017D01*
X372717Y382308D01*
X372800Y382600D01*
Y382892D01*
X372717Y383183D01*
X372592Y383433D01*
X372425Y383642D01*
G01X372800Y385517D02*
X372258Y385600D01*
X371800Y385725D01*
X371383Y385892D01*
X370925Y386100D01*
X370300Y386433D01*
Y384767D01*
G01Y388600D02*
X370383Y388267D01*
X370592Y388017D01*
X370842Y387850D01*
X371175Y387725D01*
X371550Y387683D01*
X371925Y387725D01*
X372258Y387850D01*
X372508Y388017D01*
X372717Y388267D01*
X372800Y388600D01*
X372717Y388933D01*
X372508Y389183D01*
X372258Y389350D01*
X371925Y389475D01*
X371550Y389517D01*
X371175Y389475D01*
X370842Y389350D01*
X370592Y389183D01*
X370383Y388933D01*
X370300Y388600D01*
G01X365608Y383417D02*
X365483Y383167D01*
X365400Y382875D01*
Y382542D01*
X365525Y382167D01*
X365733Y381875D01*
X365983Y381667D01*
X366400Y381500D01*
X366775Y381458D01*
X367150Y381542D01*
X367400Y381667D01*
X367650Y381917D01*
X367817Y382208D01*
X367900Y382500D01*
Y382792D01*
X367817Y383083D01*
X367692Y383333D01*
X367525Y383542D01*
G01X366858Y384708D02*
X366567Y385000D01*
X366400Y385250D01*
X366317Y385583D01*
X366400Y385875D01*
X366567Y386083D01*
X366817Y386250D01*
X367108Y386292D01*
X367358Y386250D01*
X367608Y386083D01*
X367817Y385833D01*
X367900Y385542D01*
X367817Y385208D01*
X367567Y384917D01*
X367192Y384750D01*
X366775Y384708D01*
X366233Y384792D01*
X365942Y384917D01*
X365650Y385125D01*
X365442Y385417D01*
X365400Y385708D01*
X365483Y386000D01*
X365692Y386208D01*
G01X367608Y387792D02*
X367817Y388083D01*
X367900Y388417D01*
X367817Y388750D01*
X367567Y389042D01*
X367192Y389250D01*
X366817Y389333D01*
X366358D01*
X365983Y389250D01*
X365650Y389042D01*
X365483Y388792D01*
X365400Y388500D01*
X365483Y388167D01*
X365650Y387917D01*
X365900Y387750D01*
X366233Y387667D01*
X366525Y387750D01*
X366817Y387958D01*
X366983Y388208D01*
X367025Y388500D01*
X366942Y388833D01*
X366733Y389083D01*
X366358Y389333D01*
G01X360508Y383517D02*
X360383Y383267D01*
X360300Y382975D01*
Y382642D01*
X360425Y382267D01*
X360633Y381975D01*
X360883Y381767D01*
X361300Y381600D01*
X361675Y381558D01*
X362050Y381642D01*
X362300Y381767D01*
X362550Y382017D01*
X362717Y382308D01*
X362800Y382600D01*
Y382892D01*
X362717Y383183D01*
X362592Y383433D01*
X362425Y383642D01*
G01X361758Y384808D02*
X361467Y385100D01*
X361300Y385350D01*
X361217Y385683D01*
X361300Y385975D01*
X361467Y386183D01*
X361717Y386350D01*
X362008Y386392D01*
X362258Y386350D01*
X362508Y386183D01*
X362717Y385933D01*
X362800Y385642D01*
X362717Y385308D01*
X362467Y385017D01*
X362092Y384850D01*
X361675Y384808D01*
X361133Y384892D01*
X360842Y385017D01*
X360550Y385225D01*
X360342Y385517D01*
X360300Y385808D01*
X360383Y386100D01*
X360592Y386308D01*
G01X362800Y388600D02*
X362758Y388892D01*
X362633Y389225D01*
X362425Y389433D01*
X362133Y389517D01*
X361842Y389433D01*
X361592Y389183D01*
X361467Y388808D01*
Y388392D01*
X361383Y388142D01*
X361175Y387933D01*
X360883Y387850D01*
X360592Y387975D01*
X360383Y388267D01*
X360300Y388600D01*
X360383Y388933D01*
X360592Y389225D01*
X360883Y389350D01*
X361175Y389267D01*
X361383Y389058D01*
X361467Y388808D01*
Y388392D01*
X361592Y388017D01*
X361842Y387767D01*
X362133Y387683D01*
X362425Y387767D01*
X362633Y387975D01*
X362758Y388308D01*
X362800Y388600D01*
G01X391508Y463017D02*
X391383Y462767D01*
X391300Y462475D01*
Y462142D01*
X391425Y461767D01*
X391633Y461475D01*
X391883Y461267D01*
X392300Y461100D01*
X392675Y461058D01*
X393050Y461142D01*
X393300Y461267D01*
X393550Y461517D01*
X393717Y461808D01*
X393800Y462100D01*
Y462392D01*
X393717Y462683D01*
X393592Y462933D01*
X393425Y463142D01*
G01X393800Y465100D02*
X391300D01*
X391800Y464600D01*
G01X393800D02*
Y465600D01*
G01Y468600D02*
X391300D01*
X393092Y467058D01*
Y469142D01*
G01X393800Y471100D02*
X393758Y471392D01*
X393633Y471725D01*
X393425Y471933D01*
X393133Y472017D01*
X392842Y471933D01*
X392592Y471683D01*
X392467Y471308D01*
Y470892D01*
X392383Y470642D01*
X392175Y470433D01*
X391883Y470350D01*
X391592Y470475D01*
X391383Y470767D01*
X391300Y471100D01*
X391383Y471433D01*
X391592Y471725D01*
X391883Y471850D01*
X392175Y471767D01*
X392383Y471558D01*
X392467Y471308D01*
Y470892D01*
X392592Y470517D01*
X392842Y470267D01*
X393133Y470183D01*
X393425Y470267D01*
X393633Y470475D01*
X393758Y470808D01*
X393800Y471100D01*
G01X386138Y439149D02*
X386013Y438899D01*
X385930Y438607D01*
Y438274D01*
X386055Y437899D01*
X386263Y437607D01*
X386513Y437399D01*
X386930Y437232D01*
X387305Y437190D01*
X387680Y437274D01*
X387930Y437399D01*
X388180Y437649D01*
X388347Y437940D01*
X388430Y438232D01*
Y438524D01*
X388347Y438815D01*
X388222Y439065D01*
X388055Y439274D01*
G01X388430Y441149D02*
X387888Y441232D01*
X387430Y441357D01*
X387013Y441524D01*
X386555Y441732D01*
X385930Y442065D01*
Y440399D01*
G01X388430Y444232D02*
X388388Y444524D01*
X388263Y444857D01*
X388055Y445065D01*
X387763Y445149D01*
X387472Y445065D01*
X387222Y444815D01*
X387097Y444440D01*
Y444024D01*
X387013Y443774D01*
X386805Y443565D01*
X386513Y443482D01*
X386222Y443607D01*
X386013Y443899D01*
X385930Y444232D01*
X386013Y444565D01*
X386222Y444857D01*
X386513Y444982D01*
X386805Y444899D01*
X387013Y444690D01*
X387097Y444440D01*
Y444024D01*
X387222Y443649D01*
X387472Y443399D01*
X387763Y443315D01*
X388055Y443399D01*
X388263Y443607D01*
X388388Y443940D01*
X388430Y444232D01*
G01X382200Y439188D02*
X382075Y438938D01*
X381992Y438646D01*
Y438313D01*
X382117Y437938D01*
X382325Y437646D01*
X382575Y437438D01*
X382992Y437271D01*
X383367Y437229D01*
X383742Y437313D01*
X383992Y437438D01*
X384242Y437688D01*
X384409Y437979D01*
X384492Y438271D01*
Y438563D01*
X384409Y438854D01*
X384284Y439104D01*
X384117Y439313D01*
G01X384492Y441188D02*
X383950Y441271D01*
X383492Y441396D01*
X383075Y441563D01*
X382617Y441771D01*
X381992Y442104D01*
Y440438D01*
G01X384200Y443563D02*
X384409Y443854D01*
X384492Y444188D01*
X384409Y444521D01*
X384159Y444813D01*
X383784Y445021D01*
X383409Y445104D01*
X382950D01*
X382575Y445021D01*
X382242Y444813D01*
X382075Y444563D01*
X381992Y444271D01*
X382075Y443938D01*
X382242Y443688D01*
X382492Y443521D01*
X382825Y443438D01*
X383117Y443521D01*
X383409Y443729D01*
X383575Y443979D01*
X383617Y444271D01*
X383534Y444604D01*
X383325Y444854D01*
X382950Y445104D01*
G01X370008Y441117D02*
X369883Y440867D01*
X369800Y440575D01*
Y440242D01*
X369925Y439867D01*
X370133Y439575D01*
X370383Y439367D01*
X370800Y439200D01*
X371175Y439158D01*
X371550Y439242D01*
X371800Y439367D01*
X372050Y439617D01*
X372217Y439908D01*
X372300Y440200D01*
Y440492D01*
X372217Y440783D01*
X372092Y441033D01*
X371925Y441242D01*
G01X372300Y443200D02*
X372258Y443492D01*
X372133Y443825D01*
X371925Y444033D01*
X371633Y444117D01*
X371342Y444033D01*
X371092Y443783D01*
X370967Y443408D01*
Y442992D01*
X370883Y442742D01*
X370675Y442533D01*
X370383Y442450D01*
X370092Y442575D01*
X369883Y442867D01*
X369800Y443200D01*
X369883Y443533D01*
X370092Y443825D01*
X370383Y443950D01*
X370675Y443867D01*
X370883Y443658D01*
X370967Y443408D01*
Y442992D01*
X371092Y442617D01*
X371342Y442367D01*
X371633Y442283D01*
X371925Y442367D01*
X372133Y442575D01*
X372258Y442908D01*
X372300Y443200D01*
G01X369800Y446200D02*
X369883Y445867D01*
X370092Y445617D01*
X370342Y445450D01*
X370675Y445325D01*
X371050Y445283D01*
X371425Y445325D01*
X371758Y445450D01*
X372008Y445617D01*
X372217Y445867D01*
X372300Y446200D01*
X372217Y446533D01*
X372008Y446783D01*
X371758Y446950D01*
X371425Y447075D01*
X371050Y447117D01*
X370675Y447075D01*
X370342Y446950D01*
X370092Y446783D01*
X369883Y446533D01*
X369800Y446200D01*
G01X366289Y438954D02*
X366164Y438704D01*
X366081Y438412D01*
Y438079D01*
X366206Y437704D01*
X366414Y437412D01*
X366664Y437204D01*
X367081Y437037D01*
X367456Y436995D01*
X367831Y437079D01*
X368081Y437204D01*
X368331Y437454D01*
X368498Y437745D01*
X368581Y438037D01*
Y438329D01*
X368498Y438620D01*
X368373Y438870D01*
X368206Y439079D01*
G01X368581Y441037D02*
X368539Y441329D01*
X368414Y441662D01*
X368206Y441870D01*
X367914Y441954D01*
X367623Y441870D01*
X367373Y441620D01*
X367248Y441245D01*
Y440829D01*
X367164Y440579D01*
X366956Y440370D01*
X366664Y440287D01*
X366373Y440412D01*
X366164Y440704D01*
X366081Y441037D01*
X366164Y441370D01*
X366373Y441662D01*
X366664Y441787D01*
X366956Y441704D01*
X367164Y441495D01*
X367248Y441245D01*
Y440829D01*
X367373Y440454D01*
X367623Y440204D01*
X367914Y440120D01*
X368206Y440204D01*
X368414Y440412D01*
X368539Y440745D01*
X368581Y441037D01*
G01Y444037D02*
X366081D01*
X366581Y443537D01*
G01X368581D02*
Y444537D01*
G01X362908Y441117D02*
X362783Y440867D01*
X362700Y440575D01*
Y440242D01*
X362825Y439867D01*
X363033Y439575D01*
X363283Y439367D01*
X363700Y439200D01*
X364075Y439158D01*
X364450Y439242D01*
X364700Y439367D01*
X364950Y439617D01*
X365117Y439908D01*
X365200Y440200D01*
Y440492D01*
X365117Y440783D01*
X364992Y441033D01*
X364825Y441242D01*
G01X365200Y443200D02*
X365158Y443492D01*
X365033Y443825D01*
X364825Y444033D01*
X364533Y444117D01*
X364242Y444033D01*
X363992Y443783D01*
X363867Y443408D01*
Y442992D01*
X363783Y442742D01*
X363575Y442533D01*
X363283Y442450D01*
X362992Y442575D01*
X362783Y442867D01*
X362700Y443200D01*
X362783Y443533D01*
X362992Y443825D01*
X363283Y443950D01*
X363575Y443867D01*
X363783Y443658D01*
X363867Y443408D01*
Y442992D01*
X363992Y442617D01*
X364242Y442367D01*
X364533Y442283D01*
X364825Y442367D01*
X365033Y442575D01*
X365158Y442908D01*
X365200Y443200D01*
G01X363117Y445408D02*
X362867Y445658D01*
X362742Y445950D01*
X362700Y446283D01*
X362783Y446700D01*
X362992Y446992D01*
X363242Y447075D01*
X363492Y447033D01*
X363700Y446867D01*
X364117Y446033D01*
X364408Y445658D01*
X364825Y445408D01*
X365200Y445325D01*
Y447075D01*
G01X377808Y441017D02*
X377683Y440767D01*
X377600Y440475D01*
Y440142D01*
X377725Y439767D01*
X377933Y439475D01*
X378183Y439267D01*
X378600Y439100D01*
X378975Y439058D01*
X379350Y439142D01*
X379600Y439267D01*
X379850Y439517D01*
X380017Y439808D01*
X380100Y440100D01*
Y440392D01*
X380017Y440683D01*
X379892Y440933D01*
X379725Y441142D01*
G01X380100Y443100D02*
X380058Y443392D01*
X379933Y443725D01*
X379725Y443933D01*
X379433Y444017D01*
X379142Y443933D01*
X378892Y443683D01*
X378767Y443308D01*
Y442892D01*
X378683Y442642D01*
X378475Y442433D01*
X378183Y442350D01*
X377892Y442475D01*
X377683Y442767D01*
X377600Y443100D01*
X377683Y443433D01*
X377892Y443725D01*
X378183Y443850D01*
X378475Y443767D01*
X378683Y443558D01*
X378767Y443308D01*
Y442892D01*
X378892Y442517D01*
X379142Y442267D01*
X379433Y442183D01*
X379725Y442267D01*
X379933Y442475D01*
X380058Y442808D01*
X380100Y443100D01*
G01X379725Y445183D02*
X379933Y445433D01*
X380058Y445725D01*
X380100Y446100D01*
X380017Y446475D01*
X379850Y446767D01*
X379558Y446975D01*
X379225Y447017D01*
X378892Y446933D01*
X378683Y446725D01*
X378517Y446433D01*
X378475Y446142D01*
X378517Y445850D01*
X378683Y445475D01*
X377600Y445600D01*
Y446725D01*
G01X373967Y438956D02*
X373842Y438706D01*
X373759Y438414D01*
Y438081D01*
X373884Y437706D01*
X374092Y437414D01*
X374342Y437206D01*
X374759Y437039D01*
X375134Y436997D01*
X375509Y437081D01*
X375759Y437206D01*
X376009Y437456D01*
X376176Y437747D01*
X376259Y438039D01*
Y438331D01*
X376176Y438622D01*
X376051Y438872D01*
X375884Y439081D01*
G01X376259Y441039D02*
X376217Y441331D01*
X376092Y441664D01*
X375884Y441872D01*
X375592Y441956D01*
X375301Y441872D01*
X375051Y441622D01*
X374926Y441247D01*
Y440831D01*
X374842Y440581D01*
X374634Y440372D01*
X374342Y440289D01*
X374051Y440414D01*
X373842Y440706D01*
X373759Y441039D01*
X373842Y441372D01*
X374051Y441664D01*
X374342Y441789D01*
X374634Y441706D01*
X374842Y441497D01*
X374926Y441247D01*
Y440831D01*
X375051Y440456D01*
X375301Y440206D01*
X375592Y440122D01*
X375884Y440206D01*
X376092Y440414D01*
X376217Y440747D01*
X376259Y441039D01*
G01X375217Y443247D02*
X374926Y443539D01*
X374759Y443789D01*
X374676Y444122D01*
X374759Y444414D01*
X374926Y444622D01*
X375176Y444789D01*
X375467Y444831D01*
X375717Y444789D01*
X375967Y444622D01*
X376176Y444372D01*
X376259Y444081D01*
X376176Y443747D01*
X375926Y443456D01*
X375551Y443289D01*
X375134Y443247D01*
X374592Y443331D01*
X374301Y443456D01*
X374009Y443664D01*
X373801Y443956D01*
X373759Y444247D01*
X373842Y444539D01*
X374051Y444747D01*
G01X387808Y463117D02*
X387683Y462867D01*
X387600Y462575D01*
Y462242D01*
X387725Y461867D01*
X387933Y461575D01*
X388183Y461367D01*
X388600Y461200D01*
X388975Y461158D01*
X389350Y461242D01*
X389600Y461367D01*
X389850Y461617D01*
X390017Y461908D01*
X390100Y462200D01*
Y462492D01*
X390017Y462783D01*
X389892Y463033D01*
X389725Y463242D01*
G01X390100Y465200D02*
X387600D01*
X388100Y464700D01*
G01X390100D02*
Y465700D01*
G01Y468700D02*
X387600D01*
X389392Y467158D01*
Y469242D01*
G01X389058Y470408D02*
X388767Y470700D01*
X388600Y470950D01*
X388517Y471283D01*
X388600Y471575D01*
X388767Y471783D01*
X389017Y471950D01*
X389308Y471992D01*
X389558Y471950D01*
X389808Y471783D01*
X390017Y471533D01*
X390100Y471242D01*
X390017Y470908D01*
X389767Y470617D01*
X389392Y470450D01*
X388975Y470408D01*
X388433Y470492D01*
X388142Y470617D01*
X387850Y470825D01*
X387642Y471117D01*
X387600Y471408D01*
X387683Y471700D01*
X387892Y471908D01*
G01X379508Y463017D02*
X379383Y462767D01*
X379300Y462475D01*
Y462142D01*
X379425Y461767D01*
X379633Y461475D01*
X379883Y461267D01*
X380300Y461100D01*
X380675Y461058D01*
X381050Y461142D01*
X381300Y461267D01*
X381550Y461517D01*
X381717Y461808D01*
X381800Y462100D01*
Y462392D01*
X381717Y462683D01*
X381592Y462933D01*
X381425Y463142D01*
G01X381800Y465100D02*
X379300D01*
X379800Y464600D01*
G01X381800D02*
Y465600D01*
G01Y468600D02*
X379300D01*
X381092Y467058D01*
Y469142D01*
G01X381800Y471017D02*
X381258Y471100D01*
X380800Y471225D01*
X380383Y471392D01*
X379925Y471600D01*
X379300Y471933D01*
Y470267D01*
G01X375808Y462917D02*
X375683Y462667D01*
X375600Y462375D01*
Y462042D01*
X375725Y461667D01*
X375933Y461375D01*
X376183Y461167D01*
X376600Y461000D01*
X376975Y460958D01*
X377350Y461042D01*
X377600Y461167D01*
X377850Y461417D01*
X378017Y461708D01*
X378100Y462000D01*
Y462292D01*
X378017Y462583D01*
X377892Y462833D01*
X377725Y463042D01*
G01X378100Y465000D02*
X375600D01*
X376100Y464500D01*
G01X378100D02*
Y465500D01*
G01Y468500D02*
X375600D01*
X377392Y466958D01*
Y469042D01*
G01X377725Y470083D02*
X377933Y470333D01*
X378058Y470625D01*
X378100Y471000D01*
X378017Y471375D01*
X377850Y471667D01*
X377558Y471875D01*
X377225Y471917D01*
X376892Y471833D01*
X376683Y471625D01*
X376517Y471333D01*
X376475Y471042D01*
X376517Y470750D01*
X376683Y470375D01*
X375600Y470500D01*
Y471625D01*
G01X384008Y463117D02*
X383883Y462867D01*
X383800Y462575D01*
Y462242D01*
X383925Y461867D01*
X384133Y461575D01*
X384383Y461367D01*
X384800Y461200D01*
X385175Y461158D01*
X385550Y461242D01*
X385800Y461367D01*
X386050Y461617D01*
X386217Y461908D01*
X386300Y462200D01*
Y462492D01*
X386217Y462783D01*
X386092Y463033D01*
X385925Y463242D01*
G01X386300Y465200D02*
X383800D01*
X384300Y464700D01*
G01X386300D02*
Y465700D01*
G01Y468700D02*
X383800D01*
X385592Y467158D01*
Y469242D01*
G01X384217Y470408D02*
X383967Y470658D01*
X383842Y470950D01*
X383800Y471283D01*
X383883Y471700D01*
X384092Y471992D01*
X384342Y472075D01*
X384592Y472033D01*
X384800Y471867D01*
X385217Y471033D01*
X385508Y470658D01*
X385925Y470408D01*
X386300Y470325D01*
Y472075D01*
G01X372008Y462817D02*
X371883Y462567D01*
X371800Y462275D01*
Y461942D01*
X371925Y461567D01*
X372133Y461275D01*
X372383Y461067D01*
X372800Y460900D01*
X373175Y460858D01*
X373550Y460942D01*
X373800Y461067D01*
X374050Y461317D01*
X374217Y461608D01*
X374300Y461900D01*
Y462192D01*
X374217Y462483D01*
X374092Y462733D01*
X373925Y462942D01*
G01X374300Y464900D02*
X371800D01*
X372300Y464400D01*
G01X374300D02*
Y465400D01*
G01Y468400D02*
X371800D01*
X373592Y466858D01*
Y468942D01*
G01X373800Y469983D02*
X374092Y470233D01*
X374258Y470567D01*
X374300Y470942D01*
X374258Y471275D01*
X374050Y471608D01*
X373800Y471817D01*
X373550Y471858D01*
X373258Y471775D01*
X373050Y471483D01*
X372967Y471192D01*
Y470817D01*
G01Y471192D02*
X372842Y471442D01*
X372633Y471650D01*
X372383Y471733D01*
X372133Y471650D01*
X371925Y471442D01*
X371800Y471067D01*
X371842Y470692D01*
X372008Y470317D01*
G01X368208Y463117D02*
X368083Y462867D01*
X368000Y462575D01*
Y462242D01*
X368125Y461867D01*
X368333Y461575D01*
X368583Y461367D01*
X369000Y461200D01*
X369375Y461158D01*
X369750Y461242D01*
X370000Y461367D01*
X370250Y461617D01*
X370417Y461908D01*
X370500Y462200D01*
Y462492D01*
X370417Y462783D01*
X370292Y463033D01*
X370125Y463242D01*
G01X370500Y465200D02*
X368000D01*
X368500Y464700D01*
G01X370500D02*
Y465700D01*
G01Y468700D02*
X368000D01*
X369792Y467158D01*
Y469242D01*
G01X370500Y471700D02*
X368000D01*
X369792Y470158D01*
Y472242D01*
G01X362648Y532194D02*
X362398Y532319D01*
X362106Y532402D01*
X361773D01*
X361398Y532277D01*
X361106Y532069D01*
X360898Y531819D01*
X360731Y531402D01*
X360689Y531027D01*
X360773Y530652D01*
X360898Y530402D01*
X361148Y530152D01*
X361439Y529985D01*
X361731Y529902D01*
X362023D01*
X362314Y529985D01*
X362564Y530110D01*
X362773Y530277D01*
G01X364731Y529902D02*
Y532402D01*
X364231Y531902D01*
G01Y529902D02*
X365231D01*
G01X362472Y536241D02*
X362222Y536366D01*
X361930Y536449D01*
X361597D01*
X361222Y536324D01*
X360930Y536116D01*
X360722Y535866D01*
X360555Y535449D01*
X360513Y535074D01*
X360597Y534699D01*
X360722Y534449D01*
X360972Y534199D01*
X361263Y534032D01*
X361555Y533949D01*
X361847D01*
X362138Y534032D01*
X362388Y534157D01*
X362597Y534324D01*
G01X363763Y536032D02*
X364013Y536282D01*
X364305Y536407D01*
X364638Y536449D01*
X365055Y536366D01*
X365347Y536157D01*
X365430Y535907D01*
X365388Y535657D01*
X365222Y535449D01*
X364388Y535032D01*
X364013Y534741D01*
X363763Y534324D01*
X363680Y533949D01*
X365430D01*
G01X363056Y786605D02*
Y789105D01*
X364097D01*
X364431Y788980D01*
X364639Y788813D01*
X364722Y788480D01*
X364639Y788147D01*
X364389Y787938D01*
X364097Y787813D01*
X363056D01*
G01X364097D02*
X364722Y786605D01*
G01X366889D02*
Y789105D01*
X366389Y788605D01*
G01Y786605D02*
X367389D01*
G01X369181Y786897D02*
X369472Y786688D01*
X369806Y786605D01*
X370139Y786688D01*
X370431Y786938D01*
X370639Y787313D01*
X370722Y787688D01*
Y788147D01*
X370639Y788522D01*
X370431Y788855D01*
X370181Y789022D01*
X369889Y789105D01*
X369556Y789022D01*
X369306Y788855D01*
X369139Y788605D01*
X369056Y788272D01*
X369139Y787980D01*
X369347Y787688D01*
X369597Y787522D01*
X369889Y787480D01*
X370222Y787563D01*
X370472Y787772D01*
X370722Y788147D01*
G01X371972Y786980D02*
X372222Y786772D01*
X372514Y786647D01*
X372889Y786605D01*
X373264Y786688D01*
X373556Y786855D01*
X373764Y787147D01*
X373806Y787480D01*
X373722Y787813D01*
X373514Y788022D01*
X373222Y788188D01*
X372931Y788230D01*
X372639Y788188D01*
X372264Y788022D01*
X372389Y789105D01*
X373514D01*
G01X489417Y397792D02*
X489167Y397917D01*
X488875Y398000D01*
X488542D01*
X488167Y397875D01*
X487875Y397667D01*
X487667Y397417D01*
X487500Y397000D01*
X487458Y396625D01*
X487542Y396250D01*
X487667Y396000D01*
X487917Y395750D01*
X488208Y395583D01*
X488500Y395500D01*
X488792D01*
X489083Y395583D01*
X489333Y395708D01*
X489542Y395875D01*
G01X490708Y397583D02*
X490958Y397833D01*
X491250Y397958D01*
X491583Y398000D01*
X492000Y397917D01*
X492292Y397708D01*
X492375Y397458D01*
X492333Y397208D01*
X492167Y397000D01*
X491333Y396583D01*
X490958Y396292D01*
X490708Y395875D01*
X490625Y395500D01*
X492375D01*
G01X495000D02*
Y398000D01*
X493458Y396208D01*
X495542D01*
G01X496708Y396542D02*
X497000Y396833D01*
X497250Y397000D01*
X497583Y397083D01*
X497875Y397000D01*
X498083Y396833D01*
X498250Y396583D01*
X498292Y396292D01*
X498250Y396042D01*
X498083Y395792D01*
X497833Y395583D01*
X497542Y395500D01*
X497208Y395583D01*
X496917Y395833D01*
X496750Y396208D01*
X496708Y396625D01*
X496792Y397167D01*
X496917Y397458D01*
X497125Y397750D01*
X497417Y397958D01*
X497708Y398000D01*
X498000Y397917D01*
X498208Y397708D01*
G01X487467Y410100D02*
Y412600D01*
X488508D01*
X488842Y412475D01*
X489050Y412308D01*
X489133Y411975D01*
X489050Y411642D01*
X488800Y411433D01*
X488508Y411308D01*
X487467D01*
G01X488508D02*
X489133Y410100D01*
G01X490508Y412183D02*
X490758Y412433D01*
X491050Y412558D01*
X491383Y412600D01*
X491800Y412517D01*
X492092Y412308D01*
X492175Y412058D01*
X492133Y411808D01*
X491967Y411600D01*
X491133Y411183D01*
X490758Y410892D01*
X490508Y410475D01*
X490425Y410100D01*
X492175D01*
G01X494300D02*
Y412600D01*
X493800Y412100D01*
G01Y410100D02*
X494800D01*
G01X497800D02*
Y412600D01*
X496258Y410808D01*
X498342D01*
G01X487167Y415900D02*
Y418400D01*
X488208D01*
X488542Y418275D01*
X488750Y418108D01*
X488833Y417775D01*
X488750Y417442D01*
X488500Y417233D01*
X488208Y417108D01*
X487167D01*
G01X488208D02*
X488833Y415900D01*
G01X490208Y417983D02*
X490458Y418233D01*
X490750Y418358D01*
X491083Y418400D01*
X491500Y418317D01*
X491792Y418108D01*
X491875Y417858D01*
X491833Y417608D01*
X491667Y417400D01*
X490833Y416983D01*
X490458Y416692D01*
X490208Y416275D01*
X490125Y415900D01*
X491875D01*
G01X494000D02*
Y418400D01*
X493500Y417900D01*
G01Y415900D02*
X494500D01*
G01X496208Y416942D02*
X496500Y417233D01*
X496750Y417400D01*
X497083Y417483D01*
X497375Y417400D01*
X497583Y417233D01*
X497750Y416983D01*
X497792Y416692D01*
X497750Y416442D01*
X497583Y416192D01*
X497333Y415983D01*
X497042Y415900D01*
X496708Y415983D01*
X496417Y416233D01*
X496250Y416608D01*
X496208Y417025D01*
X496292Y417567D01*
X496417Y417858D01*
X496625Y418150D01*
X496917Y418358D01*
X497208Y418400D01*
X497500Y418317D01*
X497708Y418108D01*
G01X487667Y401100D02*
Y403600D01*
X488708D01*
X489042Y403475D01*
X489250Y403308D01*
X489333Y402975D01*
X489250Y402642D01*
X489000Y402433D01*
X488708Y402308D01*
X487667D01*
G01X488708D02*
X489333Y401100D01*
G01X490708Y403183D02*
X490958Y403433D01*
X491250Y403558D01*
X491583Y403600D01*
X492000Y403517D01*
X492292Y403308D01*
X492375Y403058D01*
X492333Y402808D01*
X492167Y402600D01*
X491333Y402183D01*
X490958Y401892D01*
X490708Y401475D01*
X490625Y401100D01*
X492375D01*
G01X494500D02*
Y403600D01*
X494000Y403100D01*
G01Y401100D02*
X495000D01*
G01X497500Y403600D02*
X497167Y403517D01*
X496917Y403308D01*
X496750Y403058D01*
X496625Y402725D01*
X496583Y402350D01*
X496625Y401975D01*
X496750Y401642D01*
X496917Y401392D01*
X497167Y401183D01*
X497500Y401100D01*
X497833Y401183D01*
X498083Y401392D01*
X498250Y401642D01*
X498375Y401975D01*
X498417Y402350D01*
X498375Y402725D01*
X498250Y403058D01*
X498083Y403308D01*
X497833Y403517D01*
X497500Y403600D01*
G01X487667Y388500D02*
Y391000D01*
X488708D01*
X489042Y390875D01*
X489250Y390708D01*
X489333Y390375D01*
X489250Y390042D01*
X489000Y389833D01*
X488708Y389708D01*
X487667D01*
G01X488708D02*
X489333Y388500D01*
G01X490708Y390583D02*
X490958Y390833D01*
X491250Y390958D01*
X491583Y391000D01*
X492000Y390917D01*
X492292Y390708D01*
X492375Y390458D01*
X492333Y390208D01*
X492167Y390000D01*
X491333Y389583D01*
X490958Y389292D01*
X490708Y388875D01*
X490625Y388500D01*
X492375D01*
G01X494500D02*
Y391000D01*
X494000Y390500D01*
G01Y388500D02*
X495000D01*
G01X496583Y389000D02*
X496833Y388708D01*
X497167Y388542D01*
X497542Y388500D01*
X497875Y388542D01*
X498208Y388750D01*
X498417Y389000D01*
X498458Y389250D01*
X498375Y389542D01*
X498083Y389750D01*
X497792Y389833D01*
X497417D01*
G01X497792D02*
X498042Y389958D01*
X498250Y390167D01*
X498333Y390417D01*
X498250Y390667D01*
X498042Y390875D01*
X497667Y391000D01*
X497292Y390958D01*
X496917Y390792D01*
G01X485667Y379000D02*
Y381500D01*
X486708D01*
X487042Y381375D01*
X487250Y381208D01*
X487333Y380875D01*
X487250Y380542D01*
X487000Y380333D01*
X486708Y380208D01*
X485667D01*
G01X486708D02*
X487333Y379000D01*
G01X488583Y379500D02*
X488833Y379208D01*
X489167Y379042D01*
X489542Y379000D01*
X489875Y379042D01*
X490208Y379250D01*
X490417Y379500D01*
X490458Y379750D01*
X490375Y380042D01*
X490083Y380250D01*
X489792Y380333D01*
X489417D01*
G01X489792D02*
X490042Y380458D01*
X490250Y380667D01*
X490333Y380917D01*
X490250Y381167D01*
X490042Y381375D01*
X489667Y381500D01*
X489292Y381458D01*
X488917Y381292D01*
G01X491708Y380042D02*
X492000Y380333D01*
X492250Y380500D01*
X492583Y380583D01*
X492875Y380500D01*
X493083Y380333D01*
X493250Y380083D01*
X493292Y379792D01*
X493250Y379542D01*
X493083Y379292D01*
X492833Y379083D01*
X492542Y379000D01*
X492208Y379083D01*
X491917Y379333D01*
X491750Y379708D01*
X491708Y380125D01*
X491792Y380667D01*
X491917Y380958D01*
X492125Y381250D01*
X492417Y381458D01*
X492708Y381500D01*
X493000Y381417D01*
X493208Y381208D01*
G01X495500Y379000D02*
Y381500D01*
X495000Y381000D01*
G01Y379000D02*
X496000D01*
G01X473638Y481879D02*
X473388Y482004D01*
X473096Y482087D01*
X472763D01*
X472388Y481962D01*
X472096Y481754D01*
X471888Y481504D01*
X471721Y481087D01*
X471679Y480712D01*
X471763Y480337D01*
X471888Y480087D01*
X472138Y479837D01*
X472429Y479670D01*
X472721Y479587D01*
X473013D01*
X473304Y479670D01*
X473554Y479795D01*
X473763Y479962D01*
G01X474929Y481670D02*
X475179Y481920D01*
X475471Y482045D01*
X475804Y482087D01*
X476221Y482004D01*
X476513Y481795D01*
X476596Y481545D01*
X476554Y481295D01*
X476388Y481087D01*
X475554Y480670D01*
X475179Y480379D01*
X474929Y479962D01*
X474846Y479587D01*
X476596D01*
G01X477929Y481670D02*
X478179Y481920D01*
X478471Y482045D01*
X478804Y482087D01*
X479221Y482004D01*
X479513Y481795D01*
X479596Y481545D01*
X479554Y481295D01*
X479388Y481087D01*
X478554Y480670D01*
X478179Y480379D01*
X477929Y479962D01*
X477846Y479587D01*
X479596D01*
G01X481721D02*
X482013Y479629D01*
X482346Y479754D01*
X482554Y479962D01*
X482638Y480254D01*
X482554Y480545D01*
X482304Y480795D01*
X481929Y480920D01*
X481513D01*
X481263Y481004D01*
X481054Y481212D01*
X480971Y481504D01*
X481096Y481795D01*
X481388Y482004D01*
X481721Y482087D01*
X482054Y482004D01*
X482346Y481795D01*
X482471Y481504D01*
X482388Y481212D01*
X482179Y481004D01*
X481929Y480920D01*
X481513D01*
X481138Y480795D01*
X480888Y480545D01*
X480804Y480254D01*
X480888Y479962D01*
X481096Y479754D01*
X481429Y479629D01*
X481721Y479587D01*
G01X456317Y481992D02*
X456067Y482117D01*
X455775Y482200D01*
X455442D01*
X455067Y482075D01*
X454775Y481867D01*
X454567Y481617D01*
X454400Y481200D01*
X454358Y480825D01*
X454442Y480450D01*
X454567Y480200D01*
X454817Y479950D01*
X455108Y479783D01*
X455400Y479700D01*
X455692D01*
X455983Y479783D01*
X456233Y479908D01*
X456442Y480075D01*
G01X457608Y481783D02*
X457858Y482033D01*
X458150Y482158D01*
X458483Y482200D01*
X458900Y482117D01*
X459192Y481908D01*
X459275Y481658D01*
X459233Y481408D01*
X459067Y481200D01*
X458233Y480783D01*
X457858Y480492D01*
X457608Y480075D01*
X457525Y479700D01*
X459275D01*
G01X460608Y481783D02*
X460858Y482033D01*
X461150Y482158D01*
X461483Y482200D01*
X461900Y482117D01*
X462192Y481908D01*
X462275Y481658D01*
X462233Y481408D01*
X462067Y481200D01*
X461233Y480783D01*
X460858Y480492D01*
X460608Y480075D01*
X460525Y479700D01*
X462275D01*
G01X464317D02*
X464400Y480242D01*
X464525Y480700D01*
X464692Y481117D01*
X464900Y481575D01*
X465233Y482200D01*
X463567D01*
G01X449008Y486917D02*
X448883Y486667D01*
X448800Y486375D01*
Y486042D01*
X448925Y485667D01*
X449133Y485375D01*
X449383Y485167D01*
X449800Y485000D01*
X450175Y484958D01*
X450550Y485042D01*
X450800Y485167D01*
X451050Y485417D01*
X451217Y485708D01*
X451300Y486000D01*
Y486292D01*
X451217Y486583D01*
X451092Y486833D01*
X450925Y487042D01*
G01X449217Y488208D02*
X448967Y488458D01*
X448842Y488750D01*
X448800Y489083D01*
X448883Y489500D01*
X449092Y489792D01*
X449342Y489875D01*
X449592Y489833D01*
X449800Y489667D01*
X450217Y488833D01*
X450508Y488458D01*
X450925Y488208D01*
X451300Y488125D01*
Y489875D01*
G01X449217Y491208D02*
X448967Y491458D01*
X448842Y491750D01*
X448800Y492083D01*
X448883Y492500D01*
X449092Y492792D01*
X449342Y492875D01*
X449592Y492833D01*
X449800Y492667D01*
X450217Y491833D01*
X450508Y491458D01*
X450925Y491208D01*
X451300Y491125D01*
Y492875D01*
G01X450258Y494208D02*
X449967Y494500D01*
X449800Y494750D01*
X449717Y495083D01*
X449800Y495375D01*
X449967Y495583D01*
X450217Y495750D01*
X450508Y495792D01*
X450758Y495750D01*
X451008Y495583D01*
X451217Y495333D01*
X451300Y495042D01*
X451217Y494708D01*
X450967Y494417D01*
X450592Y494250D01*
X450175Y494208D01*
X449633Y494292D01*
X449342Y494417D01*
X449050Y494625D01*
X448842Y494917D01*
X448800Y495208D01*
X448883Y495500D01*
X449092Y495708D01*
G01X492067Y423300D02*
Y425800D01*
X493108D01*
X493442Y425675D01*
X493650Y425508D01*
X493733Y425175D01*
X493650Y424842D01*
X493400Y424633D01*
X493108Y424508D01*
X492067D01*
G01X493108D02*
X493733Y423300D01*
G01X495108Y425383D02*
X495358Y425633D01*
X495650Y425758D01*
X495983Y425800D01*
X496400Y425717D01*
X496692Y425508D01*
X496775Y425258D01*
X496733Y425008D01*
X496567Y424800D01*
X495733Y424383D01*
X495358Y424092D01*
X495108Y423675D01*
X495025Y423300D01*
X496775D01*
G01X498900D02*
Y425800D01*
X498400Y425300D01*
G01Y423300D02*
X499400D01*
G01X501108Y425383D02*
X501358Y425633D01*
X501650Y425758D01*
X501983Y425800D01*
X502400Y425717D01*
X502692Y425508D01*
X502775Y425258D01*
X502733Y425008D01*
X502567Y424800D01*
X501733Y424383D01*
X501358Y424092D01*
X501108Y423675D01*
X501025Y423300D01*
X502775D01*
G01X490867Y484400D02*
Y486900D01*
X491908D01*
X492242Y486775D01*
X492450Y486608D01*
X492533Y486275D01*
X492450Y485942D01*
X492200Y485733D01*
X491908Y485608D01*
X490867D01*
G01X491908D02*
X492533Y484400D01*
G01X493908Y486483D02*
X494158Y486733D01*
X494450Y486858D01*
X494783Y486900D01*
X495200Y486817D01*
X495492Y486608D01*
X495575Y486358D01*
X495533Y486108D01*
X495367Y485900D01*
X494533Y485483D01*
X494158Y485192D01*
X493908Y484775D01*
X493825Y484400D01*
X495575D01*
G01X498200D02*
Y486900D01*
X496658Y485108D01*
X498742D01*
G01X500700Y484400D02*
Y486900D01*
X500200Y486400D01*
G01Y484400D02*
X501200D01*
G01X471969Y475528D02*
Y478028D01*
X473010D01*
X473344Y477903D01*
X473552Y477736D01*
X473635Y477403D01*
X473552Y477070D01*
X473302Y476861D01*
X473010Y476736D01*
X471969D01*
G01X473010D02*
X473635Y475528D01*
G01X475010Y477611D02*
X475260Y477861D01*
X475552Y477986D01*
X475885Y478028D01*
X476302Y477945D01*
X476594Y477736D01*
X476677Y477486D01*
X476635Y477236D01*
X476469Y477028D01*
X475635Y476611D01*
X475260Y476320D01*
X475010Y475903D01*
X474927Y475528D01*
X476677D01*
G01X479302D02*
Y478028D01*
X477760Y476236D01*
X479844D01*
G01X481802Y478028D02*
X481469Y477945D01*
X481219Y477736D01*
X481052Y477486D01*
X480927Y477153D01*
X480885Y476778D01*
X480927Y476403D01*
X481052Y476070D01*
X481219Y475820D01*
X481469Y475611D01*
X481802Y475528D01*
X482135Y475611D01*
X482385Y475820D01*
X482552Y476070D01*
X482677Y476403D01*
X482719Y476778D01*
X482677Y477153D01*
X482552Y477486D01*
X482385Y477736D01*
X482135Y477945D01*
X481802Y478028D01*
G01X454467Y475900D02*
Y478400D01*
X455508D01*
X455842Y478275D01*
X456050Y478108D01*
X456133Y477775D01*
X456050Y477442D01*
X455800Y477233D01*
X455508Y477108D01*
X454467D01*
G01X455508D02*
X456133Y475900D01*
G01X457508Y477983D02*
X457758Y478233D01*
X458050Y478358D01*
X458383Y478400D01*
X458800Y478317D01*
X459092Y478108D01*
X459175Y477858D01*
X459133Y477608D01*
X458967Y477400D01*
X458133Y476983D01*
X457758Y476692D01*
X457508Y476275D01*
X457425Y475900D01*
X459175D01*
G01X460383Y476400D02*
X460633Y476108D01*
X460967Y475942D01*
X461342Y475900D01*
X461675Y475942D01*
X462008Y476150D01*
X462217Y476400D01*
X462258Y476650D01*
X462175Y476942D01*
X461883Y477150D01*
X461592Y477233D01*
X461217D01*
G01X461592D02*
X461842Y477358D01*
X462050Y477567D01*
X462133Y477817D01*
X462050Y478067D01*
X461842Y478275D01*
X461467Y478400D01*
X461092Y478358D01*
X460717Y478192D01*
G01X463592Y476192D02*
X463883Y475983D01*
X464217Y475900D01*
X464550Y475983D01*
X464842Y476233D01*
X465050Y476608D01*
X465133Y476983D01*
Y477442D01*
X465050Y477817D01*
X464842Y478150D01*
X464592Y478317D01*
X464300Y478400D01*
X463967Y478317D01*
X463717Y478150D01*
X463550Y477900D01*
X463467Y477567D01*
X463550Y477275D01*
X463758Y476983D01*
X464008Y476817D01*
X464300Y476775D01*
X464633Y476858D01*
X464883Y477067D01*
X465133Y477442D01*
G01X447317Y485035D02*
X444817D01*
Y486076D01*
X444942Y486410D01*
X445109Y486618D01*
X445442Y486701D01*
X445775Y486618D01*
X445984Y486368D01*
X446109Y486076D01*
Y485035D01*
G01Y486076D02*
X447317Y486701D01*
G01X445234Y488076D02*
X444984Y488326D01*
X444859Y488618D01*
X444817Y488951D01*
X444900Y489368D01*
X445109Y489660D01*
X445359Y489743D01*
X445609Y489701D01*
X445817Y489535D01*
X446234Y488701D01*
X446525Y488326D01*
X446942Y488076D01*
X447317Y487993D01*
Y489743D01*
G01Y491868D02*
X444817D01*
X445317Y491368D01*
G01X447317D02*
Y492368D01*
G01X446942Y493951D02*
X447150Y494201D01*
X447275Y494493D01*
X447317Y494868D01*
X447234Y495243D01*
X447067Y495535D01*
X446775Y495743D01*
X446442Y495785D01*
X446109Y495701D01*
X445900Y495493D01*
X445734Y495201D01*
X445692Y494910D01*
X445734Y494618D01*
X445900Y494243D01*
X444817Y494368D01*
Y495493D01*
G01X474583Y516167D02*
Y514375D01*
X474750Y514000D01*
X475083Y513750D01*
X475500Y513667D01*
X475917Y513750D01*
X476250Y514000D01*
X476417Y514375D01*
Y516167D01*
G01X478417Y513667D02*
X478500Y514209D01*
X478625Y514667D01*
X478792Y515084D01*
X479000Y515542D01*
X479333Y516167D01*
X477667D01*
G01X499717Y502692D02*
X499467Y502817D01*
X499175Y502900D01*
X498842D01*
X498467Y502775D01*
X498175Y502567D01*
X497967Y502317D01*
X497800Y501900D01*
X497758Y501525D01*
X497842Y501150D01*
X497967Y500900D01*
X498217Y500650D01*
X498508Y500483D01*
X498800Y500400D01*
X499092D01*
X499383Y500483D01*
X499633Y500608D01*
X499842Y500775D01*
G01X501008Y502483D02*
X501258Y502733D01*
X501550Y502858D01*
X501883Y502900D01*
X502300Y502817D01*
X502592Y502608D01*
X502675Y502358D01*
X502633Y502108D01*
X502467Y501900D01*
X501633Y501483D01*
X501258Y501192D01*
X501008Y500775D01*
X500925Y500400D01*
X502675D01*
G01X504008Y502483D02*
X504258Y502733D01*
X504550Y502858D01*
X504883Y502900D01*
X505300Y502817D01*
X505592Y502608D01*
X505675Y502358D01*
X505633Y502108D01*
X505467Y501900D01*
X504633Y501483D01*
X504258Y501192D01*
X504008Y500775D01*
X503925Y500400D01*
X505675D01*
G01X508300D02*
Y502900D01*
X506758Y501108D01*
X508842D01*
G01X497888Y495287D02*
X497638Y495412D01*
X497346Y495495D01*
X497013D01*
X496638Y495370D01*
X496346Y495162D01*
X496138Y494912D01*
X495971Y494495D01*
X495929Y494120D01*
X496013Y493745D01*
X496138Y493495D01*
X496388Y493245D01*
X496679Y493078D01*
X496971Y492995D01*
X497263D01*
X497554Y493078D01*
X497804Y493203D01*
X498013Y493370D01*
G01X499179Y495078D02*
X499429Y495328D01*
X499721Y495453D01*
X500054Y495495D01*
X500471Y495412D01*
X500763Y495203D01*
X500846Y494953D01*
X500804Y494703D01*
X500638Y494495D01*
X499804Y494078D01*
X499429Y493787D01*
X499179Y493370D01*
X499096Y492995D01*
X500846D01*
G01X502179Y495078D02*
X502429Y495328D01*
X502721Y495453D01*
X503054Y495495D01*
X503471Y495412D01*
X503763Y495203D01*
X503846Y494953D01*
X503804Y494703D01*
X503638Y494495D01*
X502804Y494078D01*
X502429Y493787D01*
X502179Y493370D01*
X502096Y492995D01*
X503846D01*
G01X505263Y493287D02*
X505554Y493078D01*
X505888Y492995D01*
X506221Y493078D01*
X506513Y493328D01*
X506721Y493703D01*
X506804Y494078D01*
Y494537D01*
X506721Y494912D01*
X506513Y495245D01*
X506263Y495412D01*
X505971Y495495D01*
X505638Y495412D01*
X505388Y495245D01*
X505221Y494995D01*
X505138Y494662D01*
X505221Y494370D01*
X505429Y494078D01*
X505679Y493912D01*
X505971Y493870D01*
X506304Y493953D01*
X506554Y494162D01*
X506804Y494537D01*
G01X497826Y499040D02*
X497576Y499165D01*
X497284Y499248D01*
X496951D01*
X496576Y499123D01*
X496284Y498915D01*
X496076Y498665D01*
X495909Y498248D01*
X495867Y497873D01*
X495951Y497498D01*
X496076Y497248D01*
X496326Y496998D01*
X496617Y496831D01*
X496909Y496748D01*
X497201D01*
X497492Y496831D01*
X497742Y496956D01*
X497951Y497123D01*
G01X499117Y498831D02*
X499367Y499081D01*
X499659Y499206D01*
X499992Y499248D01*
X500409Y499165D01*
X500701Y498956D01*
X500784Y498706D01*
X500742Y498456D01*
X500576Y498248D01*
X499742Y497831D01*
X499367Y497540D01*
X499117Y497123D01*
X499034Y496748D01*
X500784D01*
G01X502117Y498831D02*
X502367Y499081D01*
X502659Y499206D01*
X502992Y499248D01*
X503409Y499165D01*
X503701Y498956D01*
X503784Y498706D01*
X503742Y498456D01*
X503576Y498248D01*
X502742Y497831D01*
X502367Y497540D01*
X502117Y497123D01*
X502034Y496748D01*
X503784D01*
G01X504992Y497123D02*
X505242Y496915D01*
X505534Y496790D01*
X505909Y496748D01*
X506284Y496831D01*
X506576Y496998D01*
X506784Y497290D01*
X506826Y497623D01*
X506742Y497956D01*
X506534Y498165D01*
X506242Y498331D01*
X505951Y498373D01*
X505659Y498331D01*
X505284Y498165D01*
X505409Y499248D01*
X506534D01*
G01X450967Y519700D02*
Y522200D01*
X452008D01*
X452342Y522075D01*
X452550Y521908D01*
X452633Y521575D01*
X452550Y521242D01*
X452300Y521033D01*
X452008Y520908D01*
X450967D01*
G01X452008D02*
X452633Y519700D01*
G01X454800D02*
Y522200D01*
X454300Y521700D01*
G01Y519700D02*
X455300D01*
G01X456883Y520075D02*
X457133Y519867D01*
X457425Y519742D01*
X457800Y519700D01*
X458175Y519783D01*
X458467Y519950D01*
X458675Y520242D01*
X458717Y520575D01*
X458633Y520908D01*
X458425Y521117D01*
X458133Y521283D01*
X457842Y521325D01*
X457550Y521283D01*
X457175Y521117D01*
X457300Y522200D01*
X458425D01*
G01X459883Y520075D02*
X460133Y519867D01*
X460425Y519742D01*
X460800Y519700D01*
X461175Y519783D01*
X461467Y519950D01*
X461675Y520242D01*
X461717Y520575D01*
X461633Y520908D01*
X461425Y521117D01*
X461133Y521283D01*
X460842Y521325D01*
X460550Y521283D01*
X460175Y521117D01*
X460300Y522200D01*
X461425D01*
G01X467967Y519800D02*
Y522300D01*
X469008D01*
X469342Y522175D01*
X469550Y522008D01*
X469633Y521675D01*
X469550Y521342D01*
X469300Y521133D01*
X469008Y521008D01*
X467967D01*
G01X469008D02*
X469633Y519800D01*
G01X471800D02*
Y522300D01*
X471300Y521800D01*
G01Y519800D02*
X472300D01*
G01X473883Y520175D02*
X474133Y519967D01*
X474425Y519842D01*
X474800Y519800D01*
X475175Y519883D01*
X475467Y520050D01*
X475675Y520342D01*
X475717Y520675D01*
X475633Y521008D01*
X475425Y521217D01*
X475133Y521383D01*
X474842Y521425D01*
X474550Y521383D01*
X474175Y521217D01*
X474300Y522300D01*
X475425D01*
G01X478300Y519800D02*
Y522300D01*
X476758Y520508D01*
X478842D01*
G01X494367Y527500D02*
Y530000D01*
X495408D01*
X495742Y529875D01*
X495950Y529708D01*
X496033Y529375D01*
X495950Y529042D01*
X495700Y528833D01*
X495408Y528708D01*
X494367D01*
G01X495408D02*
X496033Y527500D01*
G01X498200D02*
Y530000D01*
X497700Y529500D01*
G01Y527500D02*
X498700D01*
G01X500408Y529583D02*
X500658Y529833D01*
X500950Y529958D01*
X501283Y530000D01*
X501700Y529917D01*
X501992Y529708D01*
X502075Y529458D01*
X502033Y529208D01*
X501867Y529000D01*
X501033Y528583D01*
X500658Y528292D01*
X500408Y527875D01*
X500325Y527500D01*
X502075D01*
G01X504700D02*
Y530000D01*
X503158Y528208D01*
X505242D01*
G01X470933Y536681D02*
Y539181D01*
X471974D01*
X472308Y539056D01*
X472516Y538889D01*
X472599Y538556D01*
X472516Y538223D01*
X472266Y538014D01*
X471974Y537889D01*
X470933D01*
G01X471974D02*
X472599Y536681D01*
G01X474766D02*
Y539181D01*
X474266Y538681D01*
G01Y536681D02*
X475266D01*
G01X476974Y538764D02*
X477224Y539014D01*
X477516Y539139D01*
X477849Y539181D01*
X478266Y539098D01*
X478558Y538889D01*
X478641Y538639D01*
X478599Y538389D01*
X478433Y538181D01*
X477599Y537764D01*
X477224Y537473D01*
X476974Y537056D01*
X476891Y536681D01*
X478641D01*
G01X479849Y537181D02*
X480099Y536889D01*
X480433Y536723D01*
X480808Y536681D01*
X481141Y536723D01*
X481474Y536931D01*
X481683Y537181D01*
X481724Y537431D01*
X481641Y537723D01*
X481349Y537931D01*
X481058Y538014D01*
X480683D01*
G01X481058D02*
X481308Y538139D01*
X481516Y538348D01*
X481599Y538598D01*
X481516Y538848D01*
X481308Y539056D01*
X480933Y539181D01*
X480558Y539139D01*
X480183Y538973D01*
G01X472167Y545400D02*
Y547900D01*
X473208D01*
X473542Y547775D01*
X473750Y547608D01*
X473833Y547275D01*
X473750Y546942D01*
X473500Y546733D01*
X473208Y546608D01*
X472167D01*
G01X473208D02*
X473833Y545400D01*
G01X476000D02*
Y547900D01*
X475500Y547400D01*
G01Y545400D02*
X476500D01*
G01X478208Y547483D02*
X478458Y547733D01*
X478750Y547858D01*
X479083Y547900D01*
X479500Y547817D01*
X479792Y547608D01*
X479875Y547358D01*
X479833Y547108D01*
X479667Y546900D01*
X478833Y546483D01*
X478458Y546192D01*
X478208Y545775D01*
X478125Y545400D01*
X479875D01*
G01X481208Y547483D02*
X481458Y547733D01*
X481750Y547858D01*
X482083Y547900D01*
X482500Y547817D01*
X482792Y547608D01*
X482875Y547358D01*
X482833Y547108D01*
X482667Y546900D01*
X481833Y546483D01*
X481458Y546192D01*
X481208Y545775D01*
X481125Y545400D01*
X482875D01*
G01X471381Y531029D02*
Y533529D01*
X472422D01*
X472756Y533404D01*
X472964Y533237D01*
X473047Y532904D01*
X472964Y532571D01*
X472714Y532362D01*
X472422Y532237D01*
X471381D01*
G01X472422D02*
X473047Y531029D01*
G01X475214D02*
Y533529D01*
X474714Y533029D01*
G01Y531029D02*
X475714D01*
G01X478214D02*
Y533529D01*
X477714Y533029D01*
G01Y531029D02*
X478714D01*
G01X481131D02*
X481214Y531571D01*
X481339Y532029D01*
X481506Y532446D01*
X481714Y532904D01*
X482047Y533529D01*
X480381D01*
G01X471014Y540415D02*
Y542915D01*
X472055D01*
X472389Y542790D01*
X472597Y542623D01*
X472680Y542290D01*
X472597Y541957D01*
X472347Y541748D01*
X472055Y541623D01*
X471014D01*
G01X472055D02*
X472680Y540415D01*
G01X474847D02*
Y542915D01*
X474347Y542415D01*
G01Y540415D02*
X475347D01*
G01X477847D02*
Y542915D01*
X477347Y542415D01*
G01Y540415D02*
X478347D01*
G01X480055Y541457D02*
X480347Y541748D01*
X480597Y541915D01*
X480930Y541998D01*
X481222Y541915D01*
X481430Y541748D01*
X481597Y541498D01*
X481639Y541207D01*
X481597Y540957D01*
X481430Y540707D01*
X481180Y540498D01*
X480889Y540415D01*
X480555Y540498D01*
X480264Y540748D01*
X480097Y541123D01*
X480055Y541540D01*
X480139Y542082D01*
X480264Y542373D01*
X480472Y542665D01*
X480764Y542873D01*
X481055Y542915D01*
X481347Y542832D01*
X481555Y542623D01*
G01X472112Y548970D02*
Y551470D01*
X473153D01*
X473487Y551345D01*
X473695Y551178D01*
X473778Y550845D01*
X473695Y550512D01*
X473445Y550303D01*
X473153Y550178D01*
X472112D01*
G01X473153D02*
X473778Y548970D01*
G01X475945D02*
Y551470D01*
X475445Y550970D01*
G01Y548970D02*
X476445D01*
G01X478945D02*
Y551470D01*
X478445Y550970D01*
G01Y548970D02*
X479445D01*
G01X481028Y549345D02*
X481278Y549137D01*
X481570Y549012D01*
X481945Y548970D01*
X482320Y549053D01*
X482612Y549220D01*
X482820Y549512D01*
X482862Y549845D01*
X482778Y550178D01*
X482570Y550387D01*
X482278Y550553D01*
X481987Y550595D01*
X481695Y550553D01*
X481320Y550387D01*
X481445Y551470D01*
X482570D01*
G01X495166Y507217D02*
Y509717D01*
X496207D01*
X496541Y509592D01*
X496749Y509425D01*
X496832Y509092D01*
X496749Y508759D01*
X496499Y508550D01*
X496207Y508425D01*
X495166D01*
G01X496207D02*
X496832Y507217D01*
G01X498999D02*
Y509717D01*
X498499Y509217D01*
G01Y507217D02*
X499499D01*
G01X501082Y507592D02*
X501332Y507384D01*
X501624Y507259D01*
X501999Y507217D01*
X502374Y507300D01*
X502666Y507467D01*
X502874Y507759D01*
X502916Y508092D01*
X502832Y508425D01*
X502624Y508634D01*
X502332Y508800D01*
X502041Y508842D01*
X501749Y508800D01*
X501374Y508634D01*
X501499Y509717D01*
X502624D01*
G01X504082Y507717D02*
X504332Y507425D01*
X504666Y507259D01*
X505041Y507217D01*
X505374Y507259D01*
X505707Y507467D01*
X505916Y507717D01*
X505957Y507967D01*
X505874Y508259D01*
X505582Y508467D01*
X505291Y508550D01*
X504916D01*
G01X505291D02*
X505541Y508675D01*
X505749Y508884D01*
X505832Y509134D01*
X505749Y509384D01*
X505541Y509592D01*
X505166Y509717D01*
X504791Y509675D01*
X504416Y509509D01*
G01X495084Y511576D02*
Y514076D01*
X496125D01*
X496459Y513951D01*
X496667Y513784D01*
X496750Y513451D01*
X496667Y513118D01*
X496417Y512909D01*
X496125Y512784D01*
X495084D01*
G01X496125D02*
X496750Y511576D01*
G01X498917D02*
Y514076D01*
X498417Y513576D01*
G01Y511576D02*
X499417D01*
G01X501000Y511951D02*
X501250Y511743D01*
X501542Y511618D01*
X501917Y511576D01*
X502292Y511659D01*
X502584Y511826D01*
X502792Y512118D01*
X502834Y512451D01*
X502750Y512784D01*
X502542Y512993D01*
X502250Y513159D01*
X501959Y513201D01*
X501667Y513159D01*
X501292Y512993D01*
X501417Y514076D01*
X502542D01*
G01X504125Y513659D02*
X504375Y513909D01*
X504667Y514034D01*
X505000Y514076D01*
X505417Y513993D01*
X505709Y513784D01*
X505792Y513534D01*
X505750Y513284D01*
X505584Y513076D01*
X504750Y512659D01*
X504375Y512368D01*
X504125Y511951D01*
X504042Y511576D01*
X505792D01*
G01X432414Y507486D02*
Y509986D01*
X433455D01*
X433789Y509861D01*
X433997Y509694D01*
X434080Y509361D01*
X433997Y509028D01*
X433747Y508819D01*
X433455Y508694D01*
X432414D01*
G01X433455D02*
X434080Y507486D01*
G01X436247D02*
Y509986D01*
X435747Y509486D01*
G01Y507486D02*
X436747D01*
G01X439247D02*
X439539Y507528D01*
X439872Y507653D01*
X440080Y507861D01*
X440164Y508153D01*
X440080Y508444D01*
X439830Y508694D01*
X439455Y508819D01*
X439039D01*
X438789Y508903D01*
X438580Y509111D01*
X438497Y509403D01*
X438622Y509694D01*
X438914Y509903D01*
X439247Y509986D01*
X439580Y509903D01*
X439872Y509694D01*
X439997Y509403D01*
X439914Y509111D01*
X439705Y508903D01*
X439455Y508819D01*
X439039D01*
X438664Y508694D01*
X438414Y508444D01*
X438330Y508153D01*
X438414Y507861D01*
X438622Y507653D01*
X438955Y507528D01*
X439247Y507486D01*
G01X441330Y507861D02*
X441580Y507653D01*
X441872Y507528D01*
X442247Y507486D01*
X442622Y507569D01*
X442914Y507736D01*
X443122Y508028D01*
X443164Y508361D01*
X443080Y508694D01*
X442872Y508903D01*
X442580Y509069D01*
X442289Y509111D01*
X441997Y509069D01*
X441622Y508903D01*
X441747Y509986D01*
X442872D01*
G01X434900Y516400D02*
Y513900D01*
G01X433942Y516400D02*
X435858D01*
G01X437067Y513900D02*
Y516400D01*
X438067D01*
X438400Y516275D01*
X438650Y515983D01*
X438733Y515650D01*
X438650Y515317D01*
X438442Y515067D01*
X438067Y514942D01*
X437067D01*
G01X440900Y513900D02*
Y516400D01*
X440400Y515900D01*
G01Y513900D02*
X441400D01*
G01X442983Y514275D02*
X443233Y514067D01*
X443525Y513942D01*
X443900Y513900D01*
X444275Y513983D01*
X444567Y514150D01*
X444775Y514442D01*
X444817Y514775D01*
X444733Y515108D01*
X444525Y515317D01*
X444233Y515483D01*
X443942Y515525D01*
X443650Y515483D01*
X443275Y515317D01*
X443400Y516400D01*
X444525D01*
G01X446900D02*
X446567Y516317D01*
X446317Y516108D01*
X446150Y515858D01*
X446025Y515525D01*
X445983Y515150D01*
X446025Y514775D01*
X446150Y514442D01*
X446317Y514192D01*
X446567Y513983D01*
X446900Y513900D01*
X447233Y513983D01*
X447483Y514192D01*
X447650Y514442D01*
X447775Y514775D01*
X447817Y515150D01*
X447775Y515525D01*
X447650Y515858D01*
X447483Y516108D01*
X447233Y516317D01*
X446900Y516400D01*
G01X543667Y394500D02*
Y397000D01*
X544708D01*
X545042Y396875D01*
X545250Y396708D01*
X545333Y396375D01*
X545250Y396042D01*
X545000Y395833D01*
X544708Y395708D01*
X543667D01*
G01X544708D02*
X545333Y394500D01*
G01X546708Y396583D02*
X546958Y396833D01*
X547250Y396958D01*
X547583Y397000D01*
X548000Y396917D01*
X548292Y396708D01*
X548375Y396458D01*
X548333Y396208D01*
X548167Y396000D01*
X547333Y395583D01*
X546958Y395292D01*
X546708Y394875D01*
X546625Y394500D01*
X548375D01*
G01X550500D02*
Y397000D01*
X550000Y396500D01*
G01Y394500D02*
X551000D01*
G01X553500D02*
Y397000D01*
X553000Y396500D01*
G01Y394500D02*
X554000D01*
G01X543667Y390500D02*
Y393000D01*
X544708D01*
X545042Y392875D01*
X545250Y392708D01*
X545333Y392375D01*
X545250Y392042D01*
X545000Y391833D01*
X544708Y391708D01*
X543667D01*
G01X544708D02*
X545333Y390500D01*
G01X546708Y392583D02*
X546958Y392833D01*
X547250Y392958D01*
X547583Y393000D01*
X548000Y392917D01*
X548292Y392708D01*
X548375Y392458D01*
X548333Y392208D01*
X548167Y392000D01*
X547333Y391583D01*
X546958Y391292D01*
X546708Y390875D01*
X546625Y390500D01*
X548375D01*
G01X549583Y391000D02*
X549833Y390708D01*
X550167Y390542D01*
X550542Y390500D01*
X550875Y390542D01*
X551208Y390750D01*
X551417Y391000D01*
X551458Y391250D01*
X551375Y391542D01*
X551083Y391750D01*
X550792Y391833D01*
X550417D01*
G01X550792D02*
X551042Y391958D01*
X551250Y392167D01*
X551333Y392417D01*
X551250Y392667D01*
X551042Y392875D01*
X550667Y393000D01*
X550292Y392958D01*
X549917Y392792D01*
G01X553417Y390500D02*
X553500Y391042D01*
X553625Y391500D01*
X553792Y391917D01*
X554000Y392375D01*
X554333Y393000D01*
X552667D01*
G01X558500Y389167D02*
X556000D01*
Y390208D01*
X556125Y390542D01*
X556292Y390750D01*
X556625Y390833D01*
X556958Y390750D01*
X557167Y390500D01*
X557292Y390208D01*
Y389167D01*
G01Y390208D02*
X558500Y390833D01*
G01X556417Y392208D02*
X556167Y392458D01*
X556042Y392750D01*
X556000Y393083D01*
X556083Y393500D01*
X556292Y393792D01*
X556542Y393875D01*
X556792Y393833D01*
X557000Y393667D01*
X557417Y392833D01*
X557708Y392458D01*
X558125Y392208D01*
X558500Y392125D01*
Y393875D01*
G01Y396000D02*
X556000D01*
X556500Y395500D01*
G01X558500D02*
Y396500D01*
G01Y398917D02*
X557958Y399000D01*
X557500Y399125D01*
X557083Y399292D01*
X556625Y399500D01*
X556000Y399833D01*
Y398167D01*
G01X542000Y391000D02*
X541958Y390667D01*
X541792Y390375D01*
X541542Y390125D01*
X541250Y389958D01*
X540917Y389875D01*
X540583D01*
X540250Y389958D01*
X539958Y390125D01*
X539708Y390375D01*
X539542Y390667D01*
X539500Y391000D01*
X539542Y391333D01*
X539708Y391625D01*
X539958Y391875D01*
X540250Y392042D01*
X540583Y392125D01*
X540917D01*
X541250Y392042D01*
X541542Y391875D01*
X541792Y391625D01*
X541958Y391333D01*
X542000Y391000D01*
G01X541333Y391333D02*
X542000Y391833D01*
G01Y394000D02*
X539500D01*
X540000Y393500D01*
G01X542000D02*
Y394500D01*
G01X539500Y397000D02*
X539583Y396667D01*
X539792Y396417D01*
X540042Y396250D01*
X540375Y396125D01*
X540750Y396083D01*
X541125Y396125D01*
X541458Y396250D01*
X541708Y396417D01*
X541917Y396667D01*
X542000Y397000D01*
X541917Y397333D01*
X541708Y397583D01*
X541458Y397750D01*
X541125Y397875D01*
X540750Y397917D01*
X540375Y397875D01*
X540042Y397750D01*
X539792Y397583D01*
X539583Y397333D01*
X539500Y397000D01*
G01X528961Y426386D02*
Y424594D01*
X529128Y424219D01*
X529461Y423969D01*
X529878Y423886D01*
X530295Y423969D01*
X530628Y424219D01*
X530795Y424594D01*
Y426386D01*
G01X532878Y423886D02*
Y426386D01*
X532378Y425886D01*
G01Y423886D02*
X533378D01*
G01X534961Y424261D02*
X535211Y424053D01*
X535503Y423928D01*
X535878Y423886D01*
X536253Y423969D01*
X536545Y424136D01*
X536753Y424428D01*
X536795Y424761D01*
X536711Y425094D01*
X536503Y425303D01*
X536211Y425469D01*
X535920Y425511D01*
X535628Y425469D01*
X535253Y425303D01*
X535378Y426386D01*
X536503D01*
G01X517017Y428592D02*
X516767Y428717D01*
X516475Y428800D01*
X516142D01*
X515767Y428675D01*
X515475Y428467D01*
X515267Y428217D01*
X515100Y427800D01*
X515058Y427425D01*
X515142Y427050D01*
X515267Y426800D01*
X515517Y426550D01*
X515808Y426383D01*
X516100Y426300D01*
X516392D01*
X516683Y426383D01*
X516933Y426508D01*
X517142Y426675D01*
G01X518183Y426800D02*
X518433Y426508D01*
X518767Y426342D01*
X519142Y426300D01*
X519475Y426342D01*
X519808Y426550D01*
X520017Y426800D01*
X520058Y427050D01*
X519975Y427342D01*
X519683Y427550D01*
X519392Y427633D01*
X519017D01*
G01X519392D02*
X519642Y427758D01*
X519850Y427967D01*
X519933Y428217D01*
X519850Y428467D01*
X519642Y428675D01*
X519267Y428800D01*
X518892Y428758D01*
X518517Y428592D01*
G01X522100Y428800D02*
X521767Y428717D01*
X521517Y428508D01*
X521350Y428258D01*
X521225Y427925D01*
X521183Y427550D01*
X521225Y427175D01*
X521350Y426842D01*
X521517Y426592D01*
X521767Y426383D01*
X522100Y426300D01*
X522433Y426383D01*
X522683Y426592D01*
X522850Y426842D01*
X522975Y427175D01*
X523017Y427550D01*
X522975Y427925D01*
X522850Y428258D01*
X522683Y428508D01*
X522433Y428717D01*
X522100Y428800D01*
G01X525600Y426300D02*
Y428800D01*
X524058Y427008D01*
X526142D01*
G01X506284Y551553D02*
Y549761D01*
X506451Y549386D01*
X506784Y549136D01*
X507201Y549053D01*
X507618Y549136D01*
X507951Y549386D01*
X508118Y549761D01*
Y551553D01*
G01X509284Y549428D02*
X509534Y549220D01*
X509826Y549095D01*
X510201Y549053D01*
X510576Y549136D01*
X510868Y549303D01*
X511076Y549595D01*
X511118Y549928D01*
X511034Y550261D01*
X510826Y550470D01*
X510534Y550636D01*
X510243Y550678D01*
X509951Y550636D01*
X509576Y550470D01*
X509701Y551553D01*
X510826D01*
G01X527605Y558813D02*
X527355Y558938D01*
X527063Y559021D01*
X526730D01*
X526355Y558896D01*
X526063Y558688D01*
X525855Y558438D01*
X525688Y558021D01*
X525646Y557646D01*
X525730Y557271D01*
X525855Y557021D01*
X526105Y556771D01*
X526396Y556604D01*
X526688Y556521D01*
X526980D01*
X527271Y556604D01*
X527521Y556729D01*
X527730Y556896D01*
G01X528896Y558604D02*
X529146Y558854D01*
X529438Y558979D01*
X529771Y559021D01*
X530188Y558938D01*
X530480Y558729D01*
X530563Y558479D01*
X530521Y558229D01*
X530355Y558021D01*
X529521Y557604D01*
X529146Y557313D01*
X528896Y556896D01*
X528813Y556521D01*
X530563D01*
G01X531896Y558604D02*
X532146Y558854D01*
X532438Y558979D01*
X532771Y559021D01*
X533188Y558938D01*
X533480Y558729D01*
X533563Y558479D01*
X533521Y558229D01*
X533355Y558021D01*
X532521Y557604D01*
X532146Y557313D01*
X531896Y556896D01*
X531813Y556521D01*
X533563D01*
G01X535688D02*
Y559021D01*
X535188Y558521D01*
G01Y556521D02*
X536188D01*
G01X527605Y554347D02*
X527355Y554472D01*
X527063Y554555D01*
X526730D01*
X526355Y554430D01*
X526063Y554222D01*
X525855Y553972D01*
X525688Y553555D01*
X525646Y553180D01*
X525730Y552805D01*
X525855Y552555D01*
X526105Y552305D01*
X526396Y552138D01*
X526688Y552055D01*
X526980D01*
X527271Y552138D01*
X527521Y552263D01*
X527730Y552430D01*
G01X528896Y554138D02*
X529146Y554388D01*
X529438Y554513D01*
X529771Y554555D01*
X530188Y554472D01*
X530480Y554263D01*
X530563Y554013D01*
X530521Y553763D01*
X530355Y553555D01*
X529521Y553138D01*
X529146Y552847D01*
X528896Y552430D01*
X528813Y552055D01*
X530563D01*
G01X531896Y554138D02*
X532146Y554388D01*
X532438Y554513D01*
X532771Y554555D01*
X533188Y554472D01*
X533480Y554263D01*
X533563Y554013D01*
X533521Y553763D01*
X533355Y553555D01*
X532521Y553138D01*
X532146Y552847D01*
X531896Y552430D01*
X531813Y552055D01*
X533563D01*
G01X535688Y554555D02*
X535355Y554472D01*
X535105Y554263D01*
X534938Y554013D01*
X534813Y553680D01*
X534771Y553305D01*
X534813Y552930D01*
X534938Y552597D01*
X535105Y552347D01*
X535355Y552138D01*
X535688Y552055D01*
X536021Y552138D01*
X536271Y552347D01*
X536438Y552597D01*
X536563Y552930D01*
X536605Y553305D01*
X536563Y553680D01*
X536438Y554013D01*
X536271Y554263D01*
X536021Y554472D01*
X535688Y554555D01*
G01X532675Y529811D02*
Y532311D01*
X533716D01*
X534050Y532186D01*
X534258Y532019D01*
X534341Y531686D01*
X534258Y531353D01*
X534008Y531144D01*
X533716Y531019D01*
X532675D01*
G01X533716D02*
X534341Y529811D01*
G01X536508D02*
Y532311D01*
X536008Y531811D01*
G01Y529811D02*
X537008D01*
G01X538716Y531894D02*
X538966Y532144D01*
X539258Y532269D01*
X539591Y532311D01*
X540008Y532228D01*
X540300Y532019D01*
X540383Y531769D01*
X540341Y531519D01*
X540175Y531311D01*
X539341Y530894D01*
X538966Y530603D01*
X538716Y530186D01*
X538633Y529811D01*
X540383D01*
G01X542508D02*
X542800Y529853D01*
X543133Y529978D01*
X543341Y530186D01*
X543425Y530478D01*
X543341Y530769D01*
X543091Y531019D01*
X542716Y531144D01*
X542300D01*
X542050Y531228D01*
X541841Y531436D01*
X541758Y531728D01*
X541883Y532019D01*
X542175Y532228D01*
X542508Y532311D01*
X542841Y532228D01*
X543133Y532019D01*
X543258Y531728D01*
X543175Y531436D01*
X542966Y531228D01*
X542716Y531144D01*
X542300D01*
X541925Y531019D01*
X541675Y530769D01*
X541591Y530478D01*
X541675Y530186D01*
X541883Y529978D01*
X542216Y529853D01*
X542508Y529811D01*
G01X532918Y524859D02*
Y527359D01*
X533959D01*
X534293Y527234D01*
X534501Y527067D01*
X534584Y526734D01*
X534501Y526401D01*
X534251Y526192D01*
X533959Y526067D01*
X532918D01*
G01X533959D02*
X534584Y524859D01*
G01X536751D02*
Y527359D01*
X536251Y526859D01*
G01Y524859D02*
X537251D01*
G01X538959Y526942D02*
X539209Y527192D01*
X539501Y527317D01*
X539834Y527359D01*
X540251Y527276D01*
X540543Y527067D01*
X540626Y526817D01*
X540584Y526567D01*
X540418Y526359D01*
X539584Y525942D01*
X539209Y525651D01*
X538959Y525234D01*
X538876Y524859D01*
X540626D01*
G01X541834Y525234D02*
X542084Y525026D01*
X542376Y524901D01*
X542751Y524859D01*
X543126Y524942D01*
X543418Y525109D01*
X543626Y525401D01*
X543668Y525734D01*
X543584Y526067D01*
X543376Y526276D01*
X543084Y526442D01*
X542793Y526484D01*
X542501Y526442D01*
X542126Y526276D01*
X542251Y527359D01*
X543376D01*
G01X534700Y538467D02*
X532200D01*
Y539508D01*
X532325Y539842D01*
X532492Y540050D01*
X532825Y540133D01*
X533158Y540050D01*
X533367Y539800D01*
X533492Y539508D01*
Y538467D01*
G01Y539508D02*
X534700Y540133D01*
G01Y542300D02*
X532200D01*
X532700Y541800D01*
G01X534700D02*
Y542800D01*
G01X532617Y544508D02*
X532367Y544758D01*
X532242Y545050D01*
X532200Y545383D01*
X532283Y545800D01*
X532492Y546092D01*
X532742Y546175D01*
X532992Y546133D01*
X533200Y545967D01*
X533617Y545133D01*
X533908Y544758D01*
X534325Y544508D01*
X534700Y544425D01*
Y546175D01*
G01Y548300D02*
X532200D01*
X532700Y547800D01*
G01X534700D02*
Y548800D01*
G01X632367Y517100D02*
Y519600D01*
X633367D01*
X633700Y519475D01*
X633950Y519183D01*
X634033Y518850D01*
X633950Y518517D01*
X633742Y518267D01*
X633367Y518142D01*
X632367D01*
G01X637117Y519392D02*
X636867Y519517D01*
X636575Y519600D01*
X636242D01*
X635867Y519475D01*
X635575Y519267D01*
X635367Y519017D01*
X635200Y518600D01*
X635158Y518225D01*
X635242Y517850D01*
X635367Y517600D01*
X635617Y517350D01*
X635908Y517183D01*
X636200Y517100D01*
X636492D01*
X636783Y517183D01*
X637033Y517308D01*
X637242Y517475D01*
G01X639700Y517100D02*
Y519600D01*
X638158Y517808D01*
X640242D01*
G01X632567Y513200D02*
Y515700D01*
X633567D01*
X633900Y515575D01*
X634150Y515283D01*
X634233Y514950D01*
X634150Y514617D01*
X633942Y514367D01*
X633567Y514242D01*
X632567D01*
G01X637317Y515492D02*
X637067Y515617D01*
X636775Y515700D01*
X636442D01*
X636067Y515575D01*
X635775Y515367D01*
X635567Y515117D01*
X635400Y514700D01*
X635358Y514325D01*
X635442Y513950D01*
X635567Y513700D01*
X635817Y513450D01*
X636108Y513283D01*
X636400Y513200D01*
X636692D01*
X636983Y513283D01*
X637233Y513408D01*
X637442Y513575D01*
G01X638483Y513700D02*
X638733Y513408D01*
X639067Y513242D01*
X639442Y513200D01*
X639775Y513242D01*
X640108Y513450D01*
X640317Y513700D01*
X640358Y513950D01*
X640275Y514242D01*
X639983Y514450D01*
X639692Y514533D01*
X639317D01*
G01X639692D02*
X639942Y514658D01*
X640150Y514867D01*
X640233Y515117D01*
X640150Y515367D01*
X639942Y515575D01*
X639567Y515700D01*
X639192Y515658D01*
X638817Y515492D01*
G01X617667Y528500D02*
Y531000D01*
X618667D01*
X619000Y530875D01*
X619250Y530583D01*
X619333Y530250D01*
X619250Y529917D01*
X619042Y529667D01*
X618667Y529542D01*
X617667D01*
G01X620667Y528500D02*
Y531000D01*
X621708D01*
X622042Y530875D01*
X622250Y530708D01*
X622333Y530375D01*
X622250Y530042D01*
X622000Y529833D01*
X621708Y529708D01*
X620667D01*
G01X621708D02*
X622333Y528500D01*
G01X623583Y528875D02*
X623833Y528667D01*
X624125Y528542D01*
X624500Y528500D01*
X624875Y528583D01*
X625167Y528750D01*
X625375Y529042D01*
X625417Y529375D01*
X625333Y529708D01*
X625125Y529917D01*
X624833Y530083D01*
X624542Y530125D01*
X624250Y530083D01*
X623875Y529917D01*
X624000Y531000D01*
X625125D01*
G01X627417Y528500D02*
X627500Y529042D01*
X627625Y529500D01*
X627792Y529917D01*
X628000Y530375D01*
X628333Y531000D01*
X626667D01*
G01X643167Y398100D02*
Y400600D01*
X644208D01*
X644542Y400475D01*
X644750Y400308D01*
X644833Y399975D01*
X644750Y399642D01*
X644500Y399433D01*
X644208Y399308D01*
X643167D01*
G01X644208D02*
X644833Y398100D01*
G01X647000D02*
Y400600D01*
X646500Y400100D01*
G01Y398100D02*
X647500D01*
G01X650000Y400600D02*
X649667Y400517D01*
X649417Y400308D01*
X649250Y400058D01*
X649125Y399725D01*
X649083Y399350D01*
X649125Y398975D01*
X649250Y398642D01*
X649417Y398392D01*
X649667Y398183D01*
X650000Y398100D01*
X650333Y398183D01*
X650583Y398392D01*
X650750Y398642D01*
X650875Y398975D01*
X650917Y399350D01*
X650875Y399725D01*
X650750Y400058D01*
X650583Y400308D01*
X650333Y400517D01*
X650000Y400600D01*
G01X653000Y398100D02*
X653292Y398142D01*
X653625Y398267D01*
X653833Y398475D01*
X653917Y398767D01*
X653833Y399058D01*
X653583Y399308D01*
X653208Y399433D01*
X652792D01*
X652542Y399517D01*
X652333Y399725D01*
X652250Y400017D01*
X652375Y400308D01*
X652667Y400517D01*
X653000Y400600D01*
X653333Y400517D01*
X653625Y400308D01*
X653750Y400017D01*
X653667Y399725D01*
X653458Y399517D01*
X653208Y399433D01*
X652792D01*
X652417Y399308D01*
X652167Y399058D01*
X652083Y398767D01*
X652167Y398475D01*
X652375Y398267D01*
X652708Y398142D01*
X653000Y398100D01*
G01X677749Y460968D02*
Y463468D01*
X678790D01*
X679124Y463343D01*
X679332Y463176D01*
X679415Y462843D01*
X679332Y462510D01*
X679082Y462301D01*
X678790Y462176D01*
X677749D01*
G01X678790D02*
X679415Y460968D01*
G01X680790Y463051D02*
X681040Y463301D01*
X681332Y463426D01*
X681665Y463468D01*
X682082Y463385D01*
X682374Y463176D01*
X682457Y462926D01*
X682415Y462676D01*
X682249Y462468D01*
X681415Y462051D01*
X681040Y461760D01*
X680790Y461343D01*
X680707Y460968D01*
X682457D01*
G01X683874Y461260D02*
X684165Y461051D01*
X684499Y460968D01*
X684832Y461051D01*
X685124Y461301D01*
X685332Y461676D01*
X685415Y462051D01*
Y462510D01*
X685332Y462885D01*
X685124Y463218D01*
X684874Y463385D01*
X684582Y463468D01*
X684249Y463385D01*
X683999Y463218D01*
X683832Y462968D01*
X683749Y462635D01*
X683832Y462343D01*
X684040Y462051D01*
X684290Y461885D01*
X684582Y461843D01*
X684915Y461926D01*
X685165Y462135D01*
X685415Y462510D01*
G01X688082Y460968D02*
Y463468D01*
X686540Y461676D01*
X688624D01*
G01X703400Y444867D02*
X700900D01*
Y445908D01*
X701025Y446242D01*
X701192Y446450D01*
X701525Y446533D01*
X701858Y446450D01*
X702067Y446200D01*
X702192Y445908D01*
Y444867D01*
G01Y445908D02*
X703400Y446533D01*
G01X701317Y447908D02*
X701067Y448158D01*
X700942Y448450D01*
X700900Y448783D01*
X700983Y449200D01*
X701192Y449492D01*
X701442Y449575D01*
X701692Y449533D01*
X701900Y449367D01*
X702317Y448533D01*
X702608Y448158D01*
X703025Y447908D01*
X703400Y447825D01*
Y449575D01*
G01X703108Y450992D02*
X703317Y451283D01*
X703400Y451617D01*
X703317Y451950D01*
X703067Y452242D01*
X702692Y452450D01*
X702317Y452533D01*
X701858D01*
X701483Y452450D01*
X701150Y452242D01*
X700983Y451992D01*
X700900Y451700D01*
X700983Y451367D01*
X701150Y451117D01*
X701400Y450950D01*
X701733Y450867D01*
X702025Y450950D01*
X702317Y451158D01*
X702483Y451408D01*
X702525Y451700D01*
X702442Y452033D01*
X702233Y452283D01*
X701858Y452533D01*
G01X702900Y453783D02*
X703192Y454033D01*
X703358Y454367D01*
X703400Y454742D01*
X703358Y455075D01*
X703150Y455408D01*
X702900Y455617D01*
X702650Y455658D01*
X702358Y455575D01*
X702150Y455283D01*
X702067Y454992D01*
Y454617D01*
G01Y454992D02*
X701942Y455242D01*
X701733Y455450D01*
X701483Y455533D01*
X701233Y455450D01*
X701025Y455242D01*
X700900Y454867D01*
X700942Y454492D01*
X701108Y454117D01*
G01X666300Y447767D02*
X663800D01*
Y448808D01*
X663925Y449142D01*
X664092Y449350D01*
X664425Y449433D01*
X664758Y449350D01*
X664967Y449100D01*
X665092Y448808D01*
Y447767D01*
G01Y448808D02*
X666300Y449433D01*
G01X664217Y450808D02*
X663967Y451058D01*
X663842Y451350D01*
X663800Y451683D01*
X663883Y452100D01*
X664092Y452392D01*
X664342Y452475D01*
X664592Y452433D01*
X664800Y452267D01*
X665217Y451433D01*
X665508Y451058D01*
X665925Y450808D01*
X666300Y450725D01*
Y452475D01*
G01X666008Y453892D02*
X666217Y454183D01*
X666300Y454517D01*
X666217Y454850D01*
X665967Y455142D01*
X665592Y455350D01*
X665217Y455433D01*
X664758D01*
X664383Y455350D01*
X664050Y455142D01*
X663883Y454892D01*
X663800Y454600D01*
X663883Y454267D01*
X664050Y454017D01*
X664300Y453850D01*
X664633Y453767D01*
X664925Y453850D01*
X665217Y454058D01*
X665383Y454308D01*
X665425Y454600D01*
X665342Y454933D01*
X665133Y455183D01*
X664758Y455433D01*
G01X663800Y457600D02*
X663883Y457267D01*
X664092Y457017D01*
X664342Y456850D01*
X664675Y456725D01*
X665050Y456683D01*
X665425Y456725D01*
X665758Y456850D01*
X666008Y457017D01*
X666217Y457267D01*
X666300Y457600D01*
X666217Y457933D01*
X666008Y458183D01*
X665758Y458350D01*
X665425Y458475D01*
X665050Y458517D01*
X664675Y458475D01*
X664342Y458350D01*
X664092Y458183D01*
X663883Y457933D01*
X663800Y457600D01*
G01X657700Y455267D02*
X655200D01*
Y456308D01*
X655325Y456642D01*
X655492Y456850D01*
X655825Y456933D01*
X656158Y456850D01*
X656367Y456600D01*
X656492Y456308D01*
Y455267D01*
G01Y456308D02*
X657700Y456933D01*
G01X655617Y458308D02*
X655367Y458558D01*
X655242Y458850D01*
X655200Y459183D01*
X655283Y459600D01*
X655492Y459892D01*
X655742Y459975D01*
X655992Y459933D01*
X656200Y459767D01*
X656617Y458933D01*
X656908Y458558D01*
X657325Y458308D01*
X657700Y458225D01*
Y459975D01*
G01Y462100D02*
X657658Y462392D01*
X657533Y462725D01*
X657325Y462933D01*
X657033Y463017D01*
X656742Y462933D01*
X656492Y462683D01*
X656367Y462308D01*
Y461892D01*
X656283Y461642D01*
X656075Y461433D01*
X655783Y461350D01*
X655492Y461475D01*
X655283Y461767D01*
X655200Y462100D01*
X655283Y462433D01*
X655492Y462725D01*
X655783Y462850D01*
X656075Y462767D01*
X656283Y462558D01*
X656367Y462308D01*
Y461892D01*
X656492Y461517D01*
X656742Y461267D01*
X657033Y461183D01*
X657325Y461267D01*
X657533Y461475D01*
X657658Y461808D01*
X657700Y462100D01*
G01Y465600D02*
X655200D01*
X656992Y464058D01*
Y466142D01*
G01X662000Y451567D02*
X659500D01*
Y452608D01*
X659625Y452942D01*
X659792Y453150D01*
X660125Y453233D01*
X660458Y453150D01*
X660667Y452900D01*
X660792Y452608D01*
Y451567D01*
G01Y452608D02*
X662000Y453233D01*
G01X659917Y454608D02*
X659667Y454858D01*
X659542Y455150D01*
X659500Y455483D01*
X659583Y455900D01*
X659792Y456192D01*
X660042Y456275D01*
X660292Y456233D01*
X660500Y456067D01*
X660917Y455233D01*
X661208Y454858D01*
X661625Y454608D01*
X662000Y454525D01*
Y456275D01*
G01Y458400D02*
X661958Y458692D01*
X661833Y459025D01*
X661625Y459233D01*
X661333Y459317D01*
X661042Y459233D01*
X660792Y458983D01*
X660667Y458608D01*
Y458192D01*
X660583Y457942D01*
X660375Y457733D01*
X660083Y457650D01*
X659792Y457775D01*
X659583Y458067D01*
X659500Y458400D01*
X659583Y458733D01*
X659792Y459025D01*
X660083Y459150D01*
X660375Y459067D01*
X660583Y458858D01*
X660667Y458608D01*
Y458192D01*
X660792Y457817D01*
X661042Y457567D01*
X661333Y457483D01*
X661625Y457567D01*
X661833Y457775D01*
X661958Y458108D01*
X662000Y458400D01*
G01X661500Y460483D02*
X661792Y460733D01*
X661958Y461067D01*
X662000Y461442D01*
X661958Y461775D01*
X661750Y462108D01*
X661500Y462317D01*
X661250Y462358D01*
X660958Y462275D01*
X660750Y461983D01*
X660667Y461692D01*
Y461317D01*
G01Y461692D02*
X660542Y461942D01*
X660333Y462150D01*
X660083Y462233D01*
X659833Y462150D01*
X659625Y461942D01*
X659500Y461567D01*
X659542Y461192D01*
X659708Y460817D01*
G01X674700Y440067D02*
X672200D01*
Y441108D01*
X672325Y441442D01*
X672492Y441650D01*
X672825Y441733D01*
X673158Y441650D01*
X673367Y441400D01*
X673492Y441108D01*
Y440067D01*
G01Y441108D02*
X674700Y441733D01*
G01X672617Y443108D02*
X672367Y443358D01*
X672242Y443650D01*
X672200Y443983D01*
X672283Y444400D01*
X672492Y444692D01*
X672742Y444775D01*
X672992Y444733D01*
X673200Y444567D01*
X673617Y443733D01*
X673908Y443358D01*
X674325Y443108D01*
X674700Y443025D01*
Y444775D01*
G01Y446900D02*
X674658Y447192D01*
X674533Y447525D01*
X674325Y447733D01*
X674033Y447817D01*
X673742Y447733D01*
X673492Y447483D01*
X673367Y447108D01*
Y446692D01*
X673283Y446442D01*
X673075Y446233D01*
X672783Y446150D01*
X672492Y446275D01*
X672283Y446567D01*
X672200Y446900D01*
X672283Y447233D01*
X672492Y447525D01*
X672783Y447650D01*
X673075Y447567D01*
X673283Y447358D01*
X673367Y447108D01*
Y446692D01*
X673492Y446317D01*
X673742Y446067D01*
X674033Y445983D01*
X674325Y446067D01*
X674533Y446275D01*
X674658Y446608D01*
X674700Y446900D01*
G01X672617Y449108D02*
X672367Y449358D01*
X672242Y449650D01*
X672200Y449983D01*
X672283Y450400D01*
X672492Y450692D01*
X672742Y450775D01*
X672992Y450733D01*
X673200Y450567D01*
X673617Y449733D01*
X673908Y449358D01*
X674325Y449108D01*
X674700Y449025D01*
Y450775D01*
G01X679600Y435567D02*
X677100D01*
Y436608D01*
X677225Y436942D01*
X677392Y437150D01*
X677725Y437233D01*
X678058Y437150D01*
X678267Y436900D01*
X678392Y436608D01*
Y435567D01*
G01Y436608D02*
X679600Y437233D01*
G01X677517Y438608D02*
X677267Y438858D01*
X677142Y439150D01*
X677100Y439483D01*
X677183Y439900D01*
X677392Y440192D01*
X677642Y440275D01*
X677892Y440233D01*
X678100Y440067D01*
X678517Y439233D01*
X678808Y438858D01*
X679225Y438608D01*
X679600Y438525D01*
Y440275D01*
G01Y442400D02*
X679558Y442692D01*
X679433Y443025D01*
X679225Y443233D01*
X678933Y443317D01*
X678642Y443233D01*
X678392Y442983D01*
X678267Y442608D01*
Y442192D01*
X678183Y441942D01*
X677975Y441733D01*
X677683Y441650D01*
X677392Y441775D01*
X677183Y442067D01*
X677100Y442400D01*
X677183Y442733D01*
X677392Y443025D01*
X677683Y443150D01*
X677975Y443067D01*
X678183Y442858D01*
X678267Y442608D01*
Y442192D01*
X678392Y441817D01*
X678642Y441567D01*
X678933Y441483D01*
X679225Y441567D01*
X679433Y441775D01*
X679558Y442108D01*
X679600Y442400D01*
G01Y445400D02*
X677100D01*
X677600Y444900D01*
G01X679600D02*
Y445900D01*
G01X662367Y477500D02*
Y480000D01*
X663408D01*
X663742Y479875D01*
X663950Y479708D01*
X664033Y479375D01*
X663950Y479042D01*
X663700Y478833D01*
X663408Y478708D01*
X662367D01*
G01X663408D02*
X664033Y477500D01*
G01X665283Y478000D02*
X665533Y477708D01*
X665867Y477542D01*
X666242Y477500D01*
X666575Y477542D01*
X666908Y477750D01*
X667117Y478000D01*
X667158Y478250D01*
X667075Y478542D01*
X666783Y478750D01*
X666492Y478833D01*
X666117D01*
G01X666492D02*
X666742Y478958D01*
X666950Y479167D01*
X667033Y479417D01*
X666950Y479667D01*
X666742Y479875D01*
X666367Y480000D01*
X665992Y479958D01*
X665617Y479792D01*
G01X669200Y477500D02*
Y480000D01*
X668700Y479500D01*
G01Y477500D02*
X669700D01*
G01X671492Y477792D02*
X671783Y477583D01*
X672117Y477500D01*
X672450Y477583D01*
X672742Y477833D01*
X672950Y478208D01*
X673033Y478583D01*
Y479042D01*
X672950Y479417D01*
X672742Y479750D01*
X672492Y479917D01*
X672200Y480000D01*
X671867Y479917D01*
X671617Y479750D01*
X671450Y479500D01*
X671367Y479167D01*
X671450Y478875D01*
X671658Y478583D01*
X671908Y478417D01*
X672200Y478375D01*
X672533Y478458D01*
X672783Y478667D01*
X673033Y479042D01*
G01X657453Y481670D02*
Y484170D01*
X658494D01*
X658828Y484045D01*
X659036Y483878D01*
X659119Y483545D01*
X659036Y483212D01*
X658786Y483003D01*
X658494Y482878D01*
X657453D01*
G01X658494D02*
X659119Y481670D01*
G01X660369Y482170D02*
X660619Y481878D01*
X660953Y481712D01*
X661328Y481670D01*
X661661Y481712D01*
X661994Y481920D01*
X662203Y482170D01*
X662244Y482420D01*
X662161Y482712D01*
X661869Y482920D01*
X661578Y483003D01*
X661203D01*
G01X661578D02*
X661828Y483128D01*
X662036Y483337D01*
X662119Y483587D01*
X662036Y483837D01*
X661828Y484045D01*
X661453Y484170D01*
X661078Y484128D01*
X660703Y483962D01*
G01X664286Y481670D02*
Y484170D01*
X663786Y483670D01*
G01Y481670D02*
X664786D01*
G01X667286D02*
X667578Y481712D01*
X667911Y481837D01*
X668119Y482045D01*
X668203Y482337D01*
X668119Y482628D01*
X667869Y482878D01*
X667494Y483003D01*
X667078D01*
X666828Y483087D01*
X666619Y483295D01*
X666536Y483587D01*
X666661Y483878D01*
X666953Y484087D01*
X667286Y484170D01*
X667619Y484087D01*
X667911Y483878D01*
X668036Y483587D01*
X667953Y483295D01*
X667744Y483087D01*
X667494Y483003D01*
X667078D01*
X666703Y482878D01*
X666453Y482628D01*
X666369Y482337D01*
X666453Y482045D01*
X666661Y481837D01*
X666994Y481712D01*
X667286Y481670D01*
G01X649000Y464667D02*
X646500D01*
Y465708D01*
X646625Y466042D01*
X646792Y466250D01*
X647125Y466333D01*
X647458Y466250D01*
X647667Y466000D01*
X647792Y465708D01*
Y464667D01*
G01Y465708D02*
X649000Y466333D01*
G01X648500Y467583D02*
X648792Y467833D01*
X648958Y468167D01*
X649000Y468542D01*
X648958Y468875D01*
X648750Y469208D01*
X648500Y469417D01*
X648250Y469458D01*
X647958Y469375D01*
X647750Y469083D01*
X647667Y468792D01*
Y468417D01*
G01Y468792D02*
X647542Y469042D01*
X647333Y469250D01*
X647083Y469333D01*
X646833Y469250D01*
X646625Y469042D01*
X646500Y468667D01*
X646542Y468292D01*
X646708Y467917D01*
G01X649000Y471500D02*
X646500D01*
X647000Y471000D01*
G01X649000D02*
Y472000D01*
G01X647958Y473708D02*
X647667Y474000D01*
X647500Y474250D01*
X647417Y474583D01*
X647500Y474875D01*
X647667Y475083D01*
X647917Y475250D01*
X648208Y475292D01*
X648458Y475250D01*
X648708Y475083D01*
X648917Y474833D01*
X649000Y474542D01*
X648917Y474208D01*
X648667Y473917D01*
X648292Y473750D01*
X647875Y473708D01*
X647333Y473792D01*
X647042Y473917D01*
X646750Y474125D01*
X646542Y474417D01*
X646500Y474708D01*
X646583Y475000D01*
X646792Y475208D01*
G01X670900Y442367D02*
X668400D01*
Y443408D01*
X668525Y443742D01*
X668692Y443950D01*
X669025Y444033D01*
X669358Y443950D01*
X669567Y443700D01*
X669692Y443408D01*
Y442367D01*
G01Y443408D02*
X670900Y444033D01*
G01X670400Y445283D02*
X670692Y445533D01*
X670858Y445867D01*
X670900Y446242D01*
X670858Y446575D01*
X670650Y446908D01*
X670400Y447117D01*
X670150Y447158D01*
X669858Y447075D01*
X669650Y446783D01*
X669567Y446492D01*
Y446117D01*
G01Y446492D02*
X669442Y446742D01*
X669233Y446950D01*
X668983Y447033D01*
X668733Y446950D01*
X668525Y446742D01*
X668400Y446367D01*
X668442Y445992D01*
X668608Y445617D01*
G01X670900Y449200D02*
X668400D01*
X668900Y448700D01*
G01X670900D02*
Y449700D01*
G01X670525Y451283D02*
X670733Y451533D01*
X670858Y451825D01*
X670900Y452200D01*
X670817Y452575D01*
X670650Y452867D01*
X670358Y453075D01*
X670025Y453117D01*
X669692Y453033D01*
X669483Y452825D01*
X669317Y452533D01*
X669275Y452242D01*
X669317Y451950D01*
X669483Y451575D01*
X668400Y451700D01*
Y452825D01*
G01X705167Y465167D02*
Y467667D01*
X706208D01*
X706542Y467542D01*
X706750Y467375D01*
X706833Y467042D01*
X706750Y466709D01*
X706500Y466500D01*
X706208Y466375D01*
X705167D01*
G01X706208D02*
X706833Y465167D01*
G01X708083Y465667D02*
X708333Y465375D01*
X708667Y465209D01*
X709042Y465167D01*
X709375Y465209D01*
X709708Y465417D01*
X709917Y465667D01*
X709958Y465917D01*
X709875Y466209D01*
X709583Y466417D01*
X709292Y466500D01*
X708917D01*
G01X709292D02*
X709542Y466625D01*
X709750Y466834D01*
X709833Y467084D01*
X709750Y467334D01*
X709542Y467542D01*
X709167Y467667D01*
X708792Y467625D01*
X708417Y467459D01*
G01X712000Y465167D02*
Y467667D01*
X711500Y467167D01*
G01Y465167D02*
X712500D01*
G01X715500D02*
Y467667D01*
X713958Y465875D01*
X716042D01*
G01X673852Y465352D02*
Y467852D01*
X674893D01*
X675227Y467727D01*
X675435Y467560D01*
X675518Y467227D01*
X675435Y466894D01*
X675185Y466685D01*
X674893Y466560D01*
X673852D01*
G01X674893D02*
X675518Y465352D01*
G01X676768Y465852D02*
X677018Y465560D01*
X677352Y465394D01*
X677727Y465352D01*
X678060Y465394D01*
X678393Y465602D01*
X678602Y465852D01*
X678643Y466102D01*
X678560Y466394D01*
X678268Y466602D01*
X677977Y466685D01*
X677602D01*
G01X677977D02*
X678227Y466810D01*
X678435Y467019D01*
X678518Y467269D01*
X678435Y467519D01*
X678227Y467727D01*
X677852Y467852D01*
X677477Y467810D01*
X677102Y467644D01*
G01X680685Y465352D02*
Y467852D01*
X680185Y467352D01*
G01Y465352D02*
X681185D01*
G01X682768Y465852D02*
X683018Y465560D01*
X683352Y465394D01*
X683727Y465352D01*
X684060Y465394D01*
X684393Y465602D01*
X684602Y465852D01*
X684643Y466102D01*
X684560Y466394D01*
X684268Y466602D01*
X683977Y466685D01*
X683602D01*
G01X683977D02*
X684227Y466810D01*
X684435Y467019D01*
X684518Y467269D01*
X684435Y467519D01*
X684227Y467727D01*
X683852Y467852D01*
X683477Y467810D01*
X683102Y467644D01*
G01X653500Y458267D02*
X651000D01*
Y459308D01*
X651125Y459642D01*
X651292Y459850D01*
X651625Y459933D01*
X651958Y459850D01*
X652167Y459600D01*
X652292Y459308D01*
Y458267D01*
G01Y459308D02*
X653500Y459933D01*
G01X653000Y461183D02*
X653292Y461433D01*
X653458Y461767D01*
X653500Y462142D01*
X653458Y462475D01*
X653250Y462808D01*
X653000Y463017D01*
X652750Y463058D01*
X652458Y462975D01*
X652250Y462683D01*
X652167Y462392D01*
Y462017D01*
G01Y462392D02*
X652042Y462642D01*
X651833Y462850D01*
X651583Y462933D01*
X651333Y462850D01*
X651125Y462642D01*
X651000Y462267D01*
X651042Y461892D01*
X651208Y461517D01*
G01X653500Y465100D02*
X651000D01*
X651500Y464600D01*
G01X653500D02*
Y465600D01*
G01X651417Y467308D02*
X651167Y467558D01*
X651042Y467850D01*
X651000Y468183D01*
X651083Y468600D01*
X651292Y468892D01*
X651542Y468975D01*
X651792Y468933D01*
X652000Y468767D01*
X652417Y467933D01*
X652708Y467558D01*
X653125Y467308D01*
X653500Y467225D01*
Y468975D01*
G01X701617Y461130D02*
Y463630D01*
X702658D01*
X702992Y463505D01*
X703200Y463338D01*
X703283Y463005D01*
X703200Y462672D01*
X702950Y462463D01*
X702658Y462338D01*
X701617D01*
G01X702658D02*
X703283Y461130D01*
G01X704533Y461630D02*
X704783Y461338D01*
X705117Y461172D01*
X705492Y461130D01*
X705825Y461172D01*
X706158Y461380D01*
X706367Y461630D01*
X706408Y461880D01*
X706325Y462172D01*
X706033Y462380D01*
X705742Y462463D01*
X705367D01*
G01X705742D02*
X705992Y462588D01*
X706200Y462797D01*
X706283Y463047D01*
X706200Y463297D01*
X705992Y463505D01*
X705617Y463630D01*
X705242Y463588D01*
X704867Y463422D01*
G01X708450Y461130D02*
Y463630D01*
X707950Y463130D01*
G01Y461130D02*
X708950D01*
G01X711450D02*
Y463630D01*
X710950Y463130D01*
G01Y461130D02*
X711950D01*
G01X665003Y473308D02*
Y475808D01*
X666044D01*
X666378Y475683D01*
X666586Y475516D01*
X666669Y475183D01*
X666586Y474850D01*
X666336Y474641D01*
X666044Y474516D01*
X665003D01*
G01X666044D02*
X666669Y473308D01*
G01X667919Y473808D02*
X668169Y473516D01*
X668503Y473350D01*
X668878Y473308D01*
X669211Y473350D01*
X669544Y473558D01*
X669753Y473808D01*
X669794Y474058D01*
X669711Y474350D01*
X669419Y474558D01*
X669128Y474641D01*
X668753D01*
G01X669128D02*
X669378Y474766D01*
X669586Y474975D01*
X669669Y475225D01*
X669586Y475475D01*
X669378Y475683D01*
X669003Y475808D01*
X668628Y475766D01*
X668253Y475600D01*
G01X671836Y473308D02*
Y475808D01*
X671336Y475308D01*
G01Y473308D02*
X672336D01*
G01X674836Y475808D02*
X674503Y475725D01*
X674253Y475516D01*
X674086Y475266D01*
X673961Y474933D01*
X673919Y474558D01*
X673961Y474183D01*
X674086Y473850D01*
X674253Y473600D01*
X674503Y473391D01*
X674836Y473308D01*
X675169Y473391D01*
X675419Y473600D01*
X675586Y473850D01*
X675711Y474183D01*
X675753Y474558D01*
X675711Y474933D01*
X675586Y475266D01*
X675419Y475516D01*
X675169Y475725D01*
X674836Y475808D01*
G01X709667Y469667D02*
Y472167D01*
X710708D01*
X711042Y472042D01*
X711250Y471875D01*
X711333Y471542D01*
X711250Y471209D01*
X711000Y471000D01*
X710708Y470875D01*
X709667D01*
G01X710708D02*
X711333Y469667D01*
G01X712583Y470167D02*
X712833Y469875D01*
X713167Y469709D01*
X713542Y469667D01*
X713875Y469709D01*
X714208Y469917D01*
X714417Y470167D01*
X714458Y470417D01*
X714375Y470709D01*
X714083Y470917D01*
X713792Y471000D01*
X713417D01*
G01X713792D02*
X714042Y471125D01*
X714250Y471334D01*
X714333Y471584D01*
X714250Y471834D01*
X714042Y472042D01*
X713667Y472167D01*
X713292Y472125D01*
X712917Y471959D01*
G01X716500Y472167D02*
X716167Y472084D01*
X715917Y471875D01*
X715750Y471625D01*
X715625Y471292D01*
X715583Y470917D01*
X715625Y470542D01*
X715750Y470209D01*
X715917Y469959D01*
X716167Y469750D01*
X716500Y469667D01*
X716833Y469750D01*
X717083Y469959D01*
X717250Y470209D01*
X717375Y470542D01*
X717417Y470917D01*
X717375Y471292D01*
X717250Y471625D01*
X717083Y471875D01*
X716833Y472084D01*
X716500Y472167D01*
G01X718708Y470709D02*
X719000Y471000D01*
X719250Y471167D01*
X719583Y471250D01*
X719875Y471167D01*
X720083Y471000D01*
X720250Y470750D01*
X720292Y470459D01*
X720250Y470209D01*
X720083Y469959D01*
X719833Y469750D01*
X719542Y469667D01*
X719208Y469750D01*
X718917Y470000D01*
X718750Y470375D01*
X718708Y470792D01*
X718792Y471334D01*
X718917Y471625D01*
X719125Y471917D01*
X719417Y472125D01*
X719708Y472167D01*
X720000Y472084D01*
X720208Y471875D01*
G01X697667Y457167D02*
Y459667D01*
X698708D01*
X699042Y459542D01*
X699250Y459375D01*
X699333Y459042D01*
X699250Y458709D01*
X699000Y458500D01*
X698708Y458375D01*
X697667D01*
G01X698708D02*
X699333Y457167D01*
G01X700583Y457667D02*
X700833Y457375D01*
X701167Y457209D01*
X701542Y457167D01*
X701875Y457209D01*
X702208Y457417D01*
X702417Y457667D01*
X702458Y457917D01*
X702375Y458209D01*
X702083Y458417D01*
X701792Y458500D01*
X701417D01*
G01X701792D02*
X702042Y458625D01*
X702250Y458834D01*
X702333Y459084D01*
X702250Y459334D01*
X702042Y459542D01*
X701667Y459667D01*
X701292Y459625D01*
X700917Y459459D01*
G01X704500Y459667D02*
X704167Y459584D01*
X703917Y459375D01*
X703750Y459125D01*
X703625Y458792D01*
X703583Y458417D01*
X703625Y458042D01*
X703750Y457709D01*
X703917Y457459D01*
X704167Y457250D01*
X704500Y457167D01*
X704833Y457250D01*
X705083Y457459D01*
X705250Y457709D01*
X705375Y458042D01*
X705417Y458417D01*
X705375Y458792D01*
X705250Y459125D01*
X705083Y459375D01*
X704833Y459584D01*
X704500Y459667D01*
G01X706583Y457542D02*
X706833Y457334D01*
X707125Y457209D01*
X707500Y457167D01*
X707875Y457250D01*
X708167Y457417D01*
X708375Y457709D01*
X708417Y458042D01*
X708333Y458375D01*
X708125Y458584D01*
X707833Y458750D01*
X707542Y458792D01*
X707250Y458750D01*
X706875Y458584D01*
X707000Y459667D01*
X708125D01*
G01X669143Y469574D02*
Y472074D01*
X670184D01*
X670518Y471949D01*
X670726Y471782D01*
X670809Y471449D01*
X670726Y471116D01*
X670476Y470907D01*
X670184Y470782D01*
X669143D01*
G01X670184D02*
X670809Y469574D01*
G01X672059Y470074D02*
X672309Y469782D01*
X672643Y469616D01*
X673018Y469574D01*
X673351Y469616D01*
X673684Y469824D01*
X673893Y470074D01*
X673934Y470324D01*
X673851Y470616D01*
X673559Y470824D01*
X673268Y470907D01*
X672893D01*
G01X673268D02*
X673518Y471032D01*
X673726Y471241D01*
X673809Y471491D01*
X673726Y471741D01*
X673518Y471949D01*
X673143Y472074D01*
X672768Y472032D01*
X672393Y471866D01*
G01X675976Y472074D02*
X675643Y471991D01*
X675393Y471782D01*
X675226Y471532D01*
X675101Y471199D01*
X675059Y470824D01*
X675101Y470449D01*
X675226Y470116D01*
X675393Y469866D01*
X675643Y469657D01*
X675976Y469574D01*
X676309Y469657D01*
X676559Y469866D01*
X676726Y470116D01*
X676851Y470449D01*
X676893Y470824D01*
X676851Y471199D01*
X676726Y471532D01*
X676559Y471782D01*
X676309Y471991D01*
X675976Y472074D01*
G01X679476Y469574D02*
Y472074D01*
X677934Y470282D01*
X680018D01*
G01X682167Y456667D02*
Y459167D01*
X683208D01*
X683542Y459042D01*
X683750Y458875D01*
X683833Y458542D01*
X683750Y458209D01*
X683500Y458000D01*
X683208Y457875D01*
X682167D01*
G01X683208D02*
X683833Y456667D01*
G01X685083Y457167D02*
X685333Y456875D01*
X685667Y456709D01*
X686042Y456667D01*
X686375Y456709D01*
X686708Y456917D01*
X686917Y457167D01*
X686958Y457417D01*
X686875Y457709D01*
X686583Y457917D01*
X686292Y458000D01*
X685917D01*
G01X686292D02*
X686542Y458125D01*
X686750Y458334D01*
X686833Y458584D01*
X686750Y458834D01*
X686542Y459042D01*
X686167Y459167D01*
X685792Y459125D01*
X685417Y458959D01*
G01X689000Y459167D02*
X688667Y459084D01*
X688417Y458875D01*
X688250Y458625D01*
X688125Y458292D01*
X688083Y457917D01*
X688125Y457542D01*
X688250Y457209D01*
X688417Y456959D01*
X688667Y456750D01*
X689000Y456667D01*
X689333Y456750D01*
X689583Y456959D01*
X689750Y457209D01*
X689875Y457542D01*
X689917Y457917D01*
X689875Y458292D01*
X689750Y458625D01*
X689583Y458875D01*
X689333Y459084D01*
X689000Y459167D01*
G01X691083Y457167D02*
X691333Y456875D01*
X691667Y456709D01*
X692042Y456667D01*
X692375Y456709D01*
X692708Y456917D01*
X692917Y457167D01*
X692958Y457417D01*
X692875Y457709D01*
X692583Y457917D01*
X692292Y458000D01*
X691917D01*
G01X692292D02*
X692542Y458125D01*
X692750Y458334D01*
X692833Y458584D01*
X692750Y458834D01*
X692542Y459042D01*
X692167Y459167D01*
X691792Y459125D01*
X691417Y458959D01*
G01X708800Y437367D02*
X706300D01*
Y438408D01*
X706425Y438742D01*
X706592Y438950D01*
X706925Y439033D01*
X707258Y438950D01*
X707467Y438700D01*
X707592Y438408D01*
Y437367D01*
G01Y438408D02*
X708800Y439033D01*
G01X708300Y440283D02*
X708592Y440533D01*
X708758Y440867D01*
X708800Y441242D01*
X708758Y441575D01*
X708550Y441908D01*
X708300Y442117D01*
X708050Y442158D01*
X707758Y442075D01*
X707550Y441783D01*
X707467Y441492D01*
Y441117D01*
G01Y441492D02*
X707342Y441742D01*
X707133Y441950D01*
X706883Y442033D01*
X706633Y441950D01*
X706425Y441742D01*
X706300Y441367D01*
X706342Y440992D01*
X706508Y440617D01*
G01X706300Y444200D02*
X706383Y443867D01*
X706592Y443617D01*
X706842Y443450D01*
X707175Y443325D01*
X707550Y443283D01*
X707925Y443325D01*
X708258Y443450D01*
X708508Y443617D01*
X708717Y443867D01*
X708800Y444200D01*
X708717Y444533D01*
X708508Y444783D01*
X708258Y444950D01*
X707925Y445075D01*
X707550Y445117D01*
X707175Y445075D01*
X706842Y444950D01*
X706592Y444783D01*
X706383Y444533D01*
X706300Y444200D01*
G01X706717Y446408D02*
X706467Y446658D01*
X706342Y446950D01*
X706300Y447283D01*
X706383Y447700D01*
X706592Y447992D01*
X706842Y448075D01*
X707092Y448033D01*
X707300Y447867D01*
X707717Y447033D01*
X708008Y446658D01*
X708425Y446408D01*
X708800Y446325D01*
Y448075D01*
G01X684567Y448100D02*
Y450600D01*
X685608D01*
X685942Y450475D01*
X686150Y450308D01*
X686233Y449975D01*
X686150Y449642D01*
X685900Y449433D01*
X685608Y449308D01*
X684567D01*
G01X685608D02*
X686233Y448100D01*
G01X687483Y448600D02*
X687733Y448308D01*
X688067Y448142D01*
X688442Y448100D01*
X688775Y448142D01*
X689108Y448350D01*
X689317Y448600D01*
X689358Y448850D01*
X689275Y449142D01*
X688983Y449350D01*
X688692Y449433D01*
X688317D01*
G01X688692D02*
X688942Y449558D01*
X689150Y449767D01*
X689233Y450017D01*
X689150Y450267D01*
X688942Y450475D01*
X688567Y450600D01*
X688192Y450558D01*
X687817Y450392D01*
G01X691400Y450600D02*
X691067Y450517D01*
X690817Y450308D01*
X690650Y450058D01*
X690525Y449725D01*
X690483Y449350D01*
X690525Y448975D01*
X690650Y448642D01*
X690817Y448392D01*
X691067Y448183D01*
X691400Y448100D01*
X691733Y448183D01*
X691983Y448392D01*
X692150Y448642D01*
X692275Y448975D01*
X692317Y449350D01*
X692275Y449725D01*
X692150Y450058D01*
X691983Y450308D01*
X691733Y450517D01*
X691400Y450600D01*
G01X694400Y448100D02*
Y450600D01*
X693900Y450100D01*
G01Y448100D02*
X694900D01*
G01X668900Y504891D02*
Y507391D01*
X669900D01*
X670233Y507266D01*
X670483Y506974D01*
X670566Y506641D01*
X670483Y506308D01*
X670275Y506058D01*
X669900Y505933D01*
X668900D01*
G01X671816Y507391D02*
Y505599D01*
X671983Y505224D01*
X672316Y504974D01*
X672733Y504891D01*
X673150Y504974D01*
X673483Y505224D01*
X673650Y505599D01*
Y507391D01*
G01X675733Y504891D02*
Y507391D01*
X675233Y506891D01*
G01Y504891D02*
X676233D01*
G01X669700Y545367D02*
X667200D01*
Y546367D01*
X667325Y546700D01*
X667617Y546950D01*
X667950Y547033D01*
X668283Y546950D01*
X668533Y546742D01*
X668658Y546367D01*
Y545367D01*
G01X667408Y550117D02*
X667283Y549867D01*
X667200Y549575D01*
Y549242D01*
X667325Y548867D01*
X667533Y548575D01*
X667783Y548367D01*
X668200Y548200D01*
X668575Y548158D01*
X668950Y548242D01*
X669200Y548367D01*
X669450Y548617D01*
X669617Y548908D01*
X669700Y549200D01*
Y549492D01*
X669617Y549783D01*
X669492Y550033D01*
X669325Y550242D01*
G01X669700Y552700D02*
X667200D01*
X668992Y551158D01*
Y553242D01*
G01X669325Y554283D02*
X669533Y554533D01*
X669658Y554825D01*
X669700Y555200D01*
X669617Y555575D01*
X669450Y555867D01*
X669158Y556075D01*
X668825Y556117D01*
X668492Y556033D01*
X668283Y555825D01*
X668117Y555533D01*
X668075Y555242D01*
X668117Y554950D01*
X668283Y554575D01*
X667200Y554700D01*
Y555825D01*
G01X657035Y537121D02*
X654535D01*
Y538121D01*
X654660Y538454D01*
X654952Y538704D01*
X655285Y538787D01*
X655618Y538704D01*
X655868Y538496D01*
X655993Y538121D01*
Y537121D01*
G01X657035Y540121D02*
X654535D01*
Y541162D01*
X654660Y541496D01*
X654827Y541704D01*
X655160Y541787D01*
X655493Y541704D01*
X655702Y541454D01*
X655827Y541162D01*
Y540121D01*
G01Y541162D02*
X657035Y541787D01*
G01X655993Y543162D02*
X655702Y543454D01*
X655535Y543704D01*
X655452Y544037D01*
X655535Y544329D01*
X655702Y544537D01*
X655952Y544704D01*
X656243Y544746D01*
X656493Y544704D01*
X656743Y544537D01*
X656952Y544287D01*
X657035Y543996D01*
X656952Y543662D01*
X656702Y543371D01*
X656327Y543204D01*
X655910Y543162D01*
X655368Y543246D01*
X655077Y543371D01*
X654785Y543579D01*
X654577Y543871D01*
X654535Y544162D01*
X654618Y544454D01*
X654827Y544662D01*
G01X650000Y538667D02*
X647500D01*
Y539667D01*
X647625Y540000D01*
X647917Y540250D01*
X648250Y540333D01*
X648583Y540250D01*
X648833Y540042D01*
X648958Y539667D01*
Y538667D01*
G01X650000Y541667D02*
X647500D01*
Y542708D01*
X647625Y543042D01*
X647792Y543250D01*
X648125Y543333D01*
X648458Y543250D01*
X648667Y543000D01*
X648792Y542708D01*
Y541667D01*
G01Y542708D02*
X650000Y543333D01*
G01X649500Y544583D02*
X649792Y544833D01*
X649958Y545167D01*
X650000Y545542D01*
X649958Y545875D01*
X649750Y546208D01*
X649500Y546417D01*
X649250Y546458D01*
X648958Y546375D01*
X648750Y546083D01*
X648667Y545792D01*
Y545417D01*
G01Y545792D02*
X648542Y546042D01*
X648333Y546250D01*
X648083Y546333D01*
X647833Y546250D01*
X647625Y546042D01*
X647500Y545667D01*
X647542Y545292D01*
X647708Y544917D01*
G01X683567Y550800D02*
Y553300D01*
X684567D01*
X684900Y553175D01*
X685150Y552883D01*
X685233Y552550D01*
X685150Y552217D01*
X684942Y551967D01*
X684567Y551842D01*
X683567D01*
G01X686567Y550800D02*
Y553300D01*
X687608D01*
X687942Y553175D01*
X688150Y553008D01*
X688233Y552675D01*
X688150Y552342D01*
X687900Y552133D01*
X687608Y552008D01*
X686567D01*
G01X687608D02*
X688233Y550800D01*
G01X690400D02*
X690692Y550842D01*
X691025Y550967D01*
X691233Y551175D01*
X691317Y551467D01*
X691233Y551758D01*
X690983Y552008D01*
X690608Y552133D01*
X690192D01*
X689942Y552217D01*
X689733Y552425D01*
X689650Y552717D01*
X689775Y553008D01*
X690067Y553217D01*
X690400Y553300D01*
X690733Y553217D01*
X691025Y553008D01*
X691150Y552717D01*
X691067Y552425D01*
X690858Y552217D01*
X690608Y552133D01*
X690192D01*
X689817Y552008D01*
X689567Y551758D01*
X689483Y551467D01*
X689567Y551175D01*
X689775Y550967D01*
X690108Y550842D01*
X690400Y550800D01*
G01X683567Y554500D02*
Y557000D01*
X684567D01*
X684900Y556875D01*
X685150Y556583D01*
X685233Y556250D01*
X685150Y555917D01*
X684942Y555667D01*
X684567Y555542D01*
X683567D01*
G01X686567Y554500D02*
Y557000D01*
X687608D01*
X687942Y556875D01*
X688150Y556708D01*
X688233Y556375D01*
X688150Y556042D01*
X687900Y555833D01*
X687608Y555708D01*
X686567D01*
G01X687608D02*
X688233Y554500D01*
G01X689608Y556583D02*
X689858Y556833D01*
X690150Y556958D01*
X690483Y557000D01*
X690900Y556917D01*
X691192Y556708D01*
X691275Y556458D01*
X691233Y556208D01*
X691067Y556000D01*
X690233Y555583D01*
X689858Y555292D01*
X689608Y554875D01*
X689525Y554500D01*
X691275D01*
G01X703267Y507500D02*
Y510000D01*
X704267D01*
X704600Y509875D01*
X704850Y509583D01*
X704933Y509250D01*
X704850Y508917D01*
X704642Y508667D01*
X704267Y508542D01*
X703267D01*
G01X708017Y509792D02*
X707767Y509917D01*
X707475Y510000D01*
X707142D01*
X706767Y509875D01*
X706475Y509667D01*
X706267Y509417D01*
X706100Y509000D01*
X706058Y508625D01*
X706142Y508250D01*
X706267Y508000D01*
X706517Y507750D01*
X706808Y507583D01*
X707100Y507500D01*
X707392D01*
X707683Y507583D01*
X707933Y507708D01*
X708142Y507875D01*
G01X709308Y509583D02*
X709558Y509833D01*
X709850Y509958D01*
X710183Y510000D01*
X710600Y509917D01*
X710892Y509708D01*
X710975Y509458D01*
X710933Y509208D01*
X710767Y509000D01*
X709933Y508583D01*
X709558Y508292D01*
X709308Y507875D01*
X709225Y507500D01*
X710975D01*
G01X711567Y524000D02*
Y526500D01*
X712567D01*
X712900Y526375D01*
X713150Y526083D01*
X713233Y525750D01*
X713150Y525417D01*
X712942Y525167D01*
X712567Y525042D01*
X711567D01*
G01X716317Y526292D02*
X716067Y526417D01*
X715775Y526500D01*
X715442D01*
X715067Y526375D01*
X714775Y526167D01*
X714567Y525917D01*
X714400Y525500D01*
X714358Y525125D01*
X714442Y524750D01*
X714567Y524500D01*
X714817Y524250D01*
X715108Y524083D01*
X715400Y524000D01*
X715692D01*
X715983Y524083D01*
X716233Y524208D01*
X716442Y524375D01*
G01X718400Y524000D02*
Y526500D01*
X717900Y526000D01*
G01Y524000D02*
X718900D01*
G01X678700Y545000D02*
X681200D01*
G01X678700Y544042D02*
Y545958D01*
G01X681200Y547167D02*
X678700D01*
Y548167D01*
X678825Y548500D01*
X679117Y548750D01*
X679450Y548833D01*
X679783Y548750D01*
X680033Y548542D01*
X680158Y548167D01*
Y547167D01*
G01X680700Y550083D02*
X680992Y550333D01*
X681158Y550667D01*
X681200Y551042D01*
X681158Y551375D01*
X680950Y551708D01*
X680700Y551917D01*
X680450Y551958D01*
X680158Y551875D01*
X679950Y551583D01*
X679867Y551292D01*
Y550917D01*
G01Y551292D02*
X679742Y551542D01*
X679533Y551750D01*
X679283Y551833D01*
X679033Y551750D01*
X678825Y551542D01*
X678700Y551167D01*
X678742Y550792D01*
X678908Y550417D01*
G01X679117Y553208D02*
X678867Y553458D01*
X678742Y553750D01*
X678700Y554083D01*
X678783Y554500D01*
X678992Y554792D01*
X679242Y554875D01*
X679492Y554833D01*
X679700Y554667D01*
X680117Y553833D01*
X680408Y553458D01*
X680825Y553208D01*
X681200Y553125D01*
Y554875D01*
G01X683800Y549600D02*
Y547100D01*
G01X682842Y549600D02*
X684758D01*
G01X685967Y547100D02*
Y549600D01*
X686967D01*
X687300Y549475D01*
X687550Y549183D01*
X687633Y548850D01*
X687550Y548517D01*
X687342Y548267D01*
X686967Y548142D01*
X685967D01*
G01X690300Y547100D02*
Y549600D01*
X688758Y547808D01*
X690842D01*
G01X692800Y549600D02*
X692467Y549517D01*
X692217Y549308D01*
X692050Y549058D01*
X691925Y548725D01*
X691883Y548350D01*
X691925Y547975D01*
X692050Y547642D01*
X692217Y547392D01*
X692467Y547183D01*
X692800Y547100D01*
X693133Y547183D01*
X693383Y547392D01*
X693550Y547642D01*
X693675Y547975D01*
X693717Y548350D01*
X693675Y548725D01*
X693550Y549058D01*
X693383Y549308D01*
X693133Y549517D01*
X692800Y549600D01*
G01X691899Y752085D02*
X691649Y752210D01*
X691357Y752293D01*
X691024D01*
X690649Y752168D01*
X690357Y751960D01*
X690149Y751710D01*
X689982Y751293D01*
X689940Y750918D01*
X690024Y750543D01*
X690149Y750293D01*
X690399Y750043D01*
X690690Y749876D01*
X690982Y749793D01*
X691274D01*
X691565Y749876D01*
X691815Y750001D01*
X692024Y750168D01*
G01X693190Y751876D02*
X693440Y752126D01*
X693732Y752251D01*
X694065Y752293D01*
X694482Y752210D01*
X694774Y752001D01*
X694857Y751751D01*
X694815Y751501D01*
X694649Y751293D01*
X693815Y750876D01*
X693440Y750585D01*
X693190Y750168D01*
X693107Y749793D01*
X694857D01*
G01X696899D02*
X696982Y750335D01*
X697107Y750793D01*
X697274Y751210D01*
X697482Y751668D01*
X697815Y752293D01*
X696149D01*
G01X699982D02*
X699649Y752210D01*
X699399Y752001D01*
X699232Y751751D01*
X699107Y751418D01*
X699065Y751043D01*
X699107Y750668D01*
X699232Y750335D01*
X699399Y750085D01*
X699649Y749876D01*
X699982Y749793D01*
X700315Y749876D01*
X700565Y750085D01*
X700732Y750335D01*
X700857Y750668D01*
X700899Y751043D01*
X700857Y751418D01*
X700732Y751751D01*
X700565Y752001D01*
X700315Y752210D01*
X699982Y752293D01*
G01X691767Y756045D02*
X691517Y756170D01*
X691225Y756253D01*
X690892D01*
X690517Y756128D01*
X690225Y755920D01*
X690017Y755670D01*
X689850Y755253D01*
X689808Y754878D01*
X689892Y754503D01*
X690017Y754253D01*
X690267Y754003D01*
X690558Y753836D01*
X690850Y753753D01*
X691142D01*
X691433Y753836D01*
X691683Y753961D01*
X691892Y754128D01*
G01X693058Y755836D02*
X693308Y756086D01*
X693600Y756211D01*
X693933Y756253D01*
X694350Y756170D01*
X694642Y755961D01*
X694725Y755711D01*
X694683Y755461D01*
X694517Y755253D01*
X693683Y754836D01*
X693308Y754545D01*
X693058Y754128D01*
X692975Y753753D01*
X694725D01*
G01X696767D02*
X696850Y754295D01*
X696975Y754753D01*
X697142Y755170D01*
X697350Y755628D01*
X697683Y756253D01*
X696017D01*
G01X699850Y753753D02*
Y756253D01*
X699350Y755753D01*
G01Y753753D02*
X700350D01*
G01X684200Y764967D02*
X681700D01*
Y766008D01*
X681825Y766342D01*
X681992Y766550D01*
X682325Y766633D01*
X682658Y766550D01*
X682867Y766300D01*
X682992Y766008D01*
Y764967D01*
G01Y766008D02*
X684200Y766633D01*
G01X682117Y768008D02*
X681867Y768258D01*
X681742Y768550D01*
X681700Y768883D01*
X681783Y769300D01*
X681992Y769592D01*
X682242Y769675D01*
X682492Y769633D01*
X682700Y769467D01*
X683117Y768633D01*
X683408Y768258D01*
X683825Y768008D01*
X684200Y767925D01*
Y769675D01*
G01X683908Y771092D02*
X684117Y771383D01*
X684200Y771717D01*
X684117Y772050D01*
X683867Y772342D01*
X683492Y772550D01*
X683117Y772633D01*
X682658D01*
X682283Y772550D01*
X681950Y772342D01*
X681783Y772092D01*
X681700Y771800D01*
X681783Y771467D01*
X681950Y771217D01*
X682200Y771050D01*
X682533Y770967D01*
X682825Y771050D01*
X683117Y771258D01*
X683283Y771508D01*
X683325Y771800D01*
X683242Y772133D01*
X683033Y772383D01*
X682658Y772633D01*
G01X684200Y774800D02*
X681700D01*
X682200Y774300D01*
G01X684200D02*
Y775300D01*
G01X692483Y802800D02*
Y801008D01*
X692650Y800633D01*
X692983Y800383D01*
X693400Y800300D01*
X693817Y800383D01*
X694150Y800633D01*
X694317Y801008D01*
Y802800D01*
G01X696400Y800300D02*
Y802800D01*
X695900Y802300D01*
G01Y800300D02*
X696900D01*
G01X699317D02*
X699400Y800842D01*
X699525Y801300D01*
X699692Y801717D01*
X699900Y802175D01*
X700233Y802800D01*
X698567D01*
G01X680517Y817492D02*
X680267Y817617D01*
X679975Y817700D01*
X679642D01*
X679267Y817575D01*
X678975Y817367D01*
X678767Y817117D01*
X678600Y816700D01*
X678558Y816325D01*
X678642Y815950D01*
X678767Y815700D01*
X679017Y815450D01*
X679308Y815283D01*
X679600Y815200D01*
X679892D01*
X680183Y815283D01*
X680433Y815408D01*
X680642Y815575D01*
G01X681808Y817283D02*
X682058Y817533D01*
X682350Y817658D01*
X682683Y817700D01*
X683100Y817617D01*
X683392Y817408D01*
X683475Y817158D01*
X683433Y816908D01*
X683267Y816700D01*
X682433Y816283D01*
X682058Y815992D01*
X681808Y815575D01*
X681725Y815200D01*
X683475D01*
G01X684808Y816242D02*
X685100Y816533D01*
X685350Y816700D01*
X685683Y816783D01*
X685975Y816700D01*
X686183Y816533D01*
X686350Y816283D01*
X686392Y815992D01*
X686350Y815742D01*
X686183Y815492D01*
X685933Y815283D01*
X685642Y815200D01*
X685308Y815283D01*
X685017Y815533D01*
X684850Y815908D01*
X684808Y816325D01*
X684892Y816867D01*
X685017Y817158D01*
X685225Y817450D01*
X685517Y817658D01*
X685808Y817700D01*
X686100Y817617D01*
X686308Y817408D01*
G01X688600Y815200D02*
X688892Y815242D01*
X689225Y815367D01*
X689433Y815575D01*
X689517Y815867D01*
X689433Y816158D01*
X689183Y816408D01*
X688808Y816533D01*
X688392D01*
X688142Y816617D01*
X687933Y816825D01*
X687850Y817117D01*
X687975Y817408D01*
X688267Y817617D01*
X688600Y817700D01*
X688933Y817617D01*
X689225Y817408D01*
X689350Y817117D01*
X689267Y816825D01*
X689058Y816617D01*
X688808Y816533D01*
X688392D01*
X688017Y816408D01*
X687767Y816158D01*
X687683Y815867D01*
X687767Y815575D01*
X687975Y815367D01*
X688308Y815242D01*
X688600Y815200D01*
G01X680517Y821092D02*
X680267Y821217D01*
X679975Y821300D01*
X679642D01*
X679267Y821175D01*
X678975Y820967D01*
X678767Y820717D01*
X678600Y820300D01*
X678558Y819925D01*
X678642Y819550D01*
X678767Y819300D01*
X679017Y819050D01*
X679308Y818883D01*
X679600Y818800D01*
X679892D01*
X680183Y818883D01*
X680433Y819008D01*
X680642Y819175D01*
G01X681808Y820883D02*
X682058Y821133D01*
X682350Y821258D01*
X682683Y821300D01*
X683100Y821217D01*
X683392Y821008D01*
X683475Y820758D01*
X683433Y820508D01*
X683267Y820300D01*
X682433Y819883D01*
X682058Y819592D01*
X681808Y819175D01*
X681725Y818800D01*
X683475D01*
G01X684808Y819842D02*
X685100Y820133D01*
X685350Y820300D01*
X685683Y820383D01*
X685975Y820300D01*
X686183Y820133D01*
X686350Y819883D01*
X686392Y819592D01*
X686350Y819342D01*
X686183Y819092D01*
X685933Y818883D01*
X685642Y818800D01*
X685308Y818883D01*
X685017Y819133D01*
X684850Y819508D01*
X684808Y819925D01*
X684892Y820467D01*
X685017Y820758D01*
X685225Y821050D01*
X685517Y821258D01*
X685808Y821300D01*
X686100Y821217D01*
X686308Y821008D01*
G01X687892Y819092D02*
X688183Y818883D01*
X688517Y818800D01*
X688850Y818883D01*
X689142Y819133D01*
X689350Y819508D01*
X689433Y819883D01*
Y820342D01*
X689350Y820717D01*
X689142Y821050D01*
X688892Y821217D01*
X688600Y821300D01*
X688267Y821217D01*
X688017Y821050D01*
X687850Y820800D01*
X687767Y820467D01*
X687850Y820175D01*
X688058Y819883D01*
X688308Y819717D01*
X688600Y819675D01*
X688933Y819758D01*
X689183Y819967D01*
X689433Y820342D01*
G01X692683Y860700D02*
Y858908D01*
X692850Y858533D01*
X693183Y858283D01*
X693600Y858200D01*
X694017Y858283D01*
X694350Y858533D01*
X694517Y858908D01*
Y860700D01*
G01X696600Y858200D02*
Y860700D01*
X696100Y860200D01*
G01Y858200D02*
X697100D01*
G01X699600D02*
X699892Y858242D01*
X700225Y858367D01*
X700433Y858575D01*
X700517Y858867D01*
X700433Y859158D01*
X700183Y859408D01*
X699808Y859533D01*
X699392D01*
X699142Y859617D01*
X698933Y859825D01*
X698850Y860117D01*
X698975Y860408D01*
X699267Y860617D01*
X699600Y860700D01*
X699933Y860617D01*
X700225Y860408D01*
X700350Y860117D01*
X700267Y859825D01*
X700058Y859617D01*
X699808Y859533D01*
X699392D01*
X699017Y859408D01*
X698767Y859158D01*
X698683Y858867D01*
X698767Y858575D01*
X698975Y858367D01*
X699308Y858242D01*
X699600Y858200D01*
G01X717039Y439176D02*
X714539D01*
Y440217D01*
X714664Y440551D01*
X714831Y440759D01*
X715164Y440842D01*
X715497Y440759D01*
X715706Y440509D01*
X715831Y440217D01*
Y439176D01*
G01Y440217D02*
X717039Y440842D01*
G01X714956Y442217D02*
X714706Y442467D01*
X714581Y442759D01*
X714539Y443092D01*
X714622Y443509D01*
X714831Y443801D01*
X715081Y443884D01*
X715331Y443842D01*
X715539Y443676D01*
X715956Y442842D01*
X716247Y442467D01*
X716664Y442217D01*
X717039Y442134D01*
Y443884D01*
G01Y446009D02*
X716997Y446301D01*
X716872Y446634D01*
X716664Y446842D01*
X716372Y446926D01*
X716081Y446842D01*
X715831Y446592D01*
X715706Y446217D01*
Y445801D01*
X715622Y445551D01*
X715414Y445342D01*
X715122Y445259D01*
X714831Y445384D01*
X714622Y445676D01*
X714539Y446009D01*
X714622Y446342D01*
X714831Y446634D01*
X715122Y446759D01*
X715414Y446676D01*
X715622Y446467D01*
X715706Y446217D01*
Y445801D01*
X715831Y445426D01*
X716081Y445176D01*
X716372Y445092D01*
X716664Y445176D01*
X716872Y445384D01*
X716997Y445717D01*
X717039Y446009D01*
G01X716747Y448301D02*
X716956Y448592D01*
X717039Y448926D01*
X716956Y449259D01*
X716706Y449551D01*
X716331Y449759D01*
X715956Y449842D01*
X715497D01*
X715122Y449759D01*
X714789Y449551D01*
X714622Y449301D01*
X714539Y449009D01*
X714622Y448676D01*
X714789Y448426D01*
X715039Y448259D01*
X715372Y448176D01*
X715664Y448259D01*
X715956Y448467D01*
X716122Y448717D01*
X716164Y449009D01*
X716081Y449342D01*
X715872Y449592D01*
X715497Y449842D01*
G01X737903Y460974D02*
X735403D01*
Y462015D01*
X735528Y462349D01*
X735695Y462557D01*
X736028Y462640D01*
X736361Y462557D01*
X736570Y462307D01*
X736695Y462015D01*
Y460974D01*
G01Y462015D02*
X737903Y462640D01*
G01X735820Y464015D02*
X735570Y464265D01*
X735445Y464557D01*
X735403Y464890D01*
X735486Y465307D01*
X735695Y465599D01*
X735945Y465682D01*
X736195Y465640D01*
X736403Y465474D01*
X736820Y464640D01*
X737111Y464265D01*
X737528Y464015D01*
X737903Y463932D01*
Y465682D01*
G01Y467807D02*
X737861Y468099D01*
X737736Y468432D01*
X737528Y468640D01*
X737236Y468724D01*
X736945Y468640D01*
X736695Y468390D01*
X736570Y468015D01*
Y467599D01*
X736486Y467349D01*
X736278Y467140D01*
X735986Y467057D01*
X735695Y467182D01*
X735486Y467474D01*
X735403Y467807D01*
X735486Y468140D01*
X735695Y468432D01*
X735986Y468557D01*
X736278Y468474D01*
X736486Y468265D01*
X736570Y468015D01*
Y467599D01*
X736695Y467224D01*
X736945Y466974D01*
X737236Y466890D01*
X737528Y466974D01*
X737736Y467182D01*
X737861Y467515D01*
X737903Y467807D01*
G01Y470807D02*
X737861Y471099D01*
X737736Y471432D01*
X737528Y471640D01*
X737236Y471724D01*
X736945Y471640D01*
X736695Y471390D01*
X736570Y471015D01*
Y470599D01*
X736486Y470349D01*
X736278Y470140D01*
X735986Y470057D01*
X735695Y470182D01*
X735486Y470474D01*
X735403Y470807D01*
X735486Y471140D01*
X735695Y471432D01*
X735986Y471557D01*
X736278Y471474D01*
X736486Y471265D01*
X736570Y471015D01*
Y470599D01*
X736695Y470224D01*
X736945Y469974D01*
X737236Y469890D01*
X737528Y469974D01*
X737736Y470182D01*
X737861Y470515D01*
X737903Y470807D01*
G01X742084Y464709D02*
X739584D01*
Y465750D01*
X739709Y466084D01*
X739876Y466292D01*
X740209Y466375D01*
X740542Y466292D01*
X740751Y466042D01*
X740876Y465750D01*
Y464709D01*
G01Y465750D02*
X742084Y466375D01*
G01X740001Y467750D02*
X739751Y468000D01*
X739626Y468292D01*
X739584Y468625D01*
X739667Y469042D01*
X739876Y469334D01*
X740126Y469417D01*
X740376Y469375D01*
X740584Y469209D01*
X741001Y468375D01*
X741292Y468000D01*
X741709Y467750D01*
X742084Y467667D01*
Y469417D01*
G01Y471542D02*
X742042Y471834D01*
X741917Y472167D01*
X741709Y472375D01*
X741417Y472459D01*
X741126Y472375D01*
X740876Y472125D01*
X740751Y471750D01*
Y471334D01*
X740667Y471084D01*
X740459Y470875D01*
X740167Y470792D01*
X739876Y470917D01*
X739667Y471209D01*
X739584Y471542D01*
X739667Y471875D01*
X739876Y472167D01*
X740167Y472292D01*
X740459Y472209D01*
X740667Y472000D01*
X740751Y471750D01*
Y471334D01*
X740876Y470959D01*
X741126Y470709D01*
X741417Y470625D01*
X741709Y470709D01*
X741917Y470917D01*
X742042Y471250D01*
X742084Y471542D01*
G01Y474459D02*
X741542Y474542D01*
X741084Y474667D01*
X740667Y474834D01*
X740209Y475042D01*
X739584Y475375D01*
Y473709D01*
G01X725726Y448107D02*
X723226D01*
Y449148D01*
X723351Y449482D01*
X723518Y449690D01*
X723851Y449773D01*
X724184Y449690D01*
X724393Y449440D01*
X724518Y449148D01*
Y448107D01*
G01Y449148D02*
X725726Y449773D01*
G01X723643Y451148D02*
X723393Y451398D01*
X723268Y451690D01*
X723226Y452023D01*
X723309Y452440D01*
X723518Y452732D01*
X723768Y452815D01*
X724018Y452773D01*
X724226Y452607D01*
X724643Y451773D01*
X724934Y451398D01*
X725351Y451148D01*
X725726Y451065D01*
Y452815D01*
G01Y454940D02*
X725684Y455232D01*
X725559Y455565D01*
X725351Y455773D01*
X725059Y455857D01*
X724768Y455773D01*
X724518Y455523D01*
X724393Y455148D01*
Y454732D01*
X724309Y454482D01*
X724101Y454273D01*
X723809Y454190D01*
X723518Y454315D01*
X723309Y454607D01*
X723226Y454940D01*
X723309Y455273D01*
X723518Y455565D01*
X723809Y455690D01*
X724101Y455607D01*
X724309Y455398D01*
X724393Y455148D01*
Y454732D01*
X724518Y454357D01*
X724768Y454107D01*
X725059Y454023D01*
X725351Y454107D01*
X725559Y454315D01*
X725684Y454648D01*
X725726Y454940D01*
G01X724684Y457148D02*
X724393Y457440D01*
X724226Y457690D01*
X724143Y458023D01*
X724226Y458315D01*
X724393Y458523D01*
X724643Y458690D01*
X724934Y458732D01*
X725184Y458690D01*
X725434Y458523D01*
X725643Y458273D01*
X725726Y457982D01*
X725643Y457648D01*
X725393Y457357D01*
X725018Y457190D01*
X724601Y457148D01*
X724059Y457232D01*
X723768Y457357D01*
X723476Y457565D01*
X723268Y457857D01*
X723226Y458148D01*
X723309Y458440D01*
X723518Y458648D01*
G01X721504Y443885D02*
X719004D01*
Y444926D01*
X719129Y445260D01*
X719296Y445468D01*
X719629Y445551D01*
X719962Y445468D01*
X720171Y445218D01*
X720296Y444926D01*
Y443885D01*
G01Y444926D02*
X721504Y445551D01*
G01X719421Y446926D02*
X719171Y447176D01*
X719046Y447468D01*
X719004Y447801D01*
X719087Y448218D01*
X719296Y448510D01*
X719546Y448593D01*
X719796Y448551D01*
X720004Y448385D01*
X720421Y447551D01*
X720712Y447176D01*
X721129Y446926D01*
X721504Y446843D01*
Y448593D01*
G01Y450718D02*
X721462Y451010D01*
X721337Y451343D01*
X721129Y451551D01*
X720837Y451635D01*
X720546Y451551D01*
X720296Y451301D01*
X720171Y450926D01*
Y450510D01*
X720087Y450260D01*
X719879Y450051D01*
X719587Y449968D01*
X719296Y450093D01*
X719087Y450385D01*
X719004Y450718D01*
X719087Y451051D01*
X719296Y451343D01*
X719587Y451468D01*
X719879Y451385D01*
X720087Y451176D01*
X720171Y450926D01*
Y450510D01*
X720296Y450135D01*
X720546Y449885D01*
X720837Y449801D01*
X721129Y449885D01*
X721337Y450093D01*
X721462Y450426D01*
X721504Y450718D01*
G01X721129Y452801D02*
X721337Y453051D01*
X721462Y453343D01*
X721504Y453718D01*
X721421Y454093D01*
X721254Y454385D01*
X720962Y454593D01*
X720629Y454635D01*
X720296Y454551D01*
X720087Y454343D01*
X719921Y454051D01*
X719879Y453760D01*
X719921Y453468D01*
X720087Y453093D01*
X719004Y453218D01*
Y454343D01*
G01X718097Y478341D02*
Y480841D01*
X719138D01*
X719472Y480716D01*
X719680Y480549D01*
X719763Y480216D01*
X719680Y479883D01*
X719430Y479674D01*
X719138Y479549D01*
X718097D01*
G01X719138D02*
X719763Y478341D01*
G01X721013Y478841D02*
X721263Y478549D01*
X721597Y478383D01*
X721972Y478341D01*
X722305Y478383D01*
X722638Y478591D01*
X722847Y478841D01*
X722888Y479091D01*
X722805Y479383D01*
X722513Y479591D01*
X722222Y479674D01*
X721847D01*
G01X722222D02*
X722472Y479799D01*
X722680Y480008D01*
X722763Y480258D01*
X722680Y480508D01*
X722472Y480716D01*
X722097Y480841D01*
X721722Y480799D01*
X721347Y480633D01*
G01X724138Y480424D02*
X724388Y480674D01*
X724680Y480799D01*
X725013Y480841D01*
X725430Y480758D01*
X725722Y480549D01*
X725805Y480299D01*
X725763Y480049D01*
X725597Y479841D01*
X724763Y479424D01*
X724388Y479133D01*
X724138Y478716D01*
X724055Y478341D01*
X725805D01*
G01X727930Y480841D02*
X727597Y480758D01*
X727347Y480549D01*
X727180Y480299D01*
X727055Y479966D01*
X727013Y479591D01*
X727055Y479216D01*
X727180Y478883D01*
X727347Y478633D01*
X727597Y478424D01*
X727930Y478341D01*
X728263Y478424D01*
X728513Y478633D01*
X728680Y478883D01*
X728805Y479216D01*
X728847Y479591D01*
X728805Y479966D01*
X728680Y480299D01*
X728513Y480549D01*
X728263Y480758D01*
X727930Y480841D01*
G01X722481Y482238D02*
Y484738D01*
X723522D01*
X723856Y484613D01*
X724064Y484446D01*
X724147Y484113D01*
X724064Y483780D01*
X723814Y483571D01*
X723522Y483446D01*
X722481D01*
G01X723522D02*
X724147Y482238D01*
G01X725397Y482738D02*
X725647Y482446D01*
X725981Y482280D01*
X726356Y482238D01*
X726689Y482280D01*
X727022Y482488D01*
X727231Y482738D01*
X727272Y482988D01*
X727189Y483280D01*
X726897Y483488D01*
X726606Y483571D01*
X726231D01*
G01X726606D02*
X726856Y483696D01*
X727064Y483905D01*
X727147Y484155D01*
X727064Y484405D01*
X726856Y484613D01*
X726481Y484738D01*
X726106Y484696D01*
X725731Y484530D01*
G01X729314Y482238D02*
Y484738D01*
X728814Y484238D01*
G01Y482238D02*
X729814D01*
G01X732231D02*
X732314Y482780D01*
X732439Y483238D01*
X732606Y483655D01*
X732814Y484113D01*
X733147Y484738D01*
X731481D01*
G01X713308Y473714D02*
Y476214D01*
X714349D01*
X714683Y476089D01*
X714891Y475922D01*
X714974Y475589D01*
X714891Y475256D01*
X714641Y475047D01*
X714349Y474922D01*
X713308D01*
G01X714349D02*
X714974Y473714D01*
G01X716224Y474214D02*
X716474Y473922D01*
X716808Y473756D01*
X717183Y473714D01*
X717516Y473756D01*
X717849Y473964D01*
X718058Y474214D01*
X718099Y474464D01*
X718016Y474756D01*
X717724Y474964D01*
X717433Y475047D01*
X717058D01*
G01X717433D02*
X717683Y475172D01*
X717891Y475381D01*
X717974Y475631D01*
X717891Y475881D01*
X717683Y476089D01*
X717308Y476214D01*
X716933Y476172D01*
X716558Y476006D01*
G01X720141Y476214D02*
X719808Y476131D01*
X719558Y475922D01*
X719391Y475672D01*
X719266Y475339D01*
X719224Y474964D01*
X719266Y474589D01*
X719391Y474256D01*
X719558Y474006D01*
X719808Y473797D01*
X720141Y473714D01*
X720474Y473797D01*
X720724Y474006D01*
X720891Y474256D01*
X721016Y474589D01*
X721058Y474964D01*
X721016Y475339D01*
X720891Y475672D01*
X720724Y475922D01*
X720474Y476131D01*
X720141Y476214D01*
G01X722433Y474006D02*
X722724Y473797D01*
X723058Y473714D01*
X723391Y473797D01*
X723683Y474047D01*
X723891Y474422D01*
X723974Y474797D01*
Y475256D01*
X723891Y475631D01*
X723683Y475964D01*
X723433Y476131D01*
X723141Y476214D01*
X722808Y476131D01*
X722558Y475964D01*
X722391Y475714D01*
X722308Y475381D01*
X722391Y475089D01*
X722599Y474797D01*
X722849Y474631D01*
X723141Y474589D01*
X723474Y474672D01*
X723724Y474881D01*
X723974Y475256D01*
G01X733800Y456067D02*
X731300D01*
Y457108D01*
X731425Y457442D01*
X731592Y457650D01*
X731925Y457733D01*
X732258Y457650D01*
X732467Y457400D01*
X732592Y457108D01*
Y456067D01*
G01Y457108D02*
X733800Y457733D01*
G01X733300Y458983D02*
X733592Y459233D01*
X733758Y459567D01*
X733800Y459942D01*
X733758Y460275D01*
X733550Y460608D01*
X733300Y460817D01*
X733050Y460858D01*
X732758Y460775D01*
X732550Y460483D01*
X732467Y460192D01*
Y459817D01*
G01Y460192D02*
X732342Y460442D01*
X732133Y460650D01*
X731883Y460733D01*
X731633Y460650D01*
X731425Y460442D01*
X731300Y460067D01*
X731342Y459692D01*
X731508Y459317D01*
G01X731300Y462900D02*
X731383Y462567D01*
X731592Y462317D01*
X731842Y462150D01*
X732175Y462025D01*
X732550Y461983D01*
X732925Y462025D01*
X733258Y462150D01*
X733508Y462317D01*
X733717Y462567D01*
X733800Y462900D01*
X733717Y463233D01*
X733508Y463483D01*
X733258Y463650D01*
X732925Y463775D01*
X732550Y463817D01*
X732175Y463775D01*
X731842Y463650D01*
X731592Y463483D01*
X731383Y463233D01*
X731300Y462900D01*
G01X733800Y465900D02*
X733758Y466192D01*
X733633Y466525D01*
X733425Y466733D01*
X733133Y466817D01*
X732842Y466733D01*
X732592Y466483D01*
X732467Y466108D01*
Y465692D01*
X732383Y465442D01*
X732175Y465233D01*
X731883Y465150D01*
X731592Y465275D01*
X731383Y465567D01*
X731300Y465900D01*
X731383Y466233D01*
X731592Y466525D01*
X731883Y466650D01*
X732175Y466567D01*
X732383Y466358D01*
X732467Y466108D01*
Y465692D01*
X732592Y465317D01*
X732842Y465067D01*
X733133Y464983D01*
X733425Y465067D01*
X733633Y465275D01*
X733758Y465608D01*
X733800Y465900D01*
G01X729500Y452267D02*
X727000D01*
Y453308D01*
X727125Y453642D01*
X727292Y453850D01*
X727625Y453933D01*
X727958Y453850D01*
X728167Y453600D01*
X728292Y453308D01*
Y452267D01*
G01Y453308D02*
X729500Y453933D01*
G01X729000Y455183D02*
X729292Y455433D01*
X729458Y455767D01*
X729500Y456142D01*
X729458Y456475D01*
X729250Y456808D01*
X729000Y457017D01*
X728750Y457058D01*
X728458Y456975D01*
X728250Y456683D01*
X728167Y456392D01*
Y456017D01*
G01Y456392D02*
X728042Y456642D01*
X727833Y456850D01*
X727583Y456933D01*
X727333Y456850D01*
X727125Y456642D01*
X727000Y456267D01*
X727042Y455892D01*
X727208Y455517D01*
G01X727000Y459100D02*
X727083Y458767D01*
X727292Y458517D01*
X727542Y458350D01*
X727875Y458225D01*
X728250Y458183D01*
X728625Y458225D01*
X728958Y458350D01*
X729208Y458517D01*
X729417Y458767D01*
X729500Y459100D01*
X729417Y459433D01*
X729208Y459683D01*
X728958Y459850D01*
X728625Y459975D01*
X728250Y460017D01*
X727875Y459975D01*
X727542Y459850D01*
X727292Y459683D01*
X727083Y459433D01*
X727000Y459100D01*
G01X729500Y462017D02*
X728958Y462100D01*
X728500Y462225D01*
X728083Y462392D01*
X727625Y462600D01*
X727000Y462933D01*
Y461267D01*
G01X759543Y420691D02*
Y421524D01*
X760293D01*
X760543Y421274D01*
X760710Y420983D01*
X760793Y420566D01*
X760710Y420149D01*
X760543Y419858D01*
X760293Y419608D01*
X760001Y419441D01*
X759668Y419358D01*
X759376D01*
X759126Y419441D01*
X758835Y419608D01*
X758585Y419858D01*
X758418Y420108D01*
X758293Y420441D01*
Y420733D01*
X758376Y421066D01*
X758543Y421316D01*
G01X760793Y422649D02*
X758293D01*
Y424233D01*
G01X759501Y423649D02*
Y422649D01*
G01X760793Y426441D02*
X758293D01*
X758793Y425941D01*
G01X760793D02*
Y426941D01*
G01X749767Y541200D02*
Y543700D01*
X750808D01*
X751142Y543575D01*
X751350Y543408D01*
X751433Y543075D01*
X751350Y542742D01*
X751100Y542533D01*
X750808Y542408D01*
X749767D01*
G01X750808D02*
X751433Y541200D01*
G01X753600D02*
Y543700D01*
X753100Y543200D01*
G01Y541200D02*
X754100D01*
G01X756600Y543700D02*
X756267Y543617D01*
X756017Y543408D01*
X755850Y543158D01*
X755725Y542825D01*
X755683Y542450D01*
X755725Y542075D01*
X755850Y541742D01*
X756017Y541492D01*
X756267Y541283D01*
X756600Y541200D01*
X756933Y541283D01*
X757183Y541492D01*
X757350Y541742D01*
X757475Y542075D01*
X757517Y542450D01*
X757475Y542825D01*
X757350Y543158D01*
X757183Y543408D01*
X756933Y543617D01*
X756600Y543700D01*
G01X759517Y541200D02*
X759600Y541742D01*
X759725Y542200D01*
X759892Y542617D01*
X760100Y543075D01*
X760433Y543700D01*
X758767D01*
G01X734267Y554900D02*
Y557400D01*
X735308D01*
X735642Y557275D01*
X735850Y557108D01*
X735933Y556775D01*
X735850Y556442D01*
X735600Y556233D01*
X735308Y556108D01*
X734267D01*
G01X735308D02*
X735933Y554900D01*
G01X737183Y555400D02*
X737433Y555108D01*
X737767Y554942D01*
X738142Y554900D01*
X738475Y554942D01*
X738808Y555150D01*
X739017Y555400D01*
X739058Y555650D01*
X738975Y555942D01*
X738683Y556150D01*
X738392Y556233D01*
X738017D01*
G01X738392D02*
X738642Y556358D01*
X738850Y556567D01*
X738933Y556817D01*
X738850Y557067D01*
X738642Y557275D01*
X738267Y557400D01*
X737892Y557358D01*
X737517Y557192D01*
G01X740183Y555275D02*
X740433Y555067D01*
X740725Y554942D01*
X741100Y554900D01*
X741475Y554983D01*
X741767Y555150D01*
X741975Y555442D01*
X742017Y555775D01*
X741933Y556108D01*
X741725Y556317D01*
X741433Y556483D01*
X741142Y556525D01*
X740850Y556483D01*
X740475Y556317D01*
X740600Y557400D01*
X741725D01*
G01X743308Y556983D02*
X743558Y557233D01*
X743850Y557358D01*
X744183Y557400D01*
X744600Y557317D01*
X744892Y557108D01*
X744975Y556858D01*
X744933Y556608D01*
X744767Y556400D01*
X743933Y555983D01*
X743558Y555692D01*
X743308Y555275D01*
X743225Y554900D01*
X744975D01*
G01X734267Y551100D02*
Y553600D01*
X735308D01*
X735642Y553475D01*
X735850Y553308D01*
X735933Y552975D01*
X735850Y552642D01*
X735600Y552433D01*
X735308Y552308D01*
X734267D01*
G01X735308D02*
X735933Y551100D01*
G01X737183Y551600D02*
X737433Y551308D01*
X737767Y551142D01*
X738142Y551100D01*
X738475Y551142D01*
X738808Y551350D01*
X739017Y551600D01*
X739058Y551850D01*
X738975Y552142D01*
X738683Y552350D01*
X738392Y552433D01*
X738017D01*
G01X738392D02*
X738642Y552558D01*
X738850Y552767D01*
X738933Y553017D01*
X738850Y553267D01*
X738642Y553475D01*
X738267Y553600D01*
X737892Y553558D01*
X737517Y553392D01*
G01X740183Y551475D02*
X740433Y551267D01*
X740725Y551142D01*
X741100Y551100D01*
X741475Y551183D01*
X741767Y551350D01*
X741975Y551642D01*
X742017Y551975D01*
X741933Y552308D01*
X741725Y552517D01*
X741433Y552683D01*
X741142Y552725D01*
X740850Y552683D01*
X740475Y552517D01*
X740600Y553600D01*
X741725D01*
G01X744100Y551100D02*
Y553600D01*
X743600Y553100D01*
G01Y551100D02*
X744600D01*
G01X717167Y532500D02*
Y535000D01*
X718167D01*
X718500Y534875D01*
X718750Y534583D01*
X718833Y534250D01*
X718750Y533917D01*
X718542Y533667D01*
X718167Y533542D01*
X717167D01*
G01X720167Y532500D02*
Y535000D01*
X721208D01*
X721542Y534875D01*
X721750Y534708D01*
X721833Y534375D01*
X721750Y534042D01*
X721500Y533833D01*
X721208Y533708D01*
X720167D01*
G01X721208D02*
X721833Y532500D01*
G01X723083Y532875D02*
X723333Y532667D01*
X723625Y532542D01*
X724000Y532500D01*
X724375Y532583D01*
X724667Y532750D01*
X724875Y533042D01*
X724917Y533375D01*
X724833Y533708D01*
X724625Y533917D01*
X724333Y534083D01*
X724042Y534125D01*
X723750Y534083D01*
X723375Y533917D01*
X723500Y535000D01*
X724625D01*
G01X726208Y533542D02*
X726500Y533833D01*
X726750Y534000D01*
X727083Y534083D01*
X727375Y534000D01*
X727583Y533833D01*
X727750Y533583D01*
X727792Y533292D01*
X727750Y533042D01*
X727583Y532792D01*
X727333Y532583D01*
X727042Y532500D01*
X726708Y532583D01*
X726417Y532833D01*
X726250Y533208D01*
X726208Y533625D01*
X726292Y534167D01*
X726417Y534458D01*
X726625Y534750D01*
X726917Y534958D01*
X727208Y535000D01*
X727500Y534917D01*
X727708Y534708D01*
G01X735467Y578800D02*
Y581300D01*
X736508D01*
X736842Y581175D01*
X737050Y581008D01*
X737133Y580675D01*
X737050Y580342D01*
X736800Y580133D01*
X736508Y580008D01*
X735467D01*
G01X736508D02*
X737133Y578800D01*
G01X738508Y580883D02*
X738758Y581133D01*
X739050Y581258D01*
X739383Y581300D01*
X739800Y581217D01*
X740092Y581008D01*
X740175Y580758D01*
X740133Y580508D01*
X739967Y580300D01*
X739133Y579883D01*
X738758Y579592D01*
X738508Y579175D01*
X738425Y578800D01*
X740175D01*
G01X741592Y579092D02*
X741883Y578883D01*
X742217Y578800D01*
X742550Y578883D01*
X742842Y579133D01*
X743050Y579508D01*
X743133Y579883D01*
Y580342D01*
X743050Y580717D01*
X742842Y581050D01*
X742592Y581217D01*
X742300Y581300D01*
X741967Y581217D01*
X741717Y581050D01*
X741550Y580800D01*
X741467Y580467D01*
X741550Y580175D01*
X741758Y579883D01*
X742008Y579717D01*
X742300Y579675D01*
X742633Y579758D01*
X742883Y579967D01*
X743133Y580342D01*
G01X745217Y578800D02*
X745300Y579342D01*
X745425Y579800D01*
X745592Y580217D01*
X745800Y580675D01*
X746133Y581300D01*
X744467D01*
G01X728167Y569000D02*
Y571500D01*
X729208D01*
X729542Y571375D01*
X729750Y571208D01*
X729833Y570875D01*
X729750Y570542D01*
X729500Y570333D01*
X729208Y570208D01*
X728167D01*
G01X729208D02*
X729833Y569000D01*
G01X731208Y571083D02*
X731458Y571333D01*
X731750Y571458D01*
X732083Y571500D01*
X732500Y571417D01*
X732792Y571208D01*
X732875Y570958D01*
X732833Y570708D01*
X732667Y570500D01*
X731833Y570083D01*
X731458Y569792D01*
X731208Y569375D01*
X731125Y569000D01*
X732875D01*
G01X734208Y570042D02*
X734500Y570333D01*
X734750Y570500D01*
X735083Y570583D01*
X735375Y570500D01*
X735583Y570333D01*
X735750Y570083D01*
X735792Y569792D01*
X735750Y569542D01*
X735583Y569292D01*
X735333Y569083D01*
X735042Y569000D01*
X734708Y569083D01*
X734417Y569333D01*
X734250Y569708D01*
X734208Y570125D01*
X734292Y570667D01*
X734417Y570958D01*
X734625Y571250D01*
X734917Y571458D01*
X735208Y571500D01*
X735500Y571417D01*
X735708Y571208D01*
G01X738000Y569000D02*
Y571500D01*
X737500Y571000D01*
G01Y569000D02*
X738500D01*
G01X734267Y559600D02*
Y562100D01*
X735308D01*
X735642Y561975D01*
X735850Y561808D01*
X735933Y561475D01*
X735850Y561142D01*
X735600Y560933D01*
X735308Y560808D01*
X734267D01*
G01X735308D02*
X735933Y559600D01*
G01X737308Y561683D02*
X737558Y561933D01*
X737850Y562058D01*
X738183Y562100D01*
X738600Y562017D01*
X738892Y561808D01*
X738975Y561558D01*
X738933Y561308D01*
X738767Y561100D01*
X737933Y560683D01*
X737558Y560392D01*
X737308Y559975D01*
X737225Y559600D01*
X738975D01*
G01X740183Y559975D02*
X740433Y559767D01*
X740725Y559642D01*
X741100Y559600D01*
X741475Y559683D01*
X741767Y559850D01*
X741975Y560142D01*
X742017Y560475D01*
X741933Y560808D01*
X741725Y561017D01*
X741433Y561183D01*
X741142Y561225D01*
X740850Y561183D01*
X740475Y561017D01*
X740600Y562100D01*
X741725D01*
G01X743392Y559892D02*
X743683Y559683D01*
X744017Y559600D01*
X744350Y559683D01*
X744642Y559933D01*
X744850Y560308D01*
X744933Y560683D01*
Y561142D01*
X744850Y561517D01*
X744642Y561850D01*
X744392Y562017D01*
X744100Y562100D01*
X743767Y562017D01*
X743517Y561850D01*
X743350Y561600D01*
X743267Y561267D01*
X743350Y560975D01*
X743558Y560683D01*
X743808Y560517D01*
X744100Y560475D01*
X744433Y560558D01*
X744683Y560767D01*
X744933Y561142D01*
G01X733067Y572900D02*
Y575400D01*
X734108D01*
X734442Y575275D01*
X734650Y575108D01*
X734733Y574775D01*
X734650Y574442D01*
X734400Y574233D01*
X734108Y574108D01*
X733067D01*
G01X734108D02*
X734733Y572900D01*
G01X736900D02*
Y575400D01*
X736400Y574900D01*
G01Y572900D02*
X737400D01*
G01X739900D02*
Y575400D01*
X739400Y574900D01*
G01Y572900D02*
X740400D01*
G01X742900Y575400D02*
X742567Y575317D01*
X742317Y575108D01*
X742150Y574858D01*
X742025Y574525D01*
X741983Y574150D01*
X742025Y573775D01*
X742150Y573442D01*
X742317Y573192D01*
X742567Y572983D01*
X742900Y572900D01*
X743233Y572983D01*
X743483Y573192D01*
X743650Y573442D01*
X743775Y573775D01*
X743817Y574150D01*
X743775Y574525D01*
X743650Y574858D01*
X743483Y575108D01*
X743233Y575317D01*
X742900Y575400D01*
G01X758468Y773527D02*
Y774360D01*
X759218D01*
X759468Y774110D01*
X759635Y773819D01*
X759718Y773402D01*
X759635Y772985D01*
X759468Y772694D01*
X759218Y772444D01*
X758926Y772277D01*
X758593Y772194D01*
X758301D01*
X758051Y772277D01*
X757760Y772444D01*
X757510Y772694D01*
X757343Y772944D01*
X757218Y773277D01*
Y773569D01*
X757301Y773902D01*
X757468Y774152D01*
G01X759718Y775485D02*
X757218D01*
Y777069D01*
G01X758426Y776485D02*
Y775485D01*
G01X757635Y778485D02*
X757385Y778735D01*
X757260Y779027D01*
X757218Y779360D01*
X757301Y779777D01*
X757510Y780069D01*
X757760Y780152D01*
X758010Y780110D01*
X758218Y779944D01*
X758635Y779110D01*
X758926Y778735D01*
X759343Y778485D01*
X759718Y778402D01*
Y780152D01*
G01X723167Y861167D02*
Y863667D01*
X724208D01*
X724542Y863542D01*
X724750Y863375D01*
X724833Y863042D01*
X724750Y862709D01*
X724500Y862500D01*
X724208Y862375D01*
X723167D01*
G01X724208D02*
X724833Y861167D01*
G01X727000D02*
Y863667D01*
X726500Y863167D01*
G01Y861167D02*
X727500D01*
G01X730000D02*
Y863667D01*
X729500Y863167D01*
G01Y861167D02*
X730500D01*
G01X732083Y861667D02*
X732333Y861375D01*
X732667Y861209D01*
X733042Y861167D01*
X733375Y861209D01*
X733708Y861417D01*
X733917Y861667D01*
X733958Y861917D01*
X733875Y862209D01*
X733583Y862417D01*
X733292Y862500D01*
X732917D01*
G01X733292D02*
X733542Y862625D01*
X733750Y862834D01*
X733833Y863084D01*
X733750Y863334D01*
X733542Y863542D01*
X733167Y863667D01*
X732792Y863625D01*
X732417Y863459D01*
G01X733001Y848635D02*
Y851135D01*
X734042D01*
X734376Y851010D01*
X734584Y850843D01*
X734667Y850510D01*
X734584Y850177D01*
X734334Y849968D01*
X734042Y849843D01*
X733001D01*
G01X734042D02*
X734667Y848635D01*
G01X735917Y849135D02*
X736167Y848843D01*
X736501Y848677D01*
X736876Y848635D01*
X737209Y848677D01*
X737542Y848885D01*
X737751Y849135D01*
X737792Y849385D01*
X737709Y849677D01*
X737417Y849885D01*
X737126Y849968D01*
X736751D01*
G01X737126D02*
X737376Y850093D01*
X737584Y850302D01*
X737667Y850552D01*
X737584Y850802D01*
X737376Y851010D01*
X737001Y851135D01*
X736626Y851093D01*
X736251Y850927D01*
G01X739834Y851135D02*
X739501Y851052D01*
X739251Y850843D01*
X739084Y850593D01*
X738959Y850260D01*
X738917Y849885D01*
X738959Y849510D01*
X739084Y849177D01*
X739251Y848927D01*
X739501Y848718D01*
X739834Y848635D01*
X740167Y848718D01*
X740417Y848927D01*
X740584Y849177D01*
X740709Y849510D01*
X740751Y849885D01*
X740709Y850260D01*
X740584Y850593D01*
X740417Y850843D01*
X740167Y851052D01*
X739834Y851135D01*
G01X742834D02*
X742501Y851052D01*
X742251Y850843D01*
X742084Y850593D01*
X741959Y850260D01*
X741917Y849885D01*
X741959Y849510D01*
X742084Y849177D01*
X742251Y848927D01*
X742501Y848718D01*
X742834Y848635D01*
X743167Y848718D01*
X743417Y848927D01*
X743584Y849177D01*
X743709Y849510D01*
X743751Y849885D01*
X743709Y850260D01*
X743584Y850593D01*
X743417Y850843D01*
X743167Y851052D01*
X742834Y851135D01*
M02*
